G04 ================== begin FILE IDENTIFICATION RECORD ==================*
G04 Layout Name:  13130-1b.brd*
G04 Film Name:    BSILK*
G04 File Format:  Gerber RS274X*
G04 File Origin:  Cadence Allegro 16.5-S037*
G04 Origin Date:  Thu Nov 13 17:26:11 2014*
G04 *
G04 Layer:  VIA CLASS/FILMMASKBOTTOM*
G04 Layer:  REF DES/ASSEMBLY_BOTTOM*
G04 Layer:  PACKAGE GEOMETRY/SILKSCREEN_BOTTOM*
G04 Layer:  DRAWING FORMAT/LAYER_PCB_STORY*
G04 Layer:  DRAWING FORMAT/LAYER_SILK_B*
G04 Layer:  BOARD GEOMETRY/SILKSCREEN_BOTTOM*
G04 *
G04 Offset:    (0.00 0.00)*
G04 Mirror:    No*
G04 Mode:      Positive*
G04 Rotation:  0*
G04 FullContactRelief:  No*
G04 UndefLineWidth:     6.00*
G04 ================== end FILE IDENTIFICATION RECORD ====================*
%FSLAX35Y35*MOIN*%
%IR0*IPPOS*OFA0.00000B0.00000*MIA0B0*SFA1.00000B1.00000*%
%ADD10C,.024*%
%ADD11C,.01*%
%ADD12C,.02*%
%ADD13C,.012*%
%ADD14C,.015*%
%ADD15C,.002*%
%ADD16C,.006*%
%ADD17C,.008*%
%ADD18C,.009*%
G75*
%LPD*%
G75*
G36*
G01X18417Y267487D02*
X16417Y265487D01*
Y269487D01*
X18417Y267487D01*
G37*
G36*
G01X66200Y260500D02*
Y288100D01*
X192200D01*
Y260500D01*
X66200D01*
G37*
G36*
G01X108402Y186219D02*
X105960Y183777D01*
Y188660D01*
X108402Y186219D01*
G37*
G36*
G01X167196Y179159D02*
Y182809D01*
X170846Y179159D01*
X167196D01*
G37*
G36*
G01X224252Y77246D02*
X232661D01*
G02X238599I2969J-1656D01*
G01X247008D01*
Y172360D01*
X239652D01*
G02X231608I-4022J1656D01*
G01X224252D01*
Y77246D01*
G37*
G36*
G01X258830Y173903D02*
Y168703D01*
X256230Y171303D01*
X258830Y173903D01*
G37*
G36*
G01X284164Y70356D02*
X282932Y71588D01*
X281700Y70356D01*
X284164D01*
G37*
G36*
G01X329082Y60285D02*
X331524Y57843D01*
X326641D01*
X329082Y60285D01*
G37*
G36*
G01X349350Y71500D02*
X343650D01*
Y74500D01*
X349350D01*
Y71500D01*
G37*
G36*
G01X343000Y266650D02*
Y272350D01*
X346000D01*
Y266650D01*
X343000D01*
G37*
G36*
G01X388913Y243160D02*
X391413Y240660D01*
X386413D01*
X388913Y243160D01*
G37*
G36*
G01X435591Y258563D02*
X425450D01*
Y266437D01*
X435591D01*
Y258563D01*
G37*
G36*
G01X443059Y264427D02*
X445559Y266927D01*
Y261927D01*
X443059Y264427D01*
G37*
G36*
G01X758017Y34590D02*
Y11006D01*
X502775D01*
Y34590D01*
X758017D01*
G37*
G36*
G01X495920Y250806D02*
Y274390D01*
X751162D01*
Y250806D01*
X495920D01*
G37*
G36*
G01X573500Y117500D02*
Y112500D01*
X553500D01*
Y117500D01*
X573500D01*
G37*
G54D10*
X38500Y148000D03*
X48500D03*
X41000Y152300D03*
Y143300D03*
X46000D03*
Y152300D03*
X43500Y148000D03*
Y138500D03*
X48500D03*
X38500D03*
X52500Y96500D03*
Y106500D03*
X57500Y96500D03*
X60000Y101500D03*
X50000D03*
X55000D03*
X57500Y106500D03*
X60000Y111300D03*
X50000D03*
X55000D03*
X79500Y230000D03*
X84500D03*
X89500D03*
X84500Y225000D03*
Y235000D03*
X162000Y226000D03*
X167000D03*
Y221500D03*
X162000D03*
Y230500D03*
X167000D03*
X162000Y235000D03*
X741104Y133763D03*
X745104Y129763D03*
X749104Y133763D03*
X745104D03*
Y137763D03*
X788515Y144060D03*
X784515D03*
X796515D03*
X792515D03*
X800515D03*
Y148060D03*
X796515D03*
X792515D03*
G54D11*
G01X21100Y172350D02*
X16900D01*
G01X205300Y77300D02*
Y70700D01*
G01X267600Y85350D02*
X263400D01*
G01X758950Y152050D02*
X765050D01*
G01X779496Y273016D02*
Y268816D01*
G01X797550Y136700D02*
Y132500D01*
G01Y131400D02*
Y127200D01*
G01Y126100D02*
Y121900D01*
G01X797650Y154400D02*
Y150200D01*
G01X797550Y142000D02*
Y137800D01*
G01X797650Y159600D02*
Y155400D01*
G01Y164800D02*
Y160600D01*
G01Y170000D02*
Y165800D01*
G01X789796Y263124D02*
Y258924D01*
G01Y278359D02*
Y283009D01*
G54D12*
G01X10636Y-27865D02*
G02I-12000J0D01*
G01X14636D02*
X-17364D01*
G01X5486D02*
G02I-6850J0D01*
G01X-1364Y-43865D02*
Y-11865D01*
G01X14636Y-43865D02*
Y-123865D01*
G01D02*
X1309236D01*
G01X14636Y-79365D02*
X1309236D01*
G01X14636Y-43865D02*
X1309236D01*
G01X443900Y152588D02*
Y135413D01*
G01X439100Y171488D02*
Y154313D01*
G01X521736Y-43865D02*
Y-123865D01*
G01X696000Y110000D02*
Y100000D01*
X706000D01*
Y72500D01*
X580500D01*
Y87500D01*
X588000D01*
Y107500D01*
X578500D01*
Y136500D01*
X695500D01*
Y124000D01*
G01X659236Y-43865D02*
Y-123865D01*
G01X774236Y-43865D02*
Y-123865D01*
G01X775400Y204488D02*
Y187313D01*
G01X941736Y-43865D02*
Y-123865D01*
G01X1111736Y-43865D02*
Y-123865D01*
G01X1309236Y-43865D02*
Y-123865D01*
G01X1341236Y-27865D02*
X1309236D01*
G01X1337236D02*
G02I-12000J0D01*
G01X1332086D02*
G02I-6850J0D01*
G01X1325236Y-43865D02*
Y-11865D01*
G54D13*
G01X21800Y113900D02*
Y109100D01*
G01X22300Y152100D02*
Y147300D01*
G01Y159200D02*
Y154400D01*
G01X58100Y123500D02*
X62900D01*
G01X100000Y176400D02*
Y171600D01*
G01Y183900D02*
Y179100D01*
G01X107100Y169500D02*
X111900D01*
G01X114600D02*
X119400D01*
G01X278900Y58500D02*
Y63300D01*
G01X276400Y65600D02*
Y70400D01*
G01X290300Y78400D02*
X295100D01*
G01X302500Y66800D02*
Y62000D01*
G01Y74000D02*
Y69200D01*
G01X337100Y59500D02*
X341900D01*
G01X344600D02*
X349400D01*
G01X354600Y268000D02*
X359400D01*
G01X371900Y55500D02*
X367100D01*
G01X362000Y249400D02*
Y244600D01*
G01Y256900D02*
Y252100D01*
G01X379400Y55500D02*
X374600D01*
G01X430000Y82600D02*
Y87400D01*
G01X442300Y179000D02*
X437500D01*
G01X449400D02*
X444600D01*
G01X434500Y203100D02*
Y207900D01*
G01X447100Y266500D02*
X451900D01*
G01X587100Y233500D02*
X591900D01*
G01X579600D02*
X584400D01*
G01X618300Y50507D02*
X613500D01*
G01X611200D02*
X606400D01*
G01X632100Y233500D02*
X636900D01*
G01X639600D02*
X644400D01*
G01X679100Y50707D02*
X674300D01*
G01X672000D02*
X667200D01*
G01X765100Y125500D02*
X769900D01*
G01X778400Y233000D02*
Y228200D01*
G01Y240400D02*
Y235600D01*
G01X790500Y103400D02*
Y98600D01*
G01Y110900D02*
Y106100D01*
G01X800800Y176200D02*
X802100D01*
G01X801100Y227000D02*
Y231800D01*
G01Y219900D02*
Y224700D01*
G01Y236600D02*
Y241400D01*
G01Y243800D02*
Y248600D01*
G01X800000Y278400D02*
Y277100D01*
G01Y281900D02*
Y280600D01*
G01X804300Y176200D02*
X805600D01*
G54D14*
G01X0Y72440D02*
Y103149D01*
G01Y210235D02*
Y240944D01*
G01Y348031D02*
Y378739D01*
G01Y485826D02*
Y516535D01*
G01X133465Y290550D02*
X102756D01*
G01X133465Y298424D02*
X102756D01*
G01X330314Y290551D02*
X299606D01*
G01X330314Y298425D02*
X299606D01*
G01X527166Y290550D02*
X496457D01*
G01X527166Y298424D02*
X496457D01*
G01X724016Y290550D02*
X693308D01*
G01X724016Y298424D02*
X693308D01*
G01X826771Y103149D02*
Y72440D01*
G01Y240944D02*
Y210235D01*
G01Y378739D02*
Y348031D01*
G01Y516535D02*
Y485826D01*
G54D15*
G01X557120Y122790D02*
X556470D01*
G01X556290Y122590D02*
X556930D01*
G01X557020Y122680D02*
X556380D01*
G01X556200Y122490D02*
X556840D01*
G01X556740Y122380D02*
X556100D01*
G01X556010Y122290D02*
X556650D01*
G01X556560Y122180D02*
X555920D01*
G01X555820Y122090D02*
X556470D01*
G01X556370Y121990D02*
X555730D01*
G01X555640Y121880D02*
X556280D01*
G01X556190Y121790D02*
X555540D01*
G01X555450Y121680D02*
X556090D01*
G01X556000Y121590D02*
X555360D01*
G01X555170Y121380D02*
X555810D01*
G01X555630Y121180D02*
X555020D01*
G01X555030Y121240D02*
X558840Y125330D01*
G01X555360Y120900D02*
X555340Y120880D01*
G01X558490Y124270D02*
X555360Y120900D01*
G01X555440Y120990D02*
X555220D01*
G01X555260Y121490D02*
X555910D01*
G01X555720Y121290D02*
X555080D01*
G01X555310Y120900D02*
X555340Y120880D01*
G01X555020Y121190D02*
X555310Y120900D01*
G01X555010Y121210D02*
X555020Y121190D01*
G01Y121220D02*
X555010Y121210D01*
G01X555030Y121240D02*
X555020Y121220D01*
G01X555540Y121090D02*
X555120D01*
G01X557170Y136880D02*
X556540D01*
G01X556440Y136990D02*
X557070D01*
G01X556970Y137090D02*
X556340D01*
G01X556150Y137290D02*
X556780D01*
G01X556590Y137490D02*
X555960D01*
G01X558650Y135350D02*
X554070Y140090D01*
G01X554040Y139480D02*
X557970Y135400D01*
G01X556880Y137180D02*
X556250D01*
G01X556060Y137380D02*
X556690D01*
G01X556490Y137590D02*
X555860D01*
G01X555760Y137680D02*
X556390D01*
G01X556300Y137790D02*
X555670D01*
G01X555570Y137880D02*
X556200D01*
G01X556100Y137990D02*
X555480D01*
G01X555380Y138090D02*
X556010D01*
G01X555820Y138290D02*
X555190D01*
G01X554990Y138490D02*
X555620D01*
G01X555430Y138680D02*
X554800D01*
G01X554900Y138590D02*
X555520D01*
G01X555330Y138790D02*
X554710D01*
G01X554610Y138880D02*
X555240D01*
G01X555140Y138990D02*
X554510D01*
G01X554410Y139090D02*
X555040D01*
G01X554950Y139180D02*
X554320D01*
G01X554220Y139290D02*
X554850D01*
G01X554750Y139380D02*
X554130D01*
G01X554020Y139590D02*
X554560D01*
G01X554030Y139510D02*
X554020Y139590D01*
G01X554040Y139480D02*
X554030Y139510D01*
G01X554650Y139490D02*
X554040D01*
G01X554020Y140080D02*
X554070Y140090D01*
G01X554020Y139590D02*
Y140080D01*
G01X554080Y140090D02*
X554040D01*
G01X554020Y139990D02*
X554170D01*
G01X554270Y139880D02*
X554020D01*
G01Y139790D02*
X554370D01*
G01X554460Y139680D02*
X554020D01*
G01X555090Y138380D02*
X555720D01*
G01X555910Y138180D02*
X555280D01*
G01X570330Y122590D02*
X570990D01*
G01X570890Y122680D02*
X570230D01*
G01X570140Y122790D02*
X570790D01*
G01X570690Y122880D02*
X570040D01*
G01X569940Y122990D02*
X570600D01*
G01X570500Y123090D02*
X569850D01*
G01X569750Y123180D02*
X570400D01*
G01X570310Y123290D02*
X569650D01*
G01X569560Y123380D02*
X570210D01*
G01X570120Y123490D02*
X569460D01*
G01X569360Y123590D02*
X570020D01*
G01X569920Y123680D02*
X569270D01*
G01X569170Y123790D02*
X569815D01*
G01X569820D02*
X569770D01*
G01X569730Y123880D02*
X569690D01*
G01X569730D02*
X569080D01*
G01X568980Y123990D02*
X569630D01*
G01X569530Y124090D02*
X568880D01*
G01X568780Y124180D02*
X569440D01*
G01X569340Y124290D02*
X568690D01*
G01X568590Y124380D02*
X569250D01*
G01X569150Y124490D02*
X568490D01*
G01X568400Y124590D02*
X569050D01*
G01X568950Y124680D02*
X568300D01*
G01X568210Y124790D02*
X568860D01*
G01X568760Y124880D02*
X568110D01*
G01X568010Y124990D02*
X568670D01*
G01X568570Y125090D02*
X567910D01*
G01X567820Y125180D02*
X568470D01*
G01X568380Y125290D02*
X567720D01*
G01X567530Y125490D02*
X568180D01*
G01X567990Y125680D02*
X567340D01*
G01X567380Y133830D02*
X572560Y139420D01*
G01X568850Y136090D02*
X569470D01*
G01X569380Y135990D02*
X568760D01*
G01X568660Y135880D02*
X569280D01*
G01X569190Y135790D02*
X568570D01*
G01X568480Y135680D02*
X569100D01*
G01X569010Y135590D02*
X568380D01*
G01X568290Y135490D02*
X568910D01*
G01X568820Y135380D02*
X568200D01*
G01X568110Y135290D02*
X568730D01*
G01X568630Y135180D02*
X568010D01*
G01X567920Y135090D02*
X568540D01*
G01X568450Y134990D02*
X567830D01*
G01X567730Y134880D02*
X568350D01*
G01X568170Y134680D02*
X566930D01*
G01X566920Y134490D02*
X567980D01*
G01X566800Y133890D02*
X563570Y130410D01*
G01X566810Y133890D02*
X566800D01*
G01X566850Y133940D02*
X566810Y133890D01*
G01X566880Y134000D02*
X566850Y133940D01*
G01X567060Y136130D02*
X566880Y134000D01*
G01X566960Y136240D02*
X567060Y136130D01*
G01X566540Y130090D02*
X567010D01*
G01X567020Y130290D02*
X566560D01*
G01X566580Y130490D02*
X567040D01*
G01X567060Y130680D02*
X566590D01*
G01X566610Y130880D02*
X567080D01*
G01X567100Y131090D02*
X566630D01*
G01X566640Y131290D02*
X567110D01*
G01X567130Y131490D02*
X566660D01*
G01X566680Y131680D02*
X567150D01*
G01X567160Y131880D02*
X566690D01*
G01X566710Y132090D02*
X567180D01*
G01X567200Y132290D02*
X566730D01*
G01X566750Y132490D02*
X567210D01*
G01X567230Y132680D02*
X566760D01*
G01X566780Y132880D02*
X567250D01*
G01X567260Y132990D02*
X566750D01*
G01X566250Y133290D02*
X567280D01*
G01X567300Y133490D02*
X566430D01*
G01X567360Y133800D02*
X567380Y133830D01*
G01X567320Y133700D02*
X567360Y133800D01*
G01X567320Y133690D02*
Y133700D01*
G01Y133680D02*
Y133690D01*
G01X566620Y133680D02*
X567320D01*
G01X567420Y133880D02*
X566800D01*
G01X566870Y133990D02*
X567520D01*
G01X567610Y134090D02*
X566880D01*
G01X566890Y134180D02*
X567700D01*
G01X567800Y134290D02*
X566900D01*
G01X566910Y134380D02*
X567890D01*
G01X568080Y134590D02*
X566930D01*
G01X566940Y134790D02*
X567420D01*
G01X567530Y136150D02*
X567630Y136240D01*
G01X567410Y134800D02*
X567530Y136150D01*
G01X567060Y136090D02*
X567520D01*
G01X567510Y135990D02*
X567040D01*
G01Y135880D02*
X567510D01*
G01X567500Y135790D02*
X567030D01*
G01X567020Y135680D02*
X567490D01*
G01X567480Y135590D02*
X567010D01*
G01X567000Y135490D02*
X567470D01*
G01X567460Y135380D02*
X566990D01*
G01Y135290D02*
X567450D01*
G01Y135180D02*
X566980D01*
G01X566970Y135090D02*
X567430D01*
G01Y134990D02*
X566960D01*
G01X566950Y134880D02*
X567420D01*
G01X567580Y134730D02*
X572600Y140120D01*
G01X567470Y134700D02*
X567580Y134730D01*
G01X567410Y134800D02*
X567470Y134700D01*
G01X568260Y134790D02*
X567640D01*
G01X567320Y133680D02*
X566880Y128530D01*
G01X566870Y128490D02*
X566400D01*
G01X566390Y128290D02*
X566860D01*
G01X566840Y128090D02*
X566370D01*
G01X566350Y127880D02*
X566820D01*
G01X566800Y127680D02*
X566330D01*
G01X566290Y127590D02*
X566790D01*
G01X566780Y126940D02*
X566880Y126830D01*
G01X566750Y127010D02*
X566780Y126940D01*
G01X566930Y126790D02*
X566240D01*
G01Y126590D02*
X567120D01*
G01X567310Y126380D02*
X566220D01*
G01X566860Y126180D02*
X567510D01*
G01X567600Y126090D02*
X566950D01*
G01X567050Y125990D02*
X567700D01*
G01X567800Y125880D02*
X567140D01*
G01X567240Y125790D02*
X567890D01*
G01X568080Y125590D02*
X567430D01*
G01X567630Y125380D02*
X568280D01*
G01X566900Y128790D02*
X566430D01*
G01X566450Y128990D02*
X566910D01*
G01X566930Y129180D02*
X566460D01*
G01X566480Y129380D02*
X566950D01*
G01X566970Y129590D02*
X566500D01*
G01X566510Y129790D02*
X566980D01*
G01X566990Y129880D02*
X566520D01*
G01X566530Y129990D02*
X567000D01*
G01X567020Y130180D02*
X566550D01*
G01X566560Y130380D02*
X567030D01*
G01X567050Y130590D02*
X566580D01*
G01X566600Y130790D02*
X567070D01*
G01X567080Y130990D02*
X566620D01*
G01X566640Y131180D02*
X567100D01*
G01X567120Y131380D02*
X566650D01*
G01X566670Y131590D02*
X567140D01*
G01X567150Y131790D02*
X566690D01*
G01X566700Y131990D02*
X567170D01*
G01X567190Y132180D02*
X566720D01*
G01X566740Y132380D02*
X567210D01*
G01X567220Y132590D02*
X566760D01*
G01X566770Y132790D02*
X567240D01*
G01X566610Y133010D02*
X563880Y130070D01*
G01X566730Y133030D02*
X566610Y133010D01*
G01X566780Y132930D02*
X566730Y133030D01*
G01X566510Y129680D02*
X566970D01*
G01X566960Y129490D02*
X566490D01*
G01X566470Y129290D02*
X566940D01*
G01X566920Y129090D02*
X566450D01*
G01X566440Y128880D02*
X566910D01*
G01X566890Y128680D02*
X566420D01*
G01X566410Y128590D02*
X566880D01*
G01X566750Y127070D02*
Y127010D01*
G01X566880Y128530D02*
X566750Y127070D01*
G01X566760Y126990D02*
X566080D01*
G01X566230Y126810D02*
X566250Y126740D01*
G01X566180Y126890D02*
X566230Y126810D01*
G01X566250Y126680D02*
X567020D01*
G01X567210Y126490D02*
X566230D01*
G01X566210Y126180D02*
X566710D01*
G01X566740Y126220D02*
X566840Y126200D01*
G01X566470Y123780D02*
X566360D01*
G01X566470Y123790D02*
Y123780D01*
G01X566670Y126140D02*
X566470Y123790D01*
G01X566740Y126220D02*
X566670Y126140D01*
G01X566370Y123880D02*
X566480D01*
G01X566475D02*
X560880D01*
G01X560815Y123790D02*
X566470D01*
G01X566230Y122740D02*
X565340D01*
G01X566270Y122780D02*
X566230Y122740D01*
G01X566270Y123460D02*
Y122780D01*
G01X566300Y123530D02*
X566270Y123460D01*
G01X566450Y123690D02*
X566300Y123530D01*
G01X566460Y123710D02*
X566450Y123690D01*
G01X566470Y123770D02*
X566460Y123710D01*
G01X565300Y122790D02*
X566270D01*
G01Y122990D02*
X565300D01*
G01Y123180D02*
X566270D01*
G01Y123380D02*
X565300D01*
G01X566020Y124090D02*
X566490D01*
G01X566510Y124180D02*
X566040D01*
G01X566050Y124380D02*
X566520D01*
G01X566540Y124590D02*
X566070D01*
G01X566090Y124790D02*
X566560D01*
G01X566570Y124990D02*
X566100D01*
G01X566120Y125180D02*
X566590D01*
G01X566610Y125380D02*
X566140D01*
G01X566150Y125590D02*
X566620D01*
G01X566640Y125790D02*
X566170D01*
G01X566190Y125990D02*
X566650D01*
G01X566760Y127180D02*
X565890D01*
G01X565700Y127380D02*
X566780D01*
G01X566810Y127790D02*
X566340D01*
G01X566330Y127640D02*
X566780Y132930D01*
G01X566590Y132990D02*
X565970D01*
G01X565780Y132790D02*
X566400D01*
G01X566220Y132590D02*
X565600D01*
G01X566340Y133380D02*
X567290D01*
G01X567310Y133590D02*
X566520D01*
G01X566710Y133790D02*
X567350D01*
G01X566390Y128380D02*
X566860D01*
G01X566850Y128180D02*
X566380D01*
G01X566360Y127990D02*
X566830D01*
G01X566260Y127550D02*
X566160Y127580D01*
G01X566330Y127640D02*
X566260Y127550D01*
G01X566350Y123590D02*
X560570D01*
G01X566030Y124160D02*
X566250Y126740D01*
G01X566030Y124090D02*
Y124160D01*
G01X565930Y124000D02*
X566030Y124090D01*
G01X561830Y124000D02*
X565930D01*
G01X566180Y126880D02*
X566830D01*
G01X566750Y127090D02*
X565990D01*
G01X566170Y126890D02*
X566180D01*
G01X566170Y126900D02*
Y126890D01*
G01Y126900D02*
X563580Y129590D01*
G01X563770Y129380D02*
X564410D01*
G01X564610Y129180D02*
X563960D01*
G01X564150Y128990D02*
X564800D01*
G01X564990Y128790D02*
X564350D01*
G01X564440Y128680D02*
X565090D01*
G01X565040Y128740D02*
X566160Y127580D01*
G01X566150Y127590D02*
X565510D01*
G01X565600Y127490D02*
X566780D01*
G01X566770Y127290D02*
X565790D01*
G01X566050Y127680D02*
X565410D01*
G01X565310Y127790D02*
X565950D01*
G01X565860Y127880D02*
X565210D01*
G01X565120Y127990D02*
X565760D01*
G01X565670Y128090D02*
X565020D01*
G01X564930Y128180D02*
X565570D01*
G01X565470Y128290D02*
X564830D01*
G01X564730Y128380D02*
X565380D01*
G01X565280Y128490D02*
X564640D01*
G01X564540Y128590D02*
X565190D01*
G01X564360Y130590D02*
X563730D01*
G01X563920Y130790D02*
X564540D01*
G01X564730Y130990D02*
X564110D01*
G01X564290Y131180D02*
X564920D01*
G01X565010Y131290D02*
X564390D01*
G01X564480Y131380D02*
X565100D01*
G01X565190Y131490D02*
X564570D01*
G01X564670Y131590D02*
X565290D01*
G01X565380Y131680D02*
X564760D01*
G01X564850Y131790D02*
X565470D01*
G01X565570Y131880D02*
X564940D01*
G01X565040Y131990D02*
X565660D01*
G01X565750Y132090D02*
X565130D01*
G01X565220Y132180D02*
X565850D01*
G01X565940Y132290D02*
X565320D01*
G01X565410Y132380D02*
X566030D01*
G01X566120Y132490D02*
X565500D01*
G01X565690Y132680D02*
X566310D01*
G01X566500Y132880D02*
X565880D01*
G01X566060Y133090D02*
X567260D01*
G01X567270Y133180D02*
X566150D01*
G01X564300Y132460D02*
X564260Y132420D01*
G01X566210Y126290D02*
X567410D01*
G01X566670Y126090D02*
X566200D01*
G01X566180Y125880D02*
X566650D01*
G01X566630Y125680D02*
X566160D01*
G01X566150Y125490D02*
X566620D01*
G01X566600Y125290D02*
X566130D01*
G01X566110Y125090D02*
X566580D01*
G01X566560Y124880D02*
X566100D01*
G01X566080Y124680D02*
X566540D01*
G01X566530Y124490D02*
X566060D01*
G01X566040Y124290D02*
X566510D01*
G01X566280Y123490D02*
X565230D01*
G01X565300Y122780D02*
X565340Y122740D01*
G01X565300Y123420D02*
Y122780D01*
G01X565200Y123520D02*
X565300Y123420D01*
G01Y122880D02*
X566270D01*
G01Y123090D02*
X565300D01*
G01Y123290D02*
X566270D01*
G01X561730Y124470D02*
Y124480D01*
G01X561740Y124400D02*
X561730Y124470D01*
G01X561740Y124140D02*
Y124400D01*
G01X561730Y124120D02*
X561740Y124140D01*
G01X561830Y124000D02*
X561730Y124120D01*
G01Y124490D02*
X560960D01*
G01X561000Y124290D02*
X561740D01*
G01X561760Y124090D02*
X560960D01*
G01X563120Y129920D02*
Y130060D01*
G01X560420Y127020D02*
X563120Y129920D01*
G01X563100Y130090D02*
X563890D01*
G01X563880Y129930D02*
X565040Y128740D01*
G01X563880Y130070D02*
Y129930D01*
G01X564890Y128880D02*
X564250D01*
G01X564060Y129090D02*
X564700D01*
G01X564510Y129290D02*
X563860D01*
G01X563670Y129490D02*
X564320D01*
G01X563430Y129590D02*
X561750Y127770D01*
G01X563580Y129590D02*
X563430D01*
G01X564220D02*
X563580D01*
G01X561760Y127790D02*
X561130D01*
G01X561320Y127990D02*
X561950D01*
G01X562130Y128180D02*
X561500D01*
G01X561690Y128380D02*
X562320D01*
G01X562410Y128490D02*
X561780D01*
G01X561880Y128590D02*
X562510D01*
G01X562600Y128680D02*
X561970D01*
G01X562060Y128790D02*
X562690D01*
G01X562780Y128880D02*
X562150D01*
G01X562250Y128990D02*
X562880D01*
G01X562970Y129090D02*
X562340D01*
G01X562430Y129180D02*
X563060D01*
G01X563150Y129290D02*
X562520D01*
G01X562620Y129380D02*
X563250D01*
G01X563340Y129490D02*
X562710D01*
G01X562800Y129590D02*
X563450D01*
G01X563080Y129880D02*
X563930D01*
G01X563880Y129990D02*
X563120D01*
G01X563000Y130180D02*
X563990D01*
G01X564080Y130290D02*
X562900D01*
G01X562800Y130380D02*
X564170D01*
G01X564260Y130490D02*
X563640D01*
G01X563430Y130410D02*
X562000Y131880D01*
G01X563570Y130410D02*
X563430D01*
G01X562100Y131790D02*
X561460D01*
G01X561650Y131590D02*
X562290D01*
G01X562380Y131490D02*
X561750D01*
G01X561840Y131380D02*
X562480D01*
G01X562580Y131290D02*
X561940D01*
G01X562030Y131180D02*
X562670D01*
G01X562770Y131090D02*
X562130D01*
G01X562230Y130990D02*
X562870D01*
G01X562960Y130880D02*
X562320D01*
G01X562420Y130790D02*
X563060D01*
G01X563150Y130680D02*
X562520D01*
G01X562610Y130590D02*
X563250D01*
G01X563350Y130490D02*
X562710D01*
G01X562990Y129790D02*
X564020D01*
G01X564120Y129680D02*
X562900D01*
G01X563830Y130680D02*
X564450D01*
G01X564640Y130880D02*
X564010D01*
G01X564200Y131090D02*
X564820D01*
G01X564210Y132420D02*
X561720D01*
G01X564260D02*
X564210D01*
G01X561710Y132180D02*
X561070D01*
G01X561260Y131990D02*
X561900D01*
G01X560780Y132490D02*
X564300D01*
G01X564260Y133450D02*
X564210D01*
G01X564300Y133410D02*
X564260Y133450D01*
G01X564300Y132460D02*
Y133410D01*
G01Y133290D02*
X561040D01*
G01X561010Y133090D02*
X564300D01*
G01Y132880D02*
X560390D01*
G01X560590Y132680D02*
X564300D01*
G01X561090Y133450D02*
X564210D01*
G01X564300Y133380D02*
X561040D01*
G01X561050Y133410D02*
X561090Y133450D01*
G01X560870Y133060D02*
X560670Y133260D01*
G01X560980Y133030D02*
X560870Y133060D01*
G01X561040Y133130D02*
X560980Y133030D01*
G01X561040Y133310D02*
Y133130D01*
G01Y133320D02*
Y133310D01*
G01X561050Y133410D02*
X561040Y133320D01*
G01X560840Y133090D02*
X560200D01*
G01X561040Y133180D02*
X564300D01*
G01X562190Y131680D02*
X561550D01*
G01X561630Y132360D02*
X561720Y132420D01*
G01X561650Y132250D02*
X561630Y132360D01*
G01X562000Y131880D02*
X561650Y132250D01*
G01X561360Y131880D02*
X562000D01*
G01X561670Y132380D02*
X560880D01*
G01X560970Y132290D02*
X561640D01*
G01X561800Y132090D02*
X561170D01*
G01X561600Y128290D02*
X562230D01*
G01X562040Y128090D02*
X561410D01*
G01X561230Y127880D02*
X561860D01*
G01X561670Y127680D02*
X561040D01*
G01X560950Y127590D02*
X561580D01*
G01X561490Y127490D02*
X560850D01*
G01X560760Y127380D02*
X561390D01*
G01X561300Y127290D02*
X560670D01*
G01X560480Y127090D02*
X561110D01*
G01X560930Y126880D02*
X559790D01*
G01X559800Y126790D02*
X560830D01*
G01X561690Y124660D02*
X561730Y124480D01*
G01X561690Y124670D02*
Y124660D01*
G01X561580Y124980D02*
X561690Y124670D01*
G01X561570Y124990D02*
X561580Y124980D01*
G01X561360Y125300D02*
X561570Y124990D01*
G01X561350Y125310D02*
X561360Y125300D01*
G01X561110Y125530D02*
X561350Y125310D01*
G01X561100Y125530D02*
X561110D01*
G01X560980Y125610D02*
X561100Y125530D01*
G01X560970Y125620D02*
X560980Y125610D01*
G01X560910Y125650D02*
X560970Y125620D01*
G01X560750Y125720D02*
X560910Y125650D01*
G01X561740Y124380D02*
X560980D01*
G01X560940Y123990D02*
X566490D01*
G01X560950Y124010D02*
X560940Y123990D01*
G01X561000Y124270D02*
X560950Y124010D01*
G01X561000Y124280D02*
Y124270D01*
G01Y124300D02*
Y124280D01*
G01X566450Y123680D02*
X560710D01*
G01X560790Y123750D02*
X560850Y123840D01*
G01X560780Y123740D02*
X560790Y123750D01*
G01X560770Y123730D02*
X560780Y123740D01*
G01X560930Y123980D02*
X560940Y123990D01*
G01X560850Y123850D02*
X560930Y123980D01*
G01X560980Y124180D02*
X561740D01*
G01X561710Y124590D02*
X560940D01*
G01X560950Y124560D02*
X561000Y124300D01*
G01X560940Y124580D02*
X560950Y124560D01*
G01X560720Y124310D02*
X560710Y124330D01*
G01X560770Y124840D02*
X560550Y125000D01*
G01X560780Y124830D02*
X560770Y124840D01*
G01X560790Y124810D02*
X560780Y124830D01*
G01X560930Y124600D02*
X560790Y124810D01*
G01X560940Y124580D02*
X560930Y124600D01*
G01X560710Y124880D02*
X561610D01*
G01X561650Y124790D02*
X560810D01*
G01X560880Y124680D02*
X561690D01*
G01X561510Y125090D02*
X560250D01*
G01X560840Y125680D02*
X559170D01*
G01X559080Y125590D02*
X561020D01*
G01X561260Y125380D02*
X558890D01*
G01X558710Y125180D02*
X561430D01*
G01X560850Y123790D02*
X560810D01*
G01X560770Y123730D02*
X560550Y123570D01*
G01X560980Y122990D02*
X559430D01*
G01X559270Y123090D02*
X561160D01*
G01X561600Y123520D02*
X565200D01*
G01X561520Y123490D02*
X561600Y123520D01*
G01X561510Y123480D02*
X561520Y123490D01*
G01X561510Y123470D02*
Y123480D01*
G01X561470Y123400D02*
X561510Y123470D01*
G01X561460Y123400D02*
X561470D01*
G01X561450Y123390D02*
X561460Y123400D01*
G01X561380Y123290D02*
X561450Y123390D01*
G01X561370Y123280D02*
X561380Y123290D01*
G01X561140Y123060D02*
X561370Y123280D01*
G01Y123290D02*
X559030D01*
G01X561120Y123050D02*
X561140Y123060D01*
G01X560320Y122750D02*
X559980Y122760D01*
G01X560330Y122750D02*
X560320D01*
G01X560340D02*
X560330D01*
G01X560500Y122770D02*
X560340Y122750D01*
G01X560520Y122770D02*
X560500D01*
G01X561120Y123050D02*
X560520Y122770D01*
G01X559870Y122790D02*
X560540D01*
G01Y123560D02*
X560550Y123570D01*
G01X560520Y123560D02*
X560540D01*
G01X560350Y123500D02*
X560520Y123560D01*
G01X560130Y123490D02*
X560110D01*
G01X560260D02*
X560130D01*
G01X560330Y123500D02*
X560260Y123490D01*
G01X560350Y123500D02*
X560330D01*
G01X560690Y124120D02*
X560720Y124310D01*
G01X560680Y124090D02*
X560690Y124120D01*
G01X560510Y123870D02*
X560680Y124090D01*
G01X560490Y123860D02*
X560510Y123870D01*
G01X560320Y123780D02*
X560490Y123860D01*
G01X560310Y123780D02*
X560320D01*
G01X560270Y123770D02*
X560310Y123780D01*
G01X560210Y123770D02*
X560270D01*
G01X560190D02*
X560210D01*
G01X560160Y124800D02*
X560150D01*
G01X560250D02*
X560160D01*
G01X560270Y124790D02*
X560250Y124800D01*
G01X560580Y124630D02*
X560270Y124790D01*
G01X560600Y124610D02*
X560580Y124630D01*
G01X560710Y124330D02*
X560600Y124610D01*
G01X560540Y125010D02*
X560550Y125000D01*
G01X560520Y125010D02*
X560540D01*
G01X560350Y125070D02*
X560520Y125010D01*
G01X560330Y125070D02*
X560350D01*
G01X560260Y125080D02*
X560330Y125070D01*
G01X560240Y125090D02*
X560260Y125080D01*
G01X560180Y125090D02*
X560240D01*
G01X560150Y125080D02*
X560180Y125090D01*
G01X560570Y124990D02*
X561570D01*
G01X560660Y124470D02*
X559720D01*
G01X559700Y124270D02*
X560710D01*
G01X560660Y124070D02*
X559750D01*
G01X559930Y123870D02*
X560500D01*
G01X560190Y123770D02*
X560060Y123790D01*
G01X559860Y124660D02*
X560510D01*
G01X560110Y125080D02*
X559910Y125030D01*
G01X560150Y125080D02*
X560110D01*
G01X560660Y125750D02*
X560750Y125720D01*
G01X560650Y125760D02*
X560660Y125750D01*
G01X560510Y125790D02*
X560650Y125760D01*
G01X560430Y125810D02*
X560510Y125790D01*
G01X560650Y126590D02*
X561750Y127770D01*
G01X560390Y126310D02*
X560650Y126590D01*
G01X560360Y126260D02*
X560390Y126310D01*
G01X560330Y126110D02*
X560360Y126260D01*
G01X560320Y126090D02*
X560330Y126110D01*
G01X560320Y126070D02*
Y126090D01*
G01X560340Y125900D02*
X560320Y126070D01*
G01X560340Y125890D02*
Y125900D01*
G01X560430Y125810D02*
X560340Y125890D01*
G01X561210Y127180D02*
X560570D01*
G01X560250Y127080D02*
X559740Y133310D01*
G01X560310Y127000D02*
X560250Y127080D01*
G01X560420Y127020D02*
X560310Y127000D01*
G01X560650Y133290D02*
X560670Y133260D01*
G01X560010Y133290D02*
X560650D01*
G01D02*
X559840Y134130D01*
G01X560260Y133680D02*
X558000D01*
G01Y133490D02*
X560450D01*
G01X560750Y133180D02*
X560110D01*
G01X560300Y132990D02*
X564300D01*
G01Y132790D02*
X560490D01*
G01X560690Y132590D02*
X564300D01*
G01X560080Y129090D02*
X559620D01*
G01X559630Y128880D02*
X560100D01*
G01X560120Y128680D02*
X559650D01*
G01X559660Y128490D02*
X560130D01*
G01X560150Y128290D02*
X559680D01*
G01X559690Y128090D02*
X560160D01*
G01X560180Y127880D02*
X559710D01*
G01X559730Y127680D02*
X560190D01*
G01X560210Y127490D02*
X559750D01*
G01X559760Y127290D02*
X560230D01*
G01X560250Y127090D02*
X559780D01*
G01X559820Y126590D02*
X560650D01*
G01X560460Y126380D02*
X559820D01*
G01X559640Y126180D02*
X560340D01*
G01X560330Y125990D02*
X559450D01*
G01X558000Y135180D02*
X559780D01*
G01X559810Y134160D02*
X559840Y134130D01*
G01X559780Y134220D02*
X559810Y134160D01*
G01X559780Y135240D02*
Y134220D01*
G01X559880Y134090D02*
X559210D01*
G01X559040Y134290D02*
X559780D01*
G01Y134490D02*
X558850D01*
G01X558660Y134680D02*
X559780D01*
G01Y134790D02*
X558000D01*
G01Y134990D02*
X559780D01*
G01X559670Y135320D02*
X559570Y135420D01*
G01X559740Y135320D02*
X559670D01*
G01X559780Y135280D02*
X559740Y135320D01*
G01X559780Y135240D02*
Y135280D01*
G01X560070Y133880D02*
X558000D01*
G01X559280Y133180D02*
X559750D01*
G01X559910Y133390D02*
X563120Y130060D01*
G01X559800Y133410D02*
X559910Y133390D01*
G01X559740Y133310D02*
X559800Y133410D01*
G01X560020Y129880D02*
X559550D01*
G01X559540Y129990D02*
X560010D01*
G01X559990Y130180D02*
X559520D01*
G01X559510Y130380D02*
X559970D01*
G01X559960Y130590D02*
X559490D01*
G01X559480Y130790D02*
X559940D01*
G01X559930Y130990D02*
X559460D01*
G01X559440Y131180D02*
X559910D01*
G01X559890Y131380D02*
X559430D01*
G01X559410Y131590D02*
X559880D01*
G01X559860Y131790D02*
X559390D01*
G01X559380Y131990D02*
X559840D01*
G01X559830Y132180D02*
X559360D01*
G01X559350Y132380D02*
X559810D01*
G01X559800Y132590D02*
X559330D01*
G01X559310Y132790D02*
X559780D01*
G01X559760Y132990D02*
X559300D01*
G01X559910Y133380D02*
X560550D01*
G01X560030Y129680D02*
X559560D01*
G01X559580Y129490D02*
X560050D01*
G01X560060Y129290D02*
X559600D01*
G01X559610Y129180D02*
X560070D01*
G01X560090Y128990D02*
X559620D01*
G01X559640Y128790D02*
X560110D01*
G01X560120Y128590D02*
X559650D01*
G01X559670Y128380D02*
X560140D01*
G01X560150Y128180D02*
X559690D01*
G01X559700Y127990D02*
X560170D01*
G01X560190Y127790D02*
X559720D01*
G01X559740Y127590D02*
X560200D01*
G01X560220Y127380D02*
X559750D01*
G01X559770Y127180D02*
X560240D01*
G01X559780Y126990D02*
X561020D01*
G01X560740Y126680D02*
X559810D01*
G01X559820Y126490D02*
X560550D01*
G01X560380Y126290D02*
X559740D01*
G01X559800Y126350D02*
X558840Y125330D01*
G01X558520Y124990D02*
X559850D01*
G01X559870Y125010D02*
X559910Y125030D01*
G01X559870Y125010D02*
X559560Y124750D01*
G01X559790Y124570D02*
X560620D01*
G01X560700Y124370D02*
X559710D01*
G01X559900Y124700D02*
X560150Y124800D01*
G01X559880Y124690D02*
X559900Y124700D01*
G01X559730Y124490D02*
X559880Y124690D01*
G01X559720Y124460D02*
X559730Y124490D01*
G01X560060Y124770D02*
X560330D01*
G01X560040Y123790D02*
X560060D01*
G01X559820Y123930D02*
X560040Y123790D01*
G01X559810Y123950D02*
X559820Y123930D01*
G01X559700Y124180D02*
X559810Y123950D01*
G01X559690Y124200D02*
X559700Y124180D01*
G01X559720Y124460D02*
X559690Y124200D01*
G01X559850Y123590D02*
X558830D01*
G01X559970Y122760D02*
X559980D01*
G01X559680Y122830D02*
X559970Y122760D01*
G01X559670Y122840D02*
X559680Y122830D01*
G01X559160Y123150D02*
X559670Y122840D01*
G01X559910Y123540D02*
X559870Y123560D01*
G01X560110Y123490D02*
X559910Y123540D01*
G01X559800Y123970D02*
X560580D01*
G01X560700Y124160D02*
X559700D01*
G01X559810Y126370D02*
X559830Y126440D01*
G01X559800Y126360D02*
X559810Y126370D01*
G01X559800Y126350D02*
Y126360D01*
G01X559510Y136130D02*
X559570Y135420D01*
G01X559600Y135380D02*
X559050D01*
G01X558760Y136110D02*
X558730Y136100D01*
G01X558840Y136120D02*
X558760Y136110D01*
G01X558910Y136140D02*
X558840Y136120D01*
G01X558920Y136140D02*
X558910D01*
G01X559050Y136050D02*
X558920Y136140D01*
G01X559100Y135440D02*
X559050Y136050D01*
G01X559000Y135330D02*
X559100Y135440D01*
G01X559000Y136090D02*
X559510D01*
G01Y136130D02*
X559610Y136240D01*
G01X559970Y133990D02*
X559150D01*
G01X559180Y134140D02*
X558630Y134720D01*
G01X559210Y134090D02*
X559180Y134140D01*
G01X559210Y134050D02*
Y134090D01*
G01X559110Y133940D02*
X559210Y134050D01*
G01X558750Y134590D02*
X559780D01*
G01Y134380D02*
X558950D01*
G01X559140Y134180D02*
X559800D01*
G01X559780Y133380D02*
X559250D01*
G01X559260Y133370D02*
X559830Y126440D01*
G01X559550Y126090D02*
X560320D01*
G01X560350Y125880D02*
X559360D01*
G01X559270Y125790D02*
X560540D01*
G01X561150Y125490D02*
X558990D01*
G01X558800Y125290D02*
X561370D01*
G01X561520Y123490D02*
X558890D01*
G01X559070Y123240D02*
X559160Y123150D01*
G01X559010Y123310D02*
X559070Y123240D01*
G01X558880Y123500D02*
X559010Y123310D01*
G01X559120Y123180D02*
X561270D01*
G01X561450Y123380D02*
X558960D01*
G01X558760Y123750D02*
X558700Y123920D01*
G01X558800Y123650D02*
X558760Y123750D01*
G01X558800Y123640D02*
Y123650D01*
G01X558870Y123510D02*
X558800Y123640D01*
G01X558880Y123500D02*
X558870Y123510D01*
G01X558710Y123880D02*
X559525D01*
G01X559520D02*
X559460D01*
G01X559560Y123820D02*
X559870Y123560D01*
G01X559530Y123870D02*
X559560Y123820D01*
G01X559730Y123680D02*
X558780D01*
G01X558750Y123790D02*
X559540D01*
G01X558780D02*
X558750D01*
G01X559530Y124700D02*
X559560Y124750D01*
G01X559410Y124310D02*
X559530Y124700D01*
G01X559410Y124250D02*
Y124310D01*
G01X559530Y123870D02*
X559410Y124250D01*
G01X559600Y124790D02*
X558340D01*
G01X558150Y124590D02*
X559490D01*
G01X559430Y124380D02*
X557970D01*
G01X558670Y124180D02*
X559430D01*
G01X559490Y123990D02*
X558690D01*
G01X559600Y122880D02*
X560760D01*
G01X560060Y129380D02*
X559590D01*
G01X559570Y129590D02*
X560040D01*
G01X560020Y129790D02*
X559560D01*
G01X559530Y130090D02*
X560000D01*
G01X559990Y130290D02*
X559520D01*
G01X559500Y130490D02*
X559970D01*
G01X559950Y130680D02*
X559490D01*
G01X559470Y130880D02*
X559930D01*
G01X559920Y131090D02*
X559450D01*
G01X559430Y131290D02*
X559900D01*
G01X559890Y131490D02*
X559420D01*
G01X559400Y131680D02*
X559870D01*
G01X559850Y131880D02*
X559390D01*
G01X559370Y132090D02*
X559840D01*
G01X559820Y132290D02*
X559360D01*
G01X559340Y132490D02*
X559800D01*
G01X559790Y132680D02*
X559320D01*
G01X559300Y132880D02*
X559770D01*
G01X559760Y133090D02*
X559290D01*
G01X559270Y133290D02*
X559740D01*
G01X559260Y133370D02*
X559170Y133460D01*
G01X558840Y135320D02*
X558720D01*
G01X559000Y135330D02*
X558840Y135320D01*
G01X559090Y135490D02*
X559560D01*
G01X559550Y135590D02*
X559080D01*
G01Y135680D02*
X559540D01*
G01Y135790D02*
X559070D01*
G01X559060Y135880D02*
X559530D01*
G01X559520Y135990D02*
X559050D01*
G01X558500Y136130D02*
X558270Y136250D01*
G01X558520Y136130D02*
X558500D01*
G01X558640Y136110D02*
X558520Y136130D01*
G01X558650Y136110D02*
X558640D01*
G01X558710Y136100D02*
X558650Y136110D01*
G01X558730Y136100D02*
X558710D01*
G01X557940Y136090D02*
X557310D01*
G01X557410Y135990D02*
X558040D01*
G01X558140Y135880D02*
X557500D01*
G01X557600Y135790D02*
X558230D01*
G01X558330Y135680D02*
X557690D01*
G01X557790Y135590D02*
X558420D01*
G01X558520Y135490D02*
X557890D01*
G01X558040Y133460D02*
X559170D01*
G01X558000Y133480D02*
X558040Y133460D01*
G01X558000Y133490D02*
Y133480D01*
G01Y135310D02*
Y133490D01*
G01Y135320D02*
Y135310D01*
G01X557970Y135400D02*
X558000Y135320D01*
G01X558520Y134740D02*
X558630Y134720D01*
G01X558460Y134640D02*
X558520Y134740D01*
G01X558460Y134040D02*
Y134640D01*
G01X558560Y133940D02*
X558460Y134040D01*
G01X559110Y133940D02*
X558560D01*
G01X558490Y134680D02*
X558000D01*
G01Y134590D02*
X558460D01*
G01Y134490D02*
X558000D01*
G01Y134380D02*
X558460D01*
G01Y134290D02*
X558000D01*
G01Y134180D02*
X558460D01*
G01Y134090D02*
X558000D01*
G01Y133990D02*
X558510D01*
G01X558000Y133790D02*
X560170D01*
G01X560360Y133590D02*
X558000D01*
G01Y134880D02*
X559780D01*
G01Y135090D02*
X558000D01*
G01Y135290D02*
X559780D01*
G01X558720Y135320D02*
X558650Y135350D01*
G01X558620Y135380D02*
X557980D01*
G01X558620Y125090D02*
X560170D01*
G01X559730Y124880D02*
X558430D01*
G01X558250Y124680D02*
X559520D01*
G01X559470Y124490D02*
X558060D01*
G01X557870Y124290D02*
X558560D01*
G01X558700Y123940D02*
Y123920D01*
G01X558660Y124210D02*
X558700Y123940D01*
G01X558600Y124290D02*
X558660Y124210D01*
G01X558680Y124090D02*
X559460D01*
G01X558600Y124290D02*
X558490Y124270D01*
G01X559410Y124290D02*
X558600D01*
G01X558410Y124180D02*
X557780D01*
G01X557690Y124090D02*
X558320D01*
G01X558230Y123990D02*
X557590D01*
G01X557540Y123880D02*
X557500D01*
G01X557490D02*
X558130D01*
G01X558040Y123790D02*
X557405D01*
G01X557410D02*
X557460D01*
G01X557305Y123680D02*
X557950D01*
G01X557860Y123590D02*
X557220D01*
G01X557130Y123490D02*
X557765D01*
G01X557665Y123380D02*
X557030D01*
G01X556940Y123290D02*
X557580D01*
G01X557475Y123180D02*
X556850D01*
G01X556750Y123090D02*
X557390D01*
G01X557300Y122990D02*
X556660D01*
G01X556570Y122880D02*
X557210D01*
G01X572300Y121220D02*
X566880Y126830D01*
G01X571960Y120900D02*
X571980Y120890D01*
G01X566840Y126200D02*
X571960Y120900D01*
G01X571880Y120990D02*
X572110D01*
G01X572230Y121090D02*
X571780D01*
G01X571680Y121180D02*
X572330D01*
G01X572240Y121290D02*
X571580D01*
G01X571490Y121380D02*
X572140D01*
G01X572050Y121490D02*
X571390D01*
G01X571300Y121590D02*
X571950D01*
G01X571860Y121680D02*
X571200D01*
G01X571100Y121790D02*
X571760D01*
G01X571660Y121880D02*
X571010D01*
G01X570910Y121990D02*
X571560D01*
G01X571470Y122090D02*
X570810D01*
G01X570720Y122180D02*
X571370D01*
G01X571270Y122290D02*
X570620D01*
G01X570520Y122380D02*
X571180D01*
G01X571080Y122490D02*
X570430D01*
G01X572530Y139380D02*
X571920D01*
G01X571830Y139290D02*
X572440D01*
G01X572350Y139180D02*
X571740D01*
G01X571640Y139090D02*
X572250D01*
G01X572160Y138990D02*
X571550D01*
G01X571460Y138880D02*
X572070D01*
G01X571980Y138790D02*
X571360D01*
G01X571270Y138680D02*
X571880D01*
G01X571790Y138590D02*
X571180D01*
G01X571080Y138490D02*
X571700D01*
G01X571600Y138380D02*
X570990D01*
G01X570900Y138290D02*
X571510D01*
G01X571420Y138180D02*
X570800D01*
G01X570710Y138090D02*
X571320D01*
G01X571230Y137990D02*
X570620D01*
G01X570520Y137880D02*
X571140D01*
G01X571050Y137790D02*
X570430D01*
G01X570340Y137680D02*
X570950D01*
G01X570860Y137590D02*
X570250D01*
G01X570150Y137490D02*
X570770D01*
G01X570670Y137380D02*
X570060D01*
G01X569970Y137290D02*
X570580D01*
G01X570490Y137180D02*
X569880D01*
G01X569780Y137090D02*
X570390D01*
G01X570300Y136990D02*
X569690D01*
G01X569600Y136880D02*
X570210D01*
G01X570120Y136790D02*
X569500D01*
G01X569410Y136680D02*
X570020D01*
G01X569930Y136590D02*
X569320D01*
G01X569220Y136490D02*
X569840D01*
G01X569750Y136380D02*
X569130D01*
G01X569040Y136290D02*
X569650D01*
G01X569560Y136180D02*
X568940D01*
G01X568230Y136780D02*
X567720D01*
G01X568270Y136740D02*
X568230Y136780D01*
G01X568270Y136280D02*
Y136740D01*
G01X568230Y136240D02*
X568270Y136280D01*
G01Y136680D02*
X558020D01*
G01X558090Y136490D02*
X568270D01*
G01Y136290D02*
X558250D01*
G01X565620Y137590D02*
X567050D01*
G01X567630Y136850D02*
X567720Y136780D01*
G01X567610Y136900D02*
X567630Y136850D01*
G01X567610Y136910D02*
Y136900D01*
G01X567490Y137160D02*
X567610Y136910D01*
G01X567470Y137170D02*
X567490Y137160D01*
G01X567040Y137590D02*
X567470Y137170D01*
G01X567710Y136790D02*
X566980D01*
G01X566870Y137120D02*
X566760Y137190D01*
G01X567040Y136950D02*
X566870Y137120D01*
G01X567060Y136840D02*
X567040Y136950D01*
G01X566970Y136780D02*
X567060Y136840D01*
G01X566900Y137090D02*
X567520D01*
G01X567570Y136990D02*
X567000D01*
G01X567050Y136880D02*
X567620D01*
G01X567360Y137290D02*
X565680D01*
G01Y137490D02*
X567150D01*
G01X567630Y136240D02*
X568230D01*
G01X567570Y136180D02*
X567010D01*
G01X566650Y137200D02*
X566760Y137190D01*
G01X566600Y137110D02*
X566650Y137200D01*
G01X566600Y136880D02*
Y137110D01*
G01X566700Y136780D02*
X566600Y136880D01*
G01X566970Y136780D02*
X566700D01*
G01X566770Y137180D02*
X567460D01*
G01X566590Y138170D02*
X566560Y138190D01*
G01X566600Y138140D02*
X566590Y138170D01*
G01X566600Y137940D02*
Y138140D01*
G01X566610Y137900D02*
X566600Y137940D01*
G01X566630Y137850D02*
X566610Y137900D01*
G01X566680Y137790D02*
X566630Y137850D01*
G01X566770Y137750D02*
X566680Y137790D01*
G01X567040Y137590D02*
X566770Y137750D01*
G01X566560Y138180D02*
X565730D01*
G01X566600Y137990D02*
X563710D01*
G01X563720Y137790D02*
X566700D01*
G01X566650Y137180D02*
X565680D01*
G01Y136990D02*
X566600D01*
G01X566690Y136790D02*
X565580D01*
G01X565680Y136880D02*
X566600D01*
G01X565580Y136780D02*
X565680Y136880D01*
G01X566600Y137090D02*
X565680D01*
G01X564350Y137790D02*
X564240Y137680D01*
G01X564620Y137760D02*
X564350Y137790D01*
G01X564900Y137730D02*
X564620Y137760D01*
G01X565020Y137720D02*
X564900Y137730D01*
G01X565120Y137700D02*
X565020Y137720D01*
G01X565370Y137660D02*
X565120Y137700D01*
G01X565380Y137660D02*
X565370D01*
G01X565470Y137640D02*
X565380Y137660D01*
G01X565480Y137640D02*
X565470D01*
G01X565600Y137620D02*
X565480Y137640D01*
G01X565680Y137520D02*
X565600Y137620D01*
G01X565680Y136880D02*
Y137520D01*
G01X565740Y138190D02*
X566560D01*
G01X565720Y138180D02*
X565740Y138190D01*
G01X565690Y138170D02*
X565720Y138180D01*
G01X565660Y138150D02*
X565690Y138170D01*
G01X565580Y138130D02*
X565660Y138150D01*
G01X565560Y138140D02*
X565580Y138130D01*
G01X565320Y138180D02*
X565560Y138140D01*
G01X564820Y138250D02*
X565320Y138180D01*
G01X564700Y138260D02*
X564820Y138250D01*
G01X564640Y138260D02*
X564700D01*
G01X564480Y138280D02*
X564640Y138260D01*
G01X564340Y138290D02*
X564480Y138280D01*
G01X566880Y137680D02*
X565230D01*
G01X565680Y137380D02*
X567250D01*
G01X565580Y136780D02*
X559740D01*
G01X561670Y138290D02*
X564360D01*
G01X564340D02*
X564240Y138390D01*
G01Y137340D02*
Y137680D01*
G01X564200Y137290D02*
X564240Y137340D01*
G01X564250Y137680D02*
X561620D01*
G01X561750Y137290D02*
X564200D01*
G01X561700Y137340D02*
X561750Y137290D01*
G01X561700Y137620D02*
Y137340D01*
G01X564240Y137380D02*
X561700D01*
G01Y137490D02*
X564240D01*
G01Y137590D02*
X561700D01*
G01X562150Y137900D02*
Y137860D01*
G01X562250Y138000D02*
X562150Y137900D01*
G01X563690Y138000D02*
X562250D01*
G01X563790Y137900D02*
X563690Y138000D01*
G01X563790Y137860D02*
Y137900D01*
G01X563690Y137750D02*
X563790Y137860D01*
G01X562250Y137750D02*
X563690D01*
G01X562150Y137860D02*
X562250Y137750D01*
G01X562150Y137880D02*
X560180D01*
G01X560470Y137990D02*
X562240D01*
G01X564240Y138420D02*
Y138390D01*
G01X564200Y138460D02*
X564240Y138420D01*
G01X561750Y138460D02*
X564200D01*
G01X561700Y138420D02*
X561750Y138460D01*
G01X561700Y138320D02*
Y138420D01*
G01X564250Y138380D02*
X561700D01*
G01X563790Y137880D02*
X566620D01*
G01X566600Y138090D02*
X560840D01*
G01X561620Y138220D02*
X561700Y138320D01*
G01X561570Y138220D02*
X561620D01*
G01X561010Y138130D02*
X561570Y138220D01*
G01X560830Y138090D02*
X561010Y138130D01*
G01X561390Y138180D02*
X565260D01*
G01X561190Y137650D02*
X560780Y137560D01*
G01X561480Y137700D02*
X561190Y137650D01*
G01X561510Y137700D02*
X561480D01*
G01X561590Y137720D02*
X561510Y137700D01*
G01X561700Y137620D02*
X561590Y137720D01*
G01X561400Y137680D02*
X559810D01*
G01X560500Y137480D02*
X560780Y137560D01*
G01X560490Y137470D02*
X560500Y137480D01*
G01X560380Y137440D02*
X560490Y137470D01*
G01X560380Y137430D02*
Y137440D01*
G01X560270Y137390D02*
X560380Y137430D01*
G01X560260Y137380D02*
X560270Y137390D01*
G01X559400Y137380D02*
X560260D01*
G01X560540Y137490D02*
X559510D01*
G01X560710Y138050D02*
X560830Y138090D01*
G01X560600Y138030D02*
X560710Y138050D01*
G01X560360Y137950D02*
X560600Y138030D01*
G01X560250Y137910D02*
X560360Y137950D01*
G01X560190Y137890D02*
X560250Y137910D01*
G01X560900Y137590D02*
X559650D01*
G01X559970Y137790D02*
X562220D01*
G01X559650Y136830D02*
X559740Y136780D01*
G01X559660Y136930D02*
X559650Y136830D01*
G01X559730Y137040D02*
X559660Y136930D01*
G01X559750Y137060D02*
X559730Y137040D01*
G01X560050Y137280D02*
X559750Y137060D01*
G01X560060Y137290D02*
X560050Y137280D01*
G01X560070Y137290D02*
X560060D01*
G01X560260Y137380D02*
X560070Y137290D01*
G01X559730Y136790D02*
X558010D01*
G01X558030Y136990D02*
X559690D01*
G01X559920Y137180D02*
X558110D01*
G01X560040Y137830D02*
X560190Y137890D01*
G01X560030Y137820D02*
X560040Y137830D01*
G01X558780Y137540D02*
X558720Y137550D01*
G01X558790Y137540D02*
X558780D01*
G01X558900Y137510D02*
X558790Y137540D01*
G01X558910Y137510D02*
X558900D01*
G01X559040Y137460D02*
X558910Y137510D01*
G01X559040Y137450D02*
Y137460D01*
G01X559100Y137420D02*
X559040Y137450D01*
G01X559120Y137400D02*
X559100Y137420D01*
G01X559180Y137350D02*
X559120Y137400D01*
G01X559200Y137330D02*
X559180Y137350D01*
G01X559340Y137330D02*
X559200D01*
G01X559520Y137500D02*
X559340Y137330D01*
G01X559530Y137510D02*
X559520Y137500D01*
G01X560030Y137820D02*
X559530Y137510D01*
G01X558970Y137490D02*
X558450D01*
G01X558400Y136180D02*
X559560D01*
G01X559610Y136240D02*
X566960D01*
G01X558650Y137550D02*
X558720D01*
G01X558640Y137540D02*
X558650Y137550D01*
G01X558380Y137470D02*
X558640Y137540D01*
G01X558370Y137460D02*
X558380Y137470D01*
G01X558170Y137290D02*
X558370Y137460D01*
G01X558160Y137280D02*
X558170Y137290D01*
G01X558040Y137050D02*
X558160Y137280D01*
G01X558030Y137030D02*
X558040Y137050D01*
G01X558010Y136750D02*
X558030Y137030D01*
G01X558010Y136740D02*
Y136750D01*
G01X558090Y136480D02*
X558010Y136740D01*
G01X558100Y136470D02*
X558090Y136480D01*
G01X558260Y136270D02*
X558100Y136470D01*
G01X558270Y136250D02*
X558260Y136270D01*
G01X559140Y137380D02*
X558280D01*
G01X558170Y137290D02*
X560060D01*
G01X559780Y137090D02*
X558060D01*
G01X558020Y136880D02*
X559650D01*
G01X558160Y136380D02*
X568270D01*
G01Y136590D02*
X558060D01*
G01X557750Y136290D02*
X557120D01*
G01X557020Y136380D02*
X557650D01*
G01X557560Y136490D02*
X556920D01*
G01X556830Y136590D02*
X557460D01*
G01X557360Y136680D02*
X556730D01*
G01X556640Y136790D02*
X557260D01*
G01X557210Y136180D02*
X557840D01*
G01X572330Y121190D02*
X572300Y121220D01*
G01X572320Y121170D02*
X572330Y121190D01*
G01X572010Y120900D02*
X572320Y121170D01*
G01X571980Y120890D02*
X572010Y120900D01*
G01X572630Y140100D02*
X572600Y140120D01*
G01X572630Y139560D02*
Y140100D01*
G01X572620Y139540D02*
X572630Y139560D01*
G01X572570Y139430D02*
X572620Y139540D01*
G01X572560Y139420D02*
X572570Y139430D01*
G01X572630Y140090D02*
X572570D01*
G01X572630Y139990D02*
X572480D01*
G01X572390Y139880D02*
X572630D01*
G01Y139790D02*
X572290D01*
G01X572200Y139680D02*
X572630D01*
G01Y139590D02*
X572110D01*
G01X572010Y139490D02*
X572600D01*
G54D16*
G01X70851Y-113865D02*
Y-96365D01*
G01X80021D02*
Y-113865D01*
G01Y-105115D02*
X70851D01*
G01X92936Y-113865D02*
X91626Y-113573D01*
X90316Y-112407D01*
X89442Y-110365D01*
X89006Y-108032D01*
X89442Y-105698D01*
X90316Y-103657D01*
X91626Y-102490D01*
X92936Y-102199D01*
X94246Y-102490D01*
X95556Y-103657D01*
X96429Y-105698D01*
X96648Y-108032D01*
X96429Y-110365D01*
X95556Y-112407D01*
X94246Y-113573D01*
X92936Y-113865D01*
G01X106724D02*
Y-102199D01*
G01Y-105115D02*
X107598Y-103657D01*
X108908Y-102490D01*
X110654Y-102199D01*
X112182Y-102490D01*
X113493Y-103657D01*
X114148Y-105698D01*
Y-113865D01*
G01X124661Y-105990D02*
X131648D01*
X130993Y-103948D01*
X129901Y-102782D01*
X128373Y-102199D01*
X126844Y-102490D01*
X125534Y-103365D01*
X124661Y-105407D01*
X124224Y-107157D01*
Y-108907D01*
X124661Y-110657D01*
X125753Y-112407D01*
X127063Y-113573D01*
X128591Y-113865D01*
X130119Y-113282D01*
X131648Y-111532D01*
G01X140851Y-119115D02*
X142161Y-119698D01*
X143908Y-119115D01*
X144999Y-117949D01*
X145873Y-116490D01*
X147182Y-111824D01*
X150021Y-102199D01*
G01X143034D02*
X147182Y-111824D01*
G01X182182Y-104532D02*
X183056Y-103657D01*
X183711Y-102199D01*
X184148Y-100156D01*
X183711Y-98407D01*
X182838Y-97240D01*
X181309Y-96365D01*
X175414D01*
Y-113865D01*
X182619D01*
X184148Y-112699D01*
X185021Y-110948D01*
X185458Y-108907D01*
X185021Y-106865D01*
X183711Y-105115D01*
X182182Y-104532D01*
X175414D01*
G01X201866Y-113865D02*
Y-102199D01*
G01Y-104240D02*
X200993Y-103074D01*
X199682Y-102490D01*
X198154Y-102199D01*
X196626Y-102782D01*
X195316Y-103948D01*
X194442Y-105698D01*
X194006Y-108032D01*
X194442Y-110365D01*
X195316Y-112115D01*
X196626Y-113282D01*
X198154Y-113865D01*
X199682Y-113573D01*
X200993Y-112699D01*
X201866Y-111532D01*
G01X219366Y-96365D02*
Y-113865D01*
G01Y-111241D02*
X218493Y-112699D01*
X217182Y-113573D01*
X215654Y-113865D01*
X213908Y-113282D01*
X212598Y-111824D01*
X211724Y-110074D01*
X211506Y-108032D01*
X211724Y-105990D01*
X212598Y-104240D01*
X213908Y-102782D01*
X215654Y-102199D01*
X217182Y-102490D01*
X218274Y-103074D01*
X219366Y-104240D01*
G01X229879Y-118240D02*
X231408Y-119407D01*
X233154Y-119698D01*
X234682Y-119407D01*
X235993Y-117949D01*
X236866Y-115907D01*
Y-102199D01*
G01Y-104532D02*
X235993Y-103365D01*
X234682Y-102490D01*
X233154Y-102199D01*
X231408Y-102782D01*
X230316Y-103948D01*
X229442Y-105990D01*
X229006Y-108032D01*
X229224Y-109782D01*
X230098Y-111824D01*
X231408Y-113282D01*
X233154Y-113865D01*
X234464Y-113573D01*
X235993Y-112407D01*
X236866Y-111241D01*
G01X247161Y-105990D02*
X254148D01*
X253493Y-103948D01*
X252401Y-102782D01*
X250873Y-102199D01*
X249344Y-102490D01*
X248034Y-103365D01*
X247161Y-105407D01*
X246724Y-107157D01*
Y-108907D01*
X247161Y-110657D01*
X248253Y-112407D01*
X249563Y-113573D01*
X251091Y-113865D01*
X252619Y-113282D01*
X254148Y-111532D01*
G01X264879Y-113865D02*
Y-102199D01*
G01Y-104532D02*
X265971Y-103365D01*
X267063Y-102490D01*
X268591Y-102199D01*
X269682Y-102490D01*
X270993Y-103365D01*
G01X298569Y-113865D02*
Y-96365D01*
X303809D01*
X305556Y-97240D01*
X306866Y-99282D01*
X307303Y-101615D01*
X306866Y-103948D01*
X305774Y-105698D01*
X303809Y-106574D01*
X298569D01*
G01X324366Y-113865D02*
Y-102199D01*
G01Y-104240D02*
X323493Y-103074D01*
X322182Y-102490D01*
X320654Y-102199D01*
X319126Y-102782D01*
X317816Y-103948D01*
X316942Y-105698D01*
X316506Y-108032D01*
X316942Y-110365D01*
X317816Y-112115D01*
X319126Y-113282D01*
X320654Y-113865D01*
X322182Y-113573D01*
X323493Y-112699D01*
X324366Y-111532D01*
G01X334224Y-113865D02*
Y-102199D01*
G01Y-105115D02*
X335098Y-103657D01*
X336408Y-102490D01*
X338154Y-102199D01*
X339682Y-102490D01*
X340993Y-103657D01*
X341648Y-105698D01*
Y-113865D01*
G01X355436Y-96365D02*
Y-113865D01*
G01X352379Y-102199D02*
X358493D01*
G01X369224Y-113865D02*
Y-96365D01*
G01Y-104823D02*
X370316Y-103365D01*
X371408Y-102490D01*
X373154Y-102199D01*
X374464Y-102490D01*
X375993Y-103657D01*
X376648Y-105407D01*
Y-113865D01*
G01X387161Y-105990D02*
X394148D01*
X393493Y-103948D01*
X392401Y-102782D01*
X390873Y-102199D01*
X389344Y-102490D01*
X388034Y-103365D01*
X387161Y-105407D01*
X386724Y-107157D01*
Y-108907D01*
X387161Y-110657D01*
X388253Y-112407D01*
X389563Y-113573D01*
X391091Y-113865D01*
X392619Y-113282D01*
X394148Y-111532D01*
G01X404879Y-113865D02*
Y-102199D01*
G01Y-104532D02*
X405971Y-103365D01*
X407063Y-102490D01*
X408591Y-102199D01*
X409682Y-102490D01*
X410993Y-103365D01*
G01X437259Y-113865D02*
Y-96365D01*
X442936Y-110948D01*
X448613Y-96365D01*
Y-113865D01*
G01X462182Y-104532D02*
X463056Y-103657D01*
X463711Y-102199D01*
X464148Y-100156D01*
X463711Y-98407D01*
X462838Y-97240D01*
X461309Y-96365D01*
X455414D01*
Y-113865D01*
X462619D01*
X464148Y-112699D01*
X465021Y-110948D01*
X465458Y-108907D01*
X465021Y-106865D01*
X463711Y-105115D01*
X462182Y-104532D01*
X455414D01*
G01X227259Y-68865D02*
Y-51365D01*
X232936Y-65948D01*
X238613Y-51365D01*
Y-68865D01*
G01X250436D02*
X249126Y-68573D01*
X247816Y-67407D01*
X246942Y-65365D01*
X246506Y-63032D01*
X246942Y-60698D01*
X247816Y-58657D01*
X249126Y-57490D01*
X250436Y-57199D01*
X251746Y-57490D01*
X253056Y-58657D01*
X253929Y-60698D01*
X254148Y-63032D01*
X253929Y-65365D01*
X253056Y-67407D01*
X251746Y-68573D01*
X250436Y-68865D01*
G01X271866Y-51365D02*
Y-68865D01*
G01Y-66241D02*
X270993Y-67699D01*
X269682Y-68573D01*
X268154Y-68865D01*
X266408Y-68282D01*
X265098Y-66824D01*
X264224Y-65074D01*
X264006Y-63032D01*
X264224Y-60990D01*
X265098Y-59240D01*
X266408Y-57782D01*
X268154Y-57199D01*
X269682Y-57490D01*
X270774Y-58074D01*
X271866Y-59240D01*
G01X282161Y-60990D02*
X289148D01*
X288493Y-58948D01*
X287401Y-57782D01*
X285873Y-57199D01*
X284344Y-57490D01*
X283034Y-58365D01*
X282161Y-60407D01*
X281724Y-62157D01*
Y-63907D01*
X282161Y-65657D01*
X283253Y-67407D01*
X284563Y-68573D01*
X286091Y-68865D01*
X287619Y-68282D01*
X289148Y-66532D01*
G01X302936Y-68865D02*
Y-51365D01*
G01X542319Y-68865D02*
Y-51365D01*
X547559D01*
X549306Y-52240D01*
X550616Y-54282D01*
X551053Y-56615D01*
X550616Y-58948D01*
X549524Y-60698D01*
X547559Y-61574D01*
X542319D01*
G01X568989Y-52824D02*
X567679Y-51948D01*
X566151Y-51365D01*
X564404D01*
X562439Y-52240D01*
X560911Y-53698D01*
X559819Y-55449D01*
X558946Y-58365D01*
X558727Y-60990D01*
X559164Y-63615D01*
X559819Y-65365D01*
X561129Y-67115D01*
X562658Y-68282D01*
X564186Y-68865D01*
X565714D01*
X567243Y-68282D01*
X568553Y-67407D01*
X569645Y-66241D01*
G01X583432Y-59532D02*
X584306Y-58657D01*
X584961Y-57199D01*
X585398Y-55156D01*
X584961Y-53407D01*
X584088Y-52240D01*
X582559Y-51365D01*
X576664D01*
Y-68865D01*
X583869D01*
X585398Y-67699D01*
X586271Y-65948D01*
X586708Y-63907D01*
X586271Y-61865D01*
X584961Y-60115D01*
X583432Y-59532D01*
X576664D01*
G01X592636Y-74698D02*
X605736D01*
G01X611664Y-68865D02*
Y-51365D01*
X621708Y-68865D01*
Y-51365D01*
G01X634186Y-68865D02*
X632439Y-68573D01*
X630911Y-67407D01*
X629601Y-65657D01*
X628727Y-63615D01*
X628291Y-61282D01*
Y-58948D01*
X628727Y-56615D01*
X629601Y-54573D01*
X630911Y-52824D01*
X632439Y-51657D01*
X634186Y-51365D01*
X635932Y-51657D01*
X637461Y-52824D01*
X638771Y-54573D01*
X639645Y-56615D01*
X640081Y-58948D01*
Y-61282D01*
X639645Y-63615D01*
X638771Y-65657D01*
X637461Y-67407D01*
X635932Y-68573D01*
X634186Y-68865D01*
G01X555436Y-113865D02*
Y-96365D01*
X552816Y-99865D01*
G01Y-113865D02*
X558056D01*
G01X568133Y-110365D02*
X569442Y-112407D01*
X571189Y-113573D01*
X573154Y-113865D01*
X574901Y-113573D01*
X576648Y-112115D01*
X577739Y-110365D01*
X577958Y-108615D01*
X577521Y-106574D01*
X575993Y-105115D01*
X574464Y-104532D01*
X572499D01*
G01X574464D02*
X575774Y-103657D01*
X576866Y-102199D01*
X577303Y-100449D01*
X576866Y-98698D01*
X575774Y-97240D01*
X573809Y-96365D01*
X571844Y-96657D01*
X569879Y-97824D01*
G01X590436Y-113865D02*
Y-96365D01*
X587816Y-99865D01*
G01Y-113865D02*
X593056D01*
G01X603133Y-110365D02*
X604442Y-112407D01*
X606189Y-113573D01*
X608154Y-113865D01*
X609901Y-113573D01*
X611648Y-112115D01*
X612739Y-110365D01*
X612958Y-108615D01*
X612521Y-106574D01*
X610993Y-105115D01*
X609464Y-104532D01*
X607499D01*
G01X609464D02*
X610774Y-103657D01*
X611866Y-102199D01*
X612303Y-100449D01*
X611866Y-98698D01*
X610774Y-97240D01*
X608809Y-96365D01*
X606844Y-96657D01*
X604879Y-97824D01*
G01X625436Y-96365D02*
X623689Y-96948D01*
X622379Y-98407D01*
X621506Y-100156D01*
X620851Y-102490D01*
X620633Y-105115D01*
X620851Y-107740D01*
X621506Y-110074D01*
X622379Y-111824D01*
X623689Y-113282D01*
X625436Y-113865D01*
X627182Y-113282D01*
X628493Y-111824D01*
X629366Y-110074D01*
X630021Y-107740D01*
X630239Y-105115D01*
X630021Y-102490D01*
X629366Y-100156D01*
X628493Y-98407D01*
X627182Y-96948D01*
X625436Y-96365D01*
G01X685027Y-51365D02*
X690486Y-68865D01*
X695945Y-51365D01*
G01X712353Y-68865D02*
X703619D01*
Y-51365D01*
X712353D01*
G01X708859Y-59823D02*
X703619D01*
G01X721119Y-68865D02*
Y-51365D01*
X726578D01*
X728324Y-52240D01*
X729416Y-53407D01*
X729853Y-55740D01*
X729416Y-58074D01*
X728106Y-59532D01*
X726578Y-60407D01*
X721119D01*
G01X726578D02*
X729853Y-68865D01*
G01X742986Y-69448D02*
X742549Y-69157D01*
Y-68573D01*
X742986Y-68282D01*
X743423Y-68573D01*
Y-69157D01*
X742986Y-69448D01*
G01X707986Y-113865D02*
Y-96365D01*
X705366Y-99865D01*
G01Y-113865D02*
X710606D01*
G01X727232Y-104532D02*
X728106Y-103657D01*
X728761Y-102199D01*
X729198Y-100156D01*
X728761Y-98407D01*
X727888Y-97240D01*
X726359Y-96365D01*
X720464D01*
Y-113865D01*
X727669D01*
X729198Y-112699D01*
X730071Y-110948D01*
X730508Y-108907D01*
X730071Y-106865D01*
X728761Y-105115D01*
X727232Y-104532D01*
X720464D01*
G01X891190D02*
X890316Y-103657D01*
X889661Y-102199D01*
X889224Y-100156D01*
X889661Y-98407D01*
X890534Y-97240D01*
X892063Y-96365D01*
X897958D01*
Y-113865D01*
X890753D01*
X889224Y-112699D01*
X888351Y-110948D01*
X887914Y-108907D01*
X888351Y-106865D01*
X889661Y-105115D01*
X891190Y-104532D01*
X897958D01*
G01X880021Y-111532D02*
X878274Y-112990D01*
X876309Y-113865D01*
X874563D01*
X872816Y-112990D01*
X871506Y-111532D01*
X870851Y-109490D01*
X871288Y-107449D01*
X872379Y-105698D01*
X874344Y-104532D01*
X876964Y-103948D01*
X878493Y-102782D01*
X879148Y-100740D01*
X878711Y-98698D01*
X877619Y-97240D01*
X876091Y-96365D01*
X874563D01*
X873034Y-96948D01*
X871724Y-98407D01*
G01X860556Y-96365D02*
X855316D01*
G01X857936D02*
Y-113865D01*
G01X860556D02*
X855316D01*
G01X844803Y-96365D02*
Y-113865D01*
X836069D01*
G01X827739D02*
Y-96365D01*
G01X819443D02*
X827739Y-107157D01*
G01X818133Y-113865D02*
X824028Y-102199D01*
G01X818569Y-51365D02*
Y-68865D01*
X827303D01*
G01X844366D02*
Y-57199D01*
G01Y-59240D02*
X843493Y-58074D01*
X842182Y-57490D01*
X840654Y-57199D01*
X839126Y-57782D01*
X837816Y-58948D01*
X836942Y-60698D01*
X836506Y-63032D01*
X836942Y-65365D01*
X837816Y-67115D01*
X839126Y-68282D01*
X840654Y-68865D01*
X842182Y-68573D01*
X843493Y-67699D01*
X844366Y-66532D01*
G01X853351Y-74115D02*
X854661Y-74698D01*
X856408Y-74115D01*
X857499Y-72949D01*
X858373Y-71490D01*
X859682Y-66824D01*
X862521Y-57199D01*
G01X855534D02*
X859682Y-66824D01*
G01X872161Y-60990D02*
X879148D01*
X878493Y-58948D01*
X877401Y-57782D01*
X875873Y-57199D01*
X874344Y-57490D01*
X873034Y-58365D01*
X872161Y-60407D01*
X871724Y-62157D01*
Y-63907D01*
X872161Y-65657D01*
X873253Y-67407D01*
X874563Y-68573D01*
X876091Y-68865D01*
X877619Y-68282D01*
X879148Y-66532D01*
G01X889879Y-68865D02*
Y-57199D01*
G01Y-59532D02*
X890971Y-58365D01*
X892063Y-57490D01*
X893591Y-57199D01*
X894682Y-57490D01*
X895993Y-58365D01*
G01X943619Y-110365D02*
X944711Y-112115D01*
X946021Y-113282D01*
X947549Y-113865D01*
X949296Y-113282D01*
X950606Y-112115D01*
X951916Y-110365D01*
X952353Y-108032D01*
Y-96365D01*
G01X965486Y-113865D02*
X963739Y-113573D01*
X962211Y-112407D01*
X960901Y-110657D01*
X960027Y-108615D01*
X959591Y-106282D01*
Y-103948D01*
X960027Y-101615D01*
X960901Y-99573D01*
X962211Y-97824D01*
X963739Y-96657D01*
X965486Y-96365D01*
X967232Y-96657D01*
X968761Y-97824D01*
X970071Y-99573D01*
X970945Y-101615D01*
X971381Y-103948D01*
Y-106282D01*
X970945Y-108615D01*
X970071Y-110657D01*
X968761Y-112407D01*
X967232Y-113573D01*
X965486Y-113865D01*
G01X978401Y-111532D02*
X980148Y-112990D01*
X982113Y-113865D01*
X983859D01*
X985606Y-112990D01*
X986916Y-111532D01*
X987571Y-109490D01*
X987134Y-107449D01*
X986043Y-105698D01*
X984078Y-104532D01*
X981458Y-103948D01*
X979929Y-102782D01*
X979274Y-100740D01*
X979711Y-98698D01*
X980803Y-97240D01*
X982331Y-96365D01*
X983859D01*
X985388Y-96948D01*
X986698Y-98407D01*
G01X1004853Y-113865D02*
X996119D01*
Y-96365D01*
X1004853D01*
G01X1001359Y-104823D02*
X996119D01*
G01X1013619Y-113865D02*
Y-96365D01*
X1018859D01*
X1020606Y-97240D01*
X1021916Y-99282D01*
X1022353Y-101615D01*
X1021916Y-103948D01*
X1020824Y-105698D01*
X1018859Y-106574D01*
X1013619D01*
G01X1030901Y-113865D02*
Y-96365D01*
G01X1040071D02*
Y-113865D01*
G01Y-105115D02*
X1030901D01*
G01X1066119Y-96365D02*
Y-113865D01*
X1074853D01*
G01X1082527D02*
X1087986Y-96365D01*
X1093445Y-113865D01*
G01X1091479Y-107740D02*
X1084492D01*
G01X1100683Y-96365D02*
Y-108907D01*
X1101556Y-111532D01*
X1103303Y-113282D01*
X1105486Y-113865D01*
X1107669Y-113282D01*
X1109416Y-111532D01*
X1110289Y-108907D01*
Y-96365D01*
G01X960683Y-68865D02*
Y-51365D01*
X965049D01*
X966796Y-52240D01*
X968106Y-53407D01*
X969198Y-55156D01*
X970071Y-57199D01*
X970289Y-60115D01*
X970071Y-63032D01*
X969198Y-65074D01*
X968106Y-66824D01*
X966796Y-67990D01*
X965049Y-68865D01*
X960683D01*
G01X979711Y-60990D02*
X986698D01*
X986043Y-58948D01*
X984951Y-57782D01*
X983423Y-57199D01*
X981894Y-57490D01*
X980584Y-58365D01*
X979711Y-60407D01*
X979274Y-62157D01*
Y-63907D01*
X979711Y-65657D01*
X980803Y-67407D01*
X982113Y-68573D01*
X983641Y-68865D01*
X985169Y-68282D01*
X986698Y-66532D01*
G01X997211Y-66824D02*
X998303Y-67990D01*
X999831Y-68865D01*
X1001141D01*
X1002451Y-68282D01*
X1003324Y-67407D01*
X1003761Y-66241D01*
X1003543Y-64490D01*
X1002669Y-63615D01*
X998739Y-61865D01*
X997866Y-59823D01*
X998303Y-58365D01*
X999176Y-57490D01*
X1000486Y-57199D01*
X1001796Y-57490D01*
X1003106Y-58365D01*
G01X1017986Y-57199D02*
Y-68865D01*
G01Y-52532D02*
X1017549Y-52240D01*
Y-51657D01*
X1017986Y-51365D01*
X1018423Y-51657D01*
Y-52240D01*
X1017986Y-52532D01*
G01X1032429Y-73240D02*
X1033958Y-74407D01*
X1035704Y-74698D01*
X1037232Y-74407D01*
X1038543Y-72949D01*
X1039416Y-70907D01*
Y-57199D01*
G01Y-59532D02*
X1038543Y-58365D01*
X1037232Y-57490D01*
X1035704Y-57199D01*
X1033958Y-57782D01*
X1032866Y-58948D01*
X1031992Y-60990D01*
X1031556Y-63032D01*
X1031774Y-64782D01*
X1032648Y-66824D01*
X1033958Y-68282D01*
X1035704Y-68865D01*
X1037014Y-68573D01*
X1038543Y-67407D01*
X1039416Y-66241D01*
G01X1049274Y-68865D02*
Y-57199D01*
G01Y-60115D02*
X1050148Y-58657D01*
X1051458Y-57490D01*
X1053204Y-57199D01*
X1054732Y-57490D01*
X1056043Y-58657D01*
X1056698Y-60698D01*
Y-68865D01*
G01X1067211Y-60990D02*
X1074198D01*
X1073543Y-58948D01*
X1072451Y-57782D01*
X1070923Y-57199D01*
X1069394Y-57490D01*
X1068084Y-58365D01*
X1067211Y-60407D01*
X1066774Y-62157D01*
Y-63907D01*
X1067211Y-65657D01*
X1068303Y-67407D01*
X1069613Y-68573D01*
X1071141Y-68865D01*
X1072669Y-68282D01*
X1074198Y-66532D01*
G01X1084929Y-68865D02*
Y-57199D01*
G01Y-59532D02*
X1086021Y-58365D01*
X1087113Y-57490D01*
X1088641Y-57199D01*
X1089732Y-57490D01*
X1091043Y-58365D01*
G01X1131686Y-113865D02*
Y-96365D01*
X1129066Y-99865D01*
G01Y-113865D02*
X1134306D01*
G01X1149186D02*
Y-96365D01*
X1146566Y-99865D01*
G01Y-113865D02*
X1151806D01*
G01X1162756Y-114448D02*
X1170616Y-96365D01*
G01X1184186Y-113865D02*
Y-96365D01*
X1181566Y-99865D01*
G01Y-113865D02*
X1186806D01*
G01X1196883Y-110365D02*
X1198192Y-112407D01*
X1199939Y-113573D01*
X1201904Y-113865D01*
X1203651Y-113573D01*
X1205398Y-112115D01*
X1206489Y-110365D01*
X1206708Y-108615D01*
X1206271Y-106574D01*
X1204743Y-105115D01*
X1203214Y-104532D01*
X1201249D01*
G01X1203214D02*
X1204524Y-103657D01*
X1205616Y-102199D01*
X1206053Y-100449D01*
X1205616Y-98698D01*
X1204524Y-97240D01*
X1202559Y-96365D01*
X1200594Y-96657D01*
X1198629Y-97824D01*
G01X1215256Y-114448D02*
X1223116Y-96365D01*
G01X1232538Y-99282D02*
X1233848Y-97532D01*
X1235376Y-96657D01*
X1237123Y-96365D01*
X1239306Y-96948D01*
X1240834Y-98407D01*
X1241271Y-100156D01*
X1241053Y-101907D01*
X1240179Y-103365D01*
X1235813Y-106282D01*
X1233848Y-108323D01*
X1232538Y-111241D01*
X1232101Y-113865D01*
X1241271D01*
G01X1254186Y-96365D02*
X1252439Y-96948D01*
X1251129Y-98407D01*
X1250256Y-100156D01*
X1249601Y-102490D01*
X1249383Y-105115D01*
X1249601Y-107740D01*
X1250256Y-110074D01*
X1251129Y-111824D01*
X1252439Y-113282D01*
X1254186Y-113865D01*
X1255932Y-113282D01*
X1257243Y-111824D01*
X1258116Y-110074D01*
X1258771Y-107740D01*
X1258989Y-105115D01*
X1258771Y-102490D01*
X1258116Y-100156D01*
X1257243Y-98407D01*
X1255932Y-96948D01*
X1254186Y-96365D01*
G01X1271686Y-113865D02*
Y-96365D01*
X1269066Y-99865D01*
G01Y-113865D02*
X1274306D01*
G01X1291806D02*
Y-96365D01*
X1283727Y-108907D01*
X1294645D01*
G01X1179383Y-68865D02*
Y-51365D01*
X1183749D01*
X1185496Y-52240D01*
X1186806Y-53407D01*
X1187898Y-55156D01*
X1188771Y-57199D01*
X1188989Y-60115D01*
X1188771Y-63032D01*
X1187898Y-65074D01*
X1186806Y-66824D01*
X1185496Y-67990D01*
X1183749Y-68865D01*
X1179383D01*
G01X1205616D02*
Y-57199D01*
G01Y-59240D02*
X1204743Y-58074D01*
X1203432Y-57490D01*
X1201904Y-57199D01*
X1200376Y-57782D01*
X1199066Y-58948D01*
X1198192Y-60698D01*
X1197756Y-63032D01*
X1198192Y-65365D01*
X1199066Y-67115D01*
X1200376Y-68282D01*
X1201904Y-68865D01*
X1203432Y-68573D01*
X1204743Y-67699D01*
X1205616Y-66532D01*
G01X1219186Y-51365D02*
Y-68865D01*
G01X1216129Y-57199D02*
X1222243D01*
G01X1233411Y-60990D02*
X1240398D01*
X1239743Y-58948D01*
X1238651Y-57782D01*
X1237123Y-57199D01*
X1235594Y-57490D01*
X1234284Y-58365D01*
X1233411Y-60407D01*
X1232974Y-62157D01*
Y-63907D01*
X1233411Y-65657D01*
X1234503Y-67407D01*
X1235813Y-68573D01*
X1237341Y-68865D01*
X1238869Y-68282D01*
X1240398Y-66532D01*
G01X15533Y148000D02*
Y150500D01*
X14533D01*
X14200Y150375D01*
X13950Y150083D01*
X13867Y149750D01*
X13950Y149417D01*
X14158Y149167D01*
X14533Y149042D01*
X15533D01*
G01X10683Y150292D02*
X10933Y150417D01*
X11225Y150500D01*
X11558D01*
X11933Y150375D01*
X12225Y150167D01*
X12433Y149917D01*
X12600Y149500D01*
X12642Y149125D01*
X12558Y148750D01*
X12433Y148500D01*
X12183Y148250D01*
X11892Y148083D01*
X11600Y148000D01*
X11308D01*
X11017Y148083D01*
X10767Y148208D01*
X10558Y148375D01*
G01X8500Y148000D02*
Y150500D01*
X9000Y150000D01*
G01Y148000D02*
X8000D01*
G01X5400D02*
X5108Y148042D01*
X4775Y148167D01*
X4567Y148375D01*
X4483Y148667D01*
X4567Y148958D01*
X4817Y149208D01*
X5192Y149333D01*
X5608D01*
X5858Y149417D01*
X6067Y149625D01*
X6150Y149917D01*
X6025Y150208D01*
X5733Y150417D01*
X5400Y150500D01*
X5067Y150417D01*
X4775Y150208D01*
X4650Y149917D01*
X4733Y149625D01*
X4942Y149417D01*
X5192Y149333D01*
X5608D01*
X5983Y149208D01*
X6233Y148958D01*
X6317Y148667D01*
X6233Y148375D01*
X6025Y148167D01*
X5692Y148042D01*
X5400Y148000D01*
G01X3092Y149042D02*
X2800Y149333D01*
X2550Y149500D01*
X2217Y149583D01*
X1925Y149500D01*
X1717Y149333D01*
X1550Y149083D01*
X1508Y148792D01*
X1550Y148542D01*
X1717Y148292D01*
X1967Y148083D01*
X2258Y148000D01*
X2592Y148083D01*
X2883Y148333D01*
X3050Y148708D01*
X3092Y149125D01*
X3008Y149667D01*
X2883Y149958D01*
X2675Y150250D01*
X2383Y150458D01*
X2092Y150500D01*
X1800Y150417D01*
X1592Y150208D01*
G01X16033Y155500D02*
Y158000D01*
X15033D01*
X14700Y157875D01*
X14450Y157583D01*
X14367Y157250D01*
X14450Y156917D01*
X14658Y156667D01*
X15033Y156542D01*
X16033D01*
G01X11183Y157792D02*
X11433Y157917D01*
X11725Y158000D01*
X12058D01*
X12433Y157875D01*
X12725Y157667D01*
X12933Y157417D01*
X13100Y157000D01*
X13142Y156625D01*
X13058Y156250D01*
X12933Y156000D01*
X12683Y155750D01*
X12392Y155583D01*
X12100Y155500D01*
X11808D01*
X11517Y155583D01*
X11267Y155708D01*
X11058Y155875D01*
G01X9000Y155500D02*
Y158000D01*
X9500Y157500D01*
G01Y155500D02*
X8500D01*
G01X5900D02*
X5608Y155542D01*
X5275Y155667D01*
X5067Y155875D01*
X4983Y156167D01*
X5067Y156458D01*
X5317Y156708D01*
X5692Y156833D01*
X6108D01*
X6358Y156917D01*
X6567Y157125D01*
X6650Y157417D01*
X6525Y157708D01*
X6233Y157917D01*
X5900Y158000D01*
X5567Y157917D01*
X5275Y157708D01*
X5150Y157417D01*
X5233Y157125D01*
X5442Y156917D01*
X5692Y156833D01*
X6108D01*
X6483Y156708D01*
X6733Y156458D01*
X6817Y156167D01*
X6733Y155875D01*
X6525Y155667D01*
X6192Y155542D01*
X5900Y155500D01*
G01X3592Y157583D02*
X3342Y157833D01*
X3050Y157958D01*
X2717Y158000D01*
X2300Y157917D01*
X2008Y157708D01*
X1925Y157458D01*
X1967Y157208D01*
X2133Y157000D01*
X2967Y156583D01*
X3342Y156292D01*
X3592Y155875D01*
X3675Y155500D01*
X1925D01*
G01X27483Y116500D02*
Y119000D01*
X26483D01*
X26150Y118875D01*
X25900Y118583D01*
X25817Y118250D01*
X25900Y117917D01*
X26108Y117667D01*
X26483Y117542D01*
X27483D01*
G01X22633Y118792D02*
X22883Y118917D01*
X23175Y119000D01*
X23508D01*
X23883Y118875D01*
X24175Y118667D01*
X24383Y118417D01*
X24550Y118000D01*
X24592Y117625D01*
X24508Y117250D01*
X24383Y117000D01*
X24133Y116750D01*
X23842Y116583D01*
X23550Y116500D01*
X23258D01*
X22967Y116583D01*
X22717Y116708D01*
X22508Y116875D01*
G01X20450Y116500D02*
X20158Y116542D01*
X19825Y116667D01*
X19617Y116875D01*
X19533Y117167D01*
X19617Y117458D01*
X19867Y117708D01*
X20242Y117833D01*
X20658D01*
X20908Y117917D01*
X21117Y118125D01*
X21200Y118417D01*
X21075Y118708D01*
X20783Y118917D01*
X20450Y119000D01*
X20117Y118917D01*
X19825Y118708D01*
X19700Y118417D01*
X19783Y118125D01*
X19992Y117917D01*
X20242Y117833D01*
X20658D01*
X21033Y117708D01*
X21283Y117458D01*
X21367Y117167D01*
X21283Y116875D01*
X21075Y116667D01*
X20742Y116542D01*
X20450Y116500D01*
G01X17350D02*
Y119000D01*
X17850Y118500D01*
G01Y116500D02*
X16850D01*
G01X18033Y130000D02*
Y132500D01*
X17033D01*
X16700Y132375D01*
X16450Y132083D01*
X16367Y131750D01*
X16450Y131417D01*
X16658Y131167D01*
X17033Y131042D01*
X18033D01*
G01X14933Y130000D02*
Y132500D01*
X13892D01*
X13558Y132375D01*
X13350Y132208D01*
X13267Y131875D01*
X13350Y131542D01*
X13600Y131333D01*
X13892Y131208D01*
X14933D01*
G01X13892D02*
X13267Y130000D01*
G01X11792Y132083D02*
X11542Y132333D01*
X11250Y132458D01*
X10917Y132500D01*
X10500Y132417D01*
X10208Y132208D01*
X10125Y131958D01*
X10167Y131708D01*
X10333Y131500D01*
X11167Y131083D01*
X11542Y130792D01*
X11792Y130375D01*
X11875Y130000D01*
X10125D01*
G01X7900Y132500D02*
X8233Y132417D01*
X8483Y132208D01*
X8650Y131958D01*
X8775Y131625D01*
X8817Y131250D01*
X8775Y130875D01*
X8650Y130542D01*
X8483Y130292D01*
X8233Y130083D01*
X7900Y130000D01*
X7567Y130083D01*
X7317Y130292D01*
X7150Y130542D01*
X7025Y130875D01*
X6983Y131250D01*
X7025Y131625D01*
X7150Y131958D01*
X7317Y132208D01*
X7567Y132417D01*
X7900Y132500D01*
G01X4883Y130000D02*
X4800Y130542D01*
X4675Y131000D01*
X4508Y131417D01*
X4300Y131875D01*
X3967Y132500D01*
X5633D01*
G01X21033Y122000D02*
Y124500D01*
X20033D01*
X19700Y124375D01*
X19450Y124083D01*
X19367Y123750D01*
X19450Y123417D01*
X19658Y123167D01*
X20033Y123042D01*
X21033D01*
G01X17933Y122000D02*
Y124500D01*
X16892D01*
X16558Y124375D01*
X16350Y124208D01*
X16267Y123875D01*
X16350Y123542D01*
X16600Y123333D01*
X16892Y123208D01*
X17933D01*
G01X16892D02*
X16267Y122000D01*
G01X14792Y124083D02*
X14542Y124333D01*
X14250Y124458D01*
X13917Y124500D01*
X13500Y124417D01*
X13208Y124208D01*
X13125Y123958D01*
X13167Y123708D01*
X13333Y123500D01*
X14167Y123083D01*
X14542Y122792D01*
X14792Y122375D01*
X14875Y122000D01*
X13125D01*
G01X10900Y124500D02*
X11233Y124417D01*
X11483Y124208D01*
X11650Y123958D01*
X11775Y123625D01*
X11817Y123250D01*
X11775Y122875D01*
X11650Y122542D01*
X11483Y122292D01*
X11233Y122083D01*
X10900Y122000D01*
X10567Y122083D01*
X10317Y122292D01*
X10150Y122542D01*
X10025Y122875D01*
X9983Y123250D01*
X10025Y123625D01*
X10150Y123958D01*
X10317Y124208D01*
X10567Y124417D01*
X10900Y124500D01*
G01X7300Y122000D02*
Y124500D01*
X8842Y122708D01*
X6758D01*
G01X16533Y138000D02*
Y140500D01*
X15533D01*
X15200Y140375D01*
X14950Y140083D01*
X14867Y139750D01*
X14950Y139417D01*
X15158Y139167D01*
X15533Y139042D01*
X16533D01*
G01X11683Y140292D02*
X11933Y140417D01*
X12225Y140500D01*
X12558D01*
X12933Y140375D01*
X13225Y140167D01*
X13433Y139917D01*
X13600Y139500D01*
X13642Y139125D01*
X13558Y138750D01*
X13433Y138500D01*
X13183Y138250D01*
X12892Y138083D01*
X12600Y138000D01*
X12308D01*
X12017Y138083D01*
X11767Y138208D01*
X11558Y138375D01*
G01X9500Y138000D02*
Y140500D01*
X10000Y140000D01*
G01Y138000D02*
X9000D01*
G01X6400D02*
X6108Y138042D01*
X5775Y138167D01*
X5567Y138375D01*
X5483Y138667D01*
X5567Y138958D01*
X5817Y139208D01*
X6192Y139333D01*
X6608D01*
X6858Y139417D01*
X7067Y139625D01*
X7150Y139917D01*
X7025Y140208D01*
X6733Y140417D01*
X6400Y140500D01*
X6067Y140417D01*
X5775Y140208D01*
X5650Y139917D01*
X5733Y139625D01*
X5942Y139417D01*
X6192Y139333D01*
X6608D01*
X6983Y139208D01*
X7233Y138958D01*
X7317Y138667D01*
X7233Y138375D01*
X7025Y138167D01*
X6692Y138042D01*
X6400Y138000D01*
G01X4217Y138375D02*
X3967Y138167D01*
X3675Y138042D01*
X3300Y138000D01*
X2925Y138083D01*
X2633Y138250D01*
X2425Y138542D01*
X2383Y138875D01*
X2467Y139208D01*
X2675Y139417D01*
X2967Y139583D01*
X3258Y139625D01*
X3550Y139583D01*
X3925Y139417D01*
X3800Y140500D01*
X2675D01*
G01X14500Y169967D02*
X12000D01*
Y171633D01*
G01Y174733D02*
Y173067D01*
X14500D01*
Y174733D01*
G01X13292Y174067D02*
Y173067D01*
G01X12000Y176083D02*
X14500D01*
Y176917D01*
X14375Y177250D01*
X14208Y177500D01*
X13958Y177708D01*
X13667Y177875D01*
X13250Y177917D01*
X12833Y177875D01*
X12542Y177708D01*
X12292Y177500D01*
X12125Y177250D01*
X12000Y176917D01*
Y176083D01*
G01Y180100D02*
X14500D01*
X14000Y179600D01*
G01X12000D02*
Y180600D01*
G01X12375Y182283D02*
X12167Y182533D01*
X12042Y182825D01*
X12000Y183200D01*
X12083Y183575D01*
X12250Y183867D01*
X12542Y184075D01*
X12875Y184117D01*
X13208Y184033D01*
X13417Y183825D01*
X13583Y183533D01*
X13625Y183242D01*
X13583Y182950D01*
X13417Y182575D01*
X14500Y182700D01*
Y183825D01*
G01X10500Y192083D02*
X15500D01*
X10500Y195917D01*
X15500D01*
G01X13000Y200100D02*
Y201767D01*
X11500D01*
X11000Y201267D01*
X10667Y200683D01*
X10500Y199850D01*
X10667Y199017D01*
X11000Y198433D01*
X11500Y197933D01*
X12083Y197600D01*
X12750Y197433D01*
X13333D01*
X13833Y197600D01*
X14417Y197933D01*
X14917Y198433D01*
X15250Y198933D01*
X15500Y199600D01*
Y200183D01*
X15333Y200850D01*
X15000Y201350D01*
G01X10500Y203617D02*
X15500D01*
Y206783D01*
G01X13083Y205617D02*
Y203617D01*
G01X10500Y209217D02*
X15500D01*
Y212383D01*
G01X13083Y211217D02*
Y209217D01*
G01X15083Y223833D02*
X15333Y223333D01*
X15500Y222750D01*
Y222083D01*
X15250Y221333D01*
X14833Y220750D01*
X14333Y220333D01*
X13500Y220000D01*
X12750Y219917D01*
X12000Y220083D01*
X11500Y220333D01*
X11000Y220833D01*
X10667Y221417D01*
X10500Y222000D01*
Y222583D01*
X10667Y223167D01*
X10917Y223667D01*
X11250Y224083D01*
G01X10500Y227600D02*
X10583Y226933D01*
X10917Y226350D01*
X11417Y225850D01*
X12000Y225517D01*
X12667Y225350D01*
X13333D01*
X14000Y225517D01*
X14583Y225850D01*
X15083Y226350D01*
X15417Y226933D01*
X15500Y227600D01*
X15417Y228267D01*
X15083Y228850D01*
X14583Y229350D01*
X14000Y229683D01*
X13333Y229850D01*
X12667D01*
X12000Y229683D01*
X11417Y229350D01*
X10917Y228850D01*
X10583Y228267D01*
X10500Y227600D01*
G01Y231283D02*
X15500D01*
X10500Y235117D01*
X15500D01*
G01X10500Y236883D02*
X15500D01*
X10500Y240717D01*
X15500D01*
G01X13000Y247842D02*
X15500D01*
X13000Y249758D01*
X15500D01*
G01X14250Y252150D02*
Y252983D01*
X13500D01*
X13250Y252733D01*
X13083Y252442D01*
X13000Y252025D01*
X13083Y251608D01*
X13250Y251317D01*
X13500Y251067D01*
X13792Y250900D01*
X14125Y250817D01*
X14417D01*
X14667Y250900D01*
X14958Y251067D01*
X15208Y251317D01*
X15375Y251567D01*
X15500Y251900D01*
Y252192D01*
X15417Y252525D01*
X15250Y252775D01*
G01X13000Y254208D02*
X15500D01*
Y255792D01*
G01X14292Y255208D02*
Y254208D01*
G01X13000Y257308D02*
X15500D01*
Y258892D01*
G01X14292Y258308D02*
Y257308D01*
G01X13000Y261200D02*
X15500D01*
X15000Y260700D01*
G01X13000D02*
Y261700D01*
G01X25000Y76967D02*
X27500D01*
Y77967D01*
X27375Y78300D01*
X27083Y78550D01*
X26750Y78633D01*
X26417Y78550D01*
X26167Y78342D01*
X26042Y77967D01*
Y76967D01*
G01X25000Y80067D02*
X27500D01*
Y81108D01*
X27375Y81442D01*
X27208Y81650D01*
X26875Y81733D01*
X26542Y81650D01*
X26333Y81400D01*
X26208Y81108D01*
Y80067D01*
G01Y81108D02*
X25000Y81733D01*
G01Y84000D02*
X27500D01*
X27000Y83500D01*
G01X25000D02*
Y84500D01*
G01X27083Y86308D02*
X27333Y86558D01*
X27458Y86850D01*
X27500Y87183D01*
X27417Y87600D01*
X27208Y87892D01*
X26958Y87975D01*
X26708Y87933D01*
X26500Y87767D01*
X26083Y86933D01*
X25792Y86558D01*
X25375Y86308D01*
X25000Y86225D01*
Y87975D01*
G01X27500Y90200D02*
X27417Y89867D01*
X27208Y89617D01*
X26958Y89450D01*
X26625Y89325D01*
X26250Y89283D01*
X25875Y89325D01*
X25542Y89450D01*
X25292Y89617D01*
X25083Y89867D01*
X25000Y90200D01*
X25083Y90533D01*
X25292Y90783D01*
X25542Y90950D01*
X25875Y91075D01*
X26250Y91117D01*
X26625Y91075D01*
X26958Y90950D01*
X27208Y90783D01*
X27417Y90533D01*
X27500Y90200D01*
G01X44033Y102000D02*
Y104500D01*
X43033D01*
X42700Y104375D01*
X42450Y104083D01*
X42367Y103750D01*
X42450Y103417D01*
X42658Y103167D01*
X43033Y103042D01*
X44033D01*
G01X40933Y102000D02*
Y104500D01*
X39892D01*
X39558Y104375D01*
X39350Y104208D01*
X39267Y103875D01*
X39350Y103542D01*
X39600Y103333D01*
X39892Y103208D01*
X40933D01*
G01X39892D02*
X39267Y102000D01*
G01X37000D02*
Y104500D01*
X37500Y104000D01*
G01Y102000D02*
X36500D01*
G01X33900D02*
Y104500D01*
X34400Y104000D01*
G01Y102000D02*
X33400D01*
G01X30800D02*
X30508Y102042D01*
X30175Y102167D01*
X29967Y102375D01*
X29883Y102667D01*
X29967Y102958D01*
X30217Y103208D01*
X30592Y103333D01*
X31008D01*
X31258Y103417D01*
X31467Y103625D01*
X31550Y103917D01*
X31425Y104208D01*
X31133Y104417D01*
X30800Y104500D01*
X30467Y104417D01*
X30175Y104208D01*
X30050Y103917D01*
X30133Y103625D01*
X30342Y103417D01*
X30592Y103333D01*
X31008D01*
X31383Y103208D01*
X31633Y102958D01*
X31717Y102667D01*
X31633Y102375D01*
X31425Y102167D01*
X31092Y102042D01*
X30800Y102000D01*
G01X43983Y106500D02*
Y109000D01*
X42983D01*
X42650Y108875D01*
X42400Y108583D01*
X42317Y108250D01*
X42400Y107917D01*
X42608Y107667D01*
X42983Y107542D01*
X43983D01*
G01X39133Y108792D02*
X39383Y108917D01*
X39675Y109000D01*
X40008D01*
X40383Y108875D01*
X40675Y108667D01*
X40883Y108417D01*
X41050Y108000D01*
X41092Y107625D01*
X41008Y107250D01*
X40883Y107000D01*
X40633Y106750D01*
X40342Y106583D01*
X40050Y106500D01*
X39758D01*
X39467Y106583D01*
X39217Y106708D01*
X39008Y106875D01*
G01X36950Y106500D02*
X36658Y106542D01*
X36325Y106667D01*
X36117Y106875D01*
X36033Y107167D01*
X36117Y107458D01*
X36367Y107708D01*
X36742Y107833D01*
X37158D01*
X37408Y107917D01*
X37617Y108125D01*
X37700Y108417D01*
X37575Y108708D01*
X37283Y108917D01*
X36950Y109000D01*
X36617Y108917D01*
X36325Y108708D01*
X36200Y108417D01*
X36283Y108125D01*
X36492Y107917D01*
X36742Y107833D01*
X37158D01*
X37533Y107708D01*
X37783Y107458D01*
X37867Y107167D01*
X37783Y106875D01*
X37575Y106667D01*
X37242Y106542D01*
X36950Y106500D01*
G01X34558Y106792D02*
X34267Y106583D01*
X33933Y106500D01*
X33600Y106583D01*
X33308Y106833D01*
X33100Y107208D01*
X33017Y107583D01*
Y108042D01*
X33100Y108417D01*
X33308Y108750D01*
X33558Y108917D01*
X33850Y109000D01*
X34183Y108917D01*
X34433Y108750D01*
X34600Y108500D01*
X34683Y108167D01*
X34600Y107875D01*
X34392Y107583D01*
X34142Y107417D01*
X33850Y107375D01*
X33517Y107458D01*
X33267Y107667D01*
X33017Y108042D01*
G01X39000Y84967D02*
X41500D01*
Y85967D01*
X41375Y86300D01*
X41083Y86550D01*
X40750Y86633D01*
X40417Y86550D01*
X40167Y86342D01*
X40042Y85967D01*
Y84967D01*
G01X39000Y88067D02*
X41500D01*
Y89108D01*
X41375Y89442D01*
X41208Y89650D01*
X40875Y89733D01*
X40542Y89650D01*
X40333Y89400D01*
X40208Y89108D01*
Y88067D01*
G01Y89108D02*
X39000Y89733D01*
G01Y92000D02*
X41500D01*
X41000Y91500D01*
G01X39000D02*
Y92500D01*
G01Y95100D02*
X41500D01*
X41000Y94600D01*
G01X39000D02*
Y95600D01*
G01X41083Y97408D02*
X41333Y97658D01*
X41458Y97950D01*
X41500Y98283D01*
X41417Y98700D01*
X41208Y98992D01*
X40958Y99075D01*
X40708Y99033D01*
X40500Y98867D01*
X40083Y98033D01*
X39792Y97658D01*
X39375Y97408D01*
X39000Y97325D01*
Y99075D01*
G01X54533Y123000D02*
Y125500D01*
X53533D01*
X53200Y125375D01*
X52950Y125083D01*
X52867Y124750D01*
X52950Y124417D01*
X53158Y124167D01*
X53533Y124042D01*
X54533D01*
G01X49683Y125292D02*
X49933Y125417D01*
X50225Y125500D01*
X50558D01*
X50933Y125375D01*
X51225Y125167D01*
X51433Y124917D01*
X51600Y124500D01*
X51642Y124125D01*
X51558Y123750D01*
X51433Y123500D01*
X51183Y123250D01*
X50892Y123083D01*
X50600Y123000D01*
X50308D01*
X50017Y123083D01*
X49767Y123208D01*
X49558Y123375D01*
G01X47500Y123000D02*
Y125500D01*
X48000Y125000D01*
G01Y123000D02*
X47000D01*
G01X45317Y123375D02*
X45067Y123167D01*
X44775Y123042D01*
X44400Y123000D01*
X44025Y123083D01*
X43733Y123250D01*
X43525Y123542D01*
X43483Y123875D01*
X43567Y124208D01*
X43775Y124417D01*
X44067Y124583D01*
X44358Y124625D01*
X44650Y124583D01*
X45025Y124417D01*
X44900Y125500D01*
X43775D01*
G01X42008Y123292D02*
X41717Y123083D01*
X41383Y123000D01*
X41050Y123083D01*
X40758Y123333D01*
X40550Y123708D01*
X40467Y124083D01*
Y124542D01*
X40550Y124917D01*
X40758Y125250D01*
X41008Y125417D01*
X41300Y125500D01*
X41633Y125417D01*
X41883Y125250D01*
X42050Y125000D01*
X42133Y124667D01*
X42050Y124375D01*
X41842Y124083D01*
X41592Y123917D01*
X41300Y123875D01*
X40967Y123958D01*
X40717Y124167D01*
X40467Y124542D01*
G01X54733Y278492D02*
X54983Y278617D01*
X55275Y278700D01*
X55608D01*
X55983Y278575D01*
X56275Y278367D01*
X56483Y278117D01*
X56650Y277700D01*
X56692Y277325D01*
X56608Y276950D01*
X56483Y276700D01*
X56233Y276450D01*
X55942Y276283D01*
X55650Y276200D01*
X55358D01*
X55067Y276283D01*
X54817Y276408D01*
X54608Y276575D01*
G01X52550Y276200D02*
Y278700D01*
X53050Y278200D01*
G01Y276200D02*
X52050D01*
G01X49533D02*
X49450Y276742D01*
X49325Y277200D01*
X49158Y277617D01*
X48950Y278075D01*
X48617Y278700D01*
X50283D01*
G01X46433Y276200D02*
X46350Y276742D01*
X46225Y277200D01*
X46058Y277617D01*
X45850Y278075D01*
X45517Y278700D01*
X47183D01*
G01X54733Y282592D02*
X54983Y282717D01*
X55275Y282800D01*
X55608D01*
X55983Y282675D01*
X56275Y282467D01*
X56483Y282217D01*
X56650Y281800D01*
X56692Y281425D01*
X56608Y281050D01*
X56483Y280800D01*
X56233Y280550D01*
X55942Y280383D01*
X55650Y280300D01*
X55358D01*
X55067Y280383D01*
X54817Y280508D01*
X54608Y280675D01*
G01X52550Y280300D02*
Y282800D01*
X53050Y282300D01*
G01Y280300D02*
X52050D01*
G01X49533D02*
X49450Y280842D01*
X49325Y281300D01*
X49158Y281717D01*
X48950Y282175D01*
X48617Y282800D01*
X50283D01*
G01X47267Y280800D02*
X47017Y280508D01*
X46683Y280342D01*
X46308Y280300D01*
X45975Y280342D01*
X45642Y280550D01*
X45433Y280800D01*
X45392Y281050D01*
X45475Y281342D01*
X45767Y281550D01*
X46058Y281633D01*
X46433D01*
G01X46058D02*
X45808Y281758D01*
X45600Y281967D01*
X45517Y282217D01*
X45600Y282467D01*
X45808Y282675D01*
X46183Y282800D01*
X46558Y282758D01*
X46933Y282592D01*
G01X56483Y284500D02*
Y287000D01*
X55442D01*
X55108Y286875D01*
X54900Y286708D01*
X54817Y286375D01*
X54900Y286042D01*
X55150Y285833D01*
X55442Y285708D01*
X56483D01*
G01X55442D02*
X54817Y284500D01*
G01X53467Y284875D02*
X53217Y284667D01*
X52925Y284542D01*
X52550Y284500D01*
X52175Y284583D01*
X51883Y284750D01*
X51675Y285042D01*
X51633Y285375D01*
X51717Y285708D01*
X51925Y285917D01*
X52217Y286083D01*
X52508Y286125D01*
X52800Y286083D01*
X53175Y285917D01*
X53050Y287000D01*
X51925D01*
G01X49450D02*
X49783Y286917D01*
X50033Y286708D01*
X50200Y286458D01*
X50325Y286125D01*
X50367Y285750D01*
X50325Y285375D01*
X50200Y285042D01*
X50033Y284792D01*
X49783Y284583D01*
X49450Y284500D01*
X49117Y284583D01*
X48867Y284792D01*
X48700Y285042D01*
X48575Y285375D01*
X48533Y285750D01*
X48575Y286125D01*
X48700Y286458D01*
X48867Y286708D01*
X49117Y286917D01*
X49450Y287000D01*
G01X47267Y284875D02*
X47017Y284667D01*
X46725Y284542D01*
X46350Y284500D01*
X45975Y284583D01*
X45683Y284750D01*
X45475Y285042D01*
X45433Y285375D01*
X45517Y285708D01*
X45725Y285917D01*
X46017Y286083D01*
X46308Y286125D01*
X46600Y286083D01*
X46975Y285917D01*
X46850Y287000D01*
X45725D01*
G01X64292Y45767D02*
X64417Y45517D01*
X64500Y45225D01*
Y44892D01*
X64375Y44517D01*
X64167Y44225D01*
X63917Y44017D01*
X63500Y43850D01*
X63125Y43808D01*
X62750Y43892D01*
X62500Y44017D01*
X62250Y44267D01*
X62083Y44558D01*
X62000Y44850D01*
Y45142D01*
X62083Y45433D01*
X62208Y45683D01*
X62375Y45892D01*
G01X64083Y47158D02*
X64333Y47408D01*
X64458Y47700D01*
X64500Y48033D01*
X64417Y48450D01*
X64208Y48742D01*
X63958Y48825D01*
X63708Y48783D01*
X63500Y48617D01*
X63083Y47783D01*
X62792Y47408D01*
X62375Y47158D01*
X62000Y47075D01*
Y48825D01*
G01Y51050D02*
X62042Y51342D01*
X62167Y51675D01*
X62375Y51883D01*
X62667Y51967D01*
X62958Y51883D01*
X63208Y51633D01*
X63333Y51258D01*
Y50842D01*
X63417Y50592D01*
X63625Y50383D01*
X63917Y50300D01*
X64208Y50425D01*
X64417Y50717D01*
X64500Y51050D01*
X64417Y51383D01*
X64208Y51675D01*
X63917Y51800D01*
X63625Y51717D01*
X63417Y51508D01*
X63333Y51258D01*
Y50842D01*
X63208Y50467D01*
X62958Y50217D01*
X62667Y50133D01*
X62375Y50217D01*
X62167Y50425D01*
X62042Y50758D01*
X62000Y51050D01*
G01Y54067D02*
X62542Y54150D01*
X63000Y54275D01*
X63417Y54442D01*
X63875Y54650D01*
X64500Y54983D01*
Y53317D01*
G01X72983Y74000D02*
Y76500D01*
X71983D01*
X71650Y76375D01*
X71400Y76083D01*
X71317Y75750D01*
X71400Y75417D01*
X71608Y75167D01*
X71983Y75042D01*
X72983D01*
G01X69883Y74000D02*
Y76500D01*
X68842D01*
X68508Y76375D01*
X68300Y76208D01*
X68217Y75875D01*
X68300Y75542D01*
X68550Y75333D01*
X68842Y75208D01*
X69883D01*
G01X68842D02*
X68217Y74000D01*
G01X66658Y74292D02*
X66367Y74083D01*
X66033Y74000D01*
X65700Y74083D01*
X65408Y74333D01*
X65200Y74708D01*
X65117Y75083D01*
Y75542D01*
X65200Y75917D01*
X65408Y76250D01*
X65658Y76417D01*
X65950Y76500D01*
X66283Y76417D01*
X66533Y76250D01*
X66700Y76000D01*
X66783Y75667D01*
X66700Y75375D01*
X66492Y75083D01*
X66242Y74917D01*
X65950Y74875D01*
X65617Y74958D01*
X65367Y75167D01*
X65117Y75542D01*
G01X62850Y76500D02*
X63183Y76417D01*
X63433Y76208D01*
X63600Y75958D01*
X63725Y75625D01*
X63767Y75250D01*
X63725Y74875D01*
X63600Y74542D01*
X63433Y74292D01*
X63183Y74083D01*
X62850Y74000D01*
X62517Y74083D01*
X62267Y74292D01*
X62100Y74542D01*
X61975Y74875D01*
X61933Y75250D01*
X61975Y75625D01*
X62100Y75958D01*
X62267Y76208D01*
X62517Y76417D01*
X62850Y76500D01*
G01X72983Y78000D02*
Y80500D01*
X71983D01*
X71650Y80375D01*
X71400Y80083D01*
X71317Y79750D01*
X71400Y79417D01*
X71608Y79167D01*
X71983Y79042D01*
X72983D01*
G01X69883Y78000D02*
Y80500D01*
X68842D01*
X68508Y80375D01*
X68300Y80208D01*
X68217Y79875D01*
X68300Y79542D01*
X68550Y79333D01*
X68842Y79208D01*
X69883D01*
G01X68842D02*
X68217Y78000D01*
G01X66658Y78292D02*
X66367Y78083D01*
X66033Y78000D01*
X65700Y78083D01*
X65408Y78333D01*
X65200Y78708D01*
X65117Y79083D01*
Y79542D01*
X65200Y79917D01*
X65408Y80250D01*
X65658Y80417D01*
X65950Y80500D01*
X66283Y80417D01*
X66533Y80250D01*
X66700Y80000D01*
X66783Y79667D01*
X66700Y79375D01*
X66492Y79083D01*
X66242Y78917D01*
X65950Y78875D01*
X65617Y78958D01*
X65367Y79167D01*
X65117Y79542D01*
G01X63642Y79042D02*
X63350Y79333D01*
X63100Y79500D01*
X62767Y79583D01*
X62475Y79500D01*
X62267Y79333D01*
X62100Y79083D01*
X62058Y78792D01*
X62100Y78542D01*
X62267Y78292D01*
X62517Y78083D01*
X62808Y78000D01*
X63142Y78083D01*
X63433Y78333D01*
X63600Y78708D01*
X63642Y79125D01*
X63558Y79667D01*
X63433Y79958D01*
X63225Y80250D01*
X62933Y80458D01*
X62642Y80500D01*
X62350Y80417D01*
X62142Y80208D01*
G01X55000Y132967D02*
X57500D01*
Y133967D01*
X57375Y134300D01*
X57083Y134550D01*
X56750Y134633D01*
X56417Y134550D01*
X56167Y134342D01*
X56042Y133967D01*
Y132967D01*
G01X55000Y136067D02*
X57500D01*
Y137108D01*
X57375Y137442D01*
X57208Y137650D01*
X56875Y137733D01*
X56542Y137650D01*
X56333Y137400D01*
X56208Y137108D01*
Y136067D01*
G01Y137108D02*
X55000Y137733D01*
G01Y140000D02*
X57500D01*
X57000Y139500D01*
G01X55000D02*
Y140500D01*
G01X55292Y142392D02*
X55083Y142683D01*
X55000Y143017D01*
X55083Y143350D01*
X55333Y143642D01*
X55708Y143850D01*
X56083Y143933D01*
X56542D01*
X56917Y143850D01*
X57250Y143642D01*
X57417Y143392D01*
X57500Y143100D01*
X57417Y142767D01*
X57250Y142517D01*
X57000Y142350D01*
X56667Y142267D01*
X56375Y142350D01*
X56083Y142558D01*
X55917Y142808D01*
X55875Y143100D01*
X55958Y143433D01*
X56167Y143683D01*
X56542Y143933D01*
G01X55375Y145283D02*
X55167Y145533D01*
X55042Y145825D01*
X55000Y146200D01*
X55083Y146575D01*
X55250Y146867D01*
X55542Y147075D01*
X55875Y147117D01*
X56208Y147033D01*
X56417Y146825D01*
X56583Y146533D01*
X56625Y146242D01*
X56583Y145950D01*
X56417Y145575D01*
X57500Y145700D01*
Y146825D01*
G01X57792Y163267D02*
X57917Y163017D01*
X58000Y162725D01*
Y162392D01*
X57875Y162017D01*
X57667Y161725D01*
X57417Y161517D01*
X57000Y161350D01*
X56625Y161308D01*
X56250Y161392D01*
X56000Y161517D01*
X55750Y161767D01*
X55583Y162058D01*
X55500Y162350D01*
Y162642D01*
X55583Y162933D01*
X55708Y163183D01*
X55875Y163392D01*
G01X57583Y164658D02*
X57833Y164908D01*
X57958Y165200D01*
X58000Y165533D01*
X57917Y165950D01*
X57708Y166242D01*
X57458Y166325D01*
X57208Y166283D01*
X57000Y166117D01*
X56583Y165283D01*
X56292Y164908D01*
X55875Y164658D01*
X55500Y164575D01*
Y166325D01*
G01X55875Y167633D02*
X55667Y167883D01*
X55542Y168175D01*
X55500Y168550D01*
X55583Y168925D01*
X55750Y169217D01*
X56042Y169425D01*
X56375Y169467D01*
X56708Y169383D01*
X56917Y169175D01*
X57083Y168883D01*
X57125Y168592D01*
X57083Y168300D01*
X56917Y167925D01*
X58000Y168050D01*
Y169175D01*
G01Y171650D02*
X57917Y171317D01*
X57708Y171067D01*
X57458Y170900D01*
X57125Y170775D01*
X56750Y170733D01*
X56375Y170775D01*
X56042Y170900D01*
X55792Y171067D01*
X55583Y171317D01*
X55500Y171650D01*
X55583Y171983D01*
X55792Y172233D01*
X56042Y172400D01*
X56375Y172525D01*
X56750Y172567D01*
X57125Y172525D01*
X57458Y172400D01*
X57708Y172233D01*
X57917Y171983D01*
X58000Y171650D01*
G01X61792Y163267D02*
X61917Y163017D01*
X62000Y162725D01*
Y162392D01*
X61875Y162017D01*
X61667Y161725D01*
X61417Y161517D01*
X61000Y161350D01*
X60625Y161308D01*
X60250Y161392D01*
X60000Y161517D01*
X59750Y161767D01*
X59583Y162058D01*
X59500Y162350D01*
Y162642D01*
X59583Y162933D01*
X59708Y163183D01*
X59875Y163392D01*
G01X61583Y164658D02*
X61833Y164908D01*
X61958Y165200D01*
X62000Y165533D01*
X61917Y165950D01*
X61708Y166242D01*
X61458Y166325D01*
X61208Y166283D01*
X61000Y166117D01*
X60583Y165283D01*
X60292Y164908D01*
X59875Y164658D01*
X59500Y164575D01*
Y166325D01*
G01Y169050D02*
X62000D01*
X60208Y167508D01*
Y169592D01*
G01X59792Y170942D02*
X59583Y171233D01*
X59500Y171567D01*
X59583Y171900D01*
X59833Y172192D01*
X60208Y172400D01*
X60583Y172483D01*
X61042D01*
X61417Y172400D01*
X61750Y172192D01*
X61917Y171942D01*
X62000Y171650D01*
X61917Y171317D01*
X61750Y171067D01*
X61500Y170900D01*
X61167Y170817D01*
X60875Y170900D01*
X60583Y171108D01*
X60417Y171358D01*
X60375Y171650D01*
X60458Y171983D01*
X60667Y172233D01*
X61042Y172483D01*
G01X65792Y163267D02*
X65917Y163017D01*
X66000Y162725D01*
Y162392D01*
X65875Y162017D01*
X65667Y161725D01*
X65417Y161517D01*
X65000Y161350D01*
X64625Y161308D01*
X64250Y161392D01*
X64000Y161517D01*
X63750Y161767D01*
X63583Y162058D01*
X63500Y162350D01*
Y162642D01*
X63583Y162933D01*
X63708Y163183D01*
X63875Y163392D01*
G01X65583Y164658D02*
X65833Y164908D01*
X65958Y165200D01*
X66000Y165533D01*
X65917Y165950D01*
X65708Y166242D01*
X65458Y166325D01*
X65208Y166283D01*
X65000Y166117D01*
X64583Y165283D01*
X64292Y164908D01*
X63875Y164658D01*
X63500Y164575D01*
Y166325D01*
G01Y169050D02*
X66000D01*
X64208Y167508D01*
Y169592D01*
G01X63500Y171650D02*
X63542Y171942D01*
X63667Y172275D01*
X63875Y172483D01*
X64167Y172567D01*
X64458Y172483D01*
X64708Y172233D01*
X64833Y171858D01*
Y171442D01*
X64917Y171192D01*
X65125Y170983D01*
X65417Y170900D01*
X65708Y171025D01*
X65917Y171317D01*
X66000Y171650D01*
X65917Y171983D01*
X65708Y172275D01*
X65417Y172400D01*
X65125Y172317D01*
X64917Y172108D01*
X64833Y171858D01*
Y171442D01*
X64708Y171067D01*
X64458Y170817D01*
X64167Y170733D01*
X63875Y170817D01*
X63667Y171025D01*
X63542Y171358D01*
X63500Y171650D01*
G01X56500Y197517D02*
X59000D01*
Y198558D01*
X58875Y198892D01*
X58708Y199100D01*
X58375Y199183D01*
X58042Y199100D01*
X57833Y198850D01*
X57708Y198558D01*
Y197517D01*
G01Y198558D02*
X56500Y199183D01*
G01X56875Y200533D02*
X56667Y200783D01*
X56542Y201075D01*
X56500Y201450D01*
X56583Y201825D01*
X56750Y202117D01*
X57042Y202325D01*
X57375Y202367D01*
X57708Y202283D01*
X57917Y202075D01*
X58083Y201783D01*
X58125Y201492D01*
X58083Y201200D01*
X57917Y200825D01*
X59000Y200950D01*
Y202075D01*
G01Y204550D02*
X58917Y204217D01*
X58708Y203967D01*
X58458Y203800D01*
X58125Y203675D01*
X57750Y203633D01*
X57375Y203675D01*
X57042Y203800D01*
X56792Y203967D01*
X56583Y204217D01*
X56500Y204550D01*
X56583Y204883D01*
X56792Y205133D01*
X57042Y205300D01*
X57375Y205425D01*
X57750Y205467D01*
X58125Y205425D01*
X58458Y205300D01*
X58708Y205133D01*
X58917Y204883D01*
X59000Y204550D01*
G01X56500Y207650D02*
X59000D01*
X58500Y207150D01*
G01X56500D02*
Y208150D01*
G01X68483Y212500D02*
Y215000D01*
X67442D01*
X67108Y214875D01*
X66900Y214708D01*
X66817Y214375D01*
X66900Y214042D01*
X67150Y213833D01*
X67442Y213708D01*
X68483D01*
G01X67442D02*
X66817Y212500D01*
G01X65467Y213000D02*
X65217Y212708D01*
X64883Y212542D01*
X64508Y212500D01*
X64175Y212542D01*
X63842Y212750D01*
X63633Y213000D01*
X63592Y213250D01*
X63675Y213542D01*
X63967Y213750D01*
X64258Y213833D01*
X64633D01*
G01X64258D02*
X64008Y213958D01*
X63800Y214167D01*
X63717Y214417D01*
X63800Y214667D01*
X64008Y214875D01*
X64383Y215000D01*
X64758Y214958D01*
X65133Y214792D01*
G01X61533Y212500D02*
X61450Y213042D01*
X61325Y213500D01*
X61158Y213917D01*
X60950Y214375D01*
X60617Y215000D01*
X62283D01*
G01X58350D02*
X58683Y214917D01*
X58933Y214708D01*
X59100Y214458D01*
X59225Y214125D01*
X59267Y213750D01*
X59225Y213375D01*
X59100Y213042D01*
X58933Y212792D01*
X58683Y212583D01*
X58350Y212500D01*
X58017Y212583D01*
X57767Y212792D01*
X57600Y213042D01*
X57475Y213375D01*
X57433Y213750D01*
X57475Y214125D01*
X57600Y214458D01*
X57767Y214708D01*
X58017Y214917D01*
X58350Y215000D01*
G01X57000Y225017D02*
X59500D01*
Y226017D01*
X59375Y226350D01*
X59083Y226600D01*
X58750Y226683D01*
X58417Y226600D01*
X58167Y226392D01*
X58042Y226017D01*
Y225017D01*
G01X57000Y228117D02*
X59500D01*
Y229158D01*
X59375Y229492D01*
X59208Y229700D01*
X58875Y229783D01*
X58542Y229700D01*
X58333Y229450D01*
X58208Y229158D01*
Y228117D01*
G01Y229158D02*
X57000Y229783D01*
G01Y232050D02*
X59500D01*
X59000Y231550D01*
G01X57000D02*
Y232550D01*
G01X59083Y234358D02*
X59333Y234608D01*
X59458Y234900D01*
X59500Y235233D01*
X59417Y235650D01*
X59208Y235942D01*
X58958Y236025D01*
X58708Y235983D01*
X58500Y235817D01*
X58083Y234983D01*
X57792Y234608D01*
X57375Y234358D01*
X57000Y234275D01*
Y236025D01*
G01X62000Y225067D02*
X64500D01*
Y226067D01*
X64375Y226400D01*
X64083Y226650D01*
X63750Y226733D01*
X63417Y226650D01*
X63167Y226442D01*
X63042Y226067D01*
Y225067D01*
G01X62000Y228167D02*
X64500D01*
Y229208D01*
X64375Y229542D01*
X64208Y229750D01*
X63875Y229833D01*
X63542Y229750D01*
X63333Y229500D01*
X63208Y229208D01*
Y228167D01*
G01Y229208D02*
X62000Y229833D01*
G01Y232100D02*
X64500D01*
X64000Y231600D01*
G01X62000D02*
Y232600D01*
G01X63683Y243792D02*
X63933Y243917D01*
X64225Y244000D01*
X64558D01*
X64933Y243875D01*
X65225Y243667D01*
X65433Y243417D01*
X65600Y243000D01*
X65642Y242625D01*
X65558Y242250D01*
X65433Y242000D01*
X65183Y241750D01*
X64892Y241583D01*
X64600Y241500D01*
X64308D01*
X64017Y241583D01*
X63767Y241708D01*
X63558Y241875D01*
G01X62417Y242000D02*
X62167Y241708D01*
X61833Y241542D01*
X61458Y241500D01*
X61125Y241542D01*
X60792Y241750D01*
X60583Y242000D01*
X60542Y242250D01*
X60625Y242542D01*
X60917Y242750D01*
X61208Y242833D01*
X61583D01*
G01X61208D02*
X60958Y242958D01*
X60750Y243167D01*
X60667Y243417D01*
X60750Y243667D01*
X60958Y243875D01*
X61333Y244000D01*
X61708Y243958D01*
X62083Y243792D01*
G01X58400Y241500D02*
Y244000D01*
X58900Y243500D01*
G01Y241500D02*
X57900D01*
G01X64183Y248292D02*
X64433Y248417D01*
X64725Y248500D01*
X65058D01*
X65433Y248375D01*
X65725Y248167D01*
X65933Y247917D01*
X66100Y247500D01*
X66142Y247125D01*
X66058Y246750D01*
X65933Y246500D01*
X65683Y246250D01*
X65392Y246083D01*
X65100Y246000D01*
X64808D01*
X64517Y246083D01*
X64267Y246208D01*
X64058Y246375D01*
G01X62917Y246500D02*
X62667Y246208D01*
X62333Y246042D01*
X61958Y246000D01*
X61625Y246042D01*
X61292Y246250D01*
X61083Y246500D01*
X61042Y246750D01*
X61125Y247042D01*
X61417Y247250D01*
X61708Y247333D01*
X62083D01*
G01X61708D02*
X61458Y247458D01*
X61250Y247667D01*
X61167Y247917D01*
X61250Y248167D01*
X61458Y248375D01*
X61833Y248500D01*
X62208Y248458D01*
X62583Y248292D01*
G01X58900Y248500D02*
X59233Y248417D01*
X59483Y248208D01*
X59650Y247958D01*
X59775Y247625D01*
X59817Y247250D01*
X59775Y246875D01*
X59650Y246542D01*
X59483Y246292D01*
X59233Y246083D01*
X58900Y246000D01*
X58567Y246083D01*
X58317Y246292D01*
X58150Y246542D01*
X58025Y246875D01*
X57983Y247250D01*
X58025Y247625D01*
X58150Y247958D01*
X58317Y248208D01*
X58567Y248417D01*
X58900Y248500D01*
G01X68292Y45767D02*
X68417Y45517D01*
X68500Y45225D01*
Y44892D01*
X68375Y44517D01*
X68167Y44225D01*
X67917Y44017D01*
X67500Y43850D01*
X67125Y43808D01*
X66750Y43892D01*
X66500Y44017D01*
X66250Y44267D01*
X66083Y44558D01*
X66000Y44850D01*
Y45142D01*
X66083Y45433D01*
X66208Y45683D01*
X66375Y45892D01*
G01X68083Y47158D02*
X68333Y47408D01*
X68458Y47700D01*
X68500Y48033D01*
X68417Y48450D01*
X68208Y48742D01*
X67958Y48825D01*
X67708Y48783D01*
X67500Y48617D01*
X67083Y47783D01*
X66792Y47408D01*
X66375Y47158D01*
X66000Y47075D01*
Y48825D01*
G01Y51050D02*
X66042Y51342D01*
X66167Y51675D01*
X66375Y51883D01*
X66667Y51967D01*
X66958Y51883D01*
X67208Y51633D01*
X67333Y51258D01*
Y50842D01*
X67417Y50592D01*
X67625Y50383D01*
X67917Y50300D01*
X68208Y50425D01*
X68417Y50717D01*
X68500Y51050D01*
X68417Y51383D01*
X68208Y51675D01*
X67917Y51800D01*
X67625Y51717D01*
X67417Y51508D01*
X67333Y51258D01*
Y50842D01*
X67208Y50467D01*
X66958Y50217D01*
X66667Y50133D01*
X66375Y50217D01*
X66167Y50425D01*
X66042Y50758D01*
X66000Y51050D01*
G01X67042Y53358D02*
X67333Y53650D01*
X67500Y53900D01*
X67583Y54233D01*
X67500Y54525D01*
X67333Y54733D01*
X67083Y54900D01*
X66792Y54942D01*
X66542Y54900D01*
X66292Y54733D01*
X66083Y54483D01*
X66000Y54192D01*
X66083Y53858D01*
X66333Y53567D01*
X66708Y53400D01*
X67125Y53358D01*
X67667Y53442D01*
X67958Y53567D01*
X68250Y53775D01*
X68458Y54067D01*
X68500Y54358D01*
X68417Y54650D01*
X68208Y54858D01*
G01X76292Y45767D02*
X76417Y45517D01*
X76500Y45225D01*
Y44892D01*
X76375Y44517D01*
X76167Y44225D01*
X75917Y44017D01*
X75500Y43850D01*
X75125Y43808D01*
X74750Y43892D01*
X74500Y44017D01*
X74250Y44267D01*
X74083Y44558D01*
X74000Y44850D01*
Y45142D01*
X74083Y45433D01*
X74208Y45683D01*
X74375Y45892D01*
G01X76083Y47158D02*
X76333Y47408D01*
X76458Y47700D01*
X76500Y48033D01*
X76417Y48450D01*
X76208Y48742D01*
X75958Y48825D01*
X75708Y48783D01*
X75500Y48617D01*
X75083Y47783D01*
X74792Y47408D01*
X74375Y47158D01*
X74000Y47075D01*
Y48825D01*
G01Y51050D02*
X74042Y51342D01*
X74167Y51675D01*
X74375Y51883D01*
X74667Y51967D01*
X74958Y51883D01*
X75208Y51633D01*
X75333Y51258D01*
Y50842D01*
X75417Y50592D01*
X75625Y50383D01*
X75917Y50300D01*
X76208Y50425D01*
X76417Y50717D01*
X76500Y51050D01*
X76417Y51383D01*
X76208Y51675D01*
X75917Y51800D01*
X75625Y51717D01*
X75417Y51508D01*
X75333Y51258D01*
Y50842D01*
X75208Y50467D01*
X74958Y50217D01*
X74667Y50133D01*
X74375Y50217D01*
X74167Y50425D01*
X74042Y50758D01*
X74000Y51050D01*
G01Y54650D02*
X76500D01*
X74708Y53108D01*
Y55192D01*
G01X72292Y45767D02*
X72417Y45517D01*
X72500Y45225D01*
Y44892D01*
X72375Y44517D01*
X72167Y44225D01*
X71917Y44017D01*
X71500Y43850D01*
X71125Y43808D01*
X70750Y43892D01*
X70500Y44017D01*
X70250Y44267D01*
X70083Y44558D01*
X70000Y44850D01*
Y45142D01*
X70083Y45433D01*
X70208Y45683D01*
X70375Y45892D01*
G01X72083Y47158D02*
X72333Y47408D01*
X72458Y47700D01*
X72500Y48033D01*
X72417Y48450D01*
X72208Y48742D01*
X71958Y48825D01*
X71708Y48783D01*
X71500Y48617D01*
X71083Y47783D01*
X70792Y47408D01*
X70375Y47158D01*
X70000Y47075D01*
Y48825D01*
G01Y51050D02*
X70042Y51342D01*
X70167Y51675D01*
X70375Y51883D01*
X70667Y51967D01*
X70958Y51883D01*
X71208Y51633D01*
X71333Y51258D01*
Y50842D01*
X71417Y50592D01*
X71625Y50383D01*
X71917Y50300D01*
X72208Y50425D01*
X72417Y50717D01*
X72500Y51050D01*
X72417Y51383D01*
X72208Y51675D01*
X71917Y51800D01*
X71625Y51717D01*
X71417Y51508D01*
X71333Y51258D01*
Y50842D01*
X71208Y50467D01*
X70958Y50217D01*
X70667Y50133D01*
X70375Y50217D01*
X70167Y50425D01*
X70042Y50758D01*
X70000Y51050D01*
G01X70375Y53233D02*
X70167Y53483D01*
X70042Y53775D01*
X70000Y54150D01*
X70083Y54525D01*
X70250Y54817D01*
X70542Y55025D01*
X70875Y55067D01*
X71208Y54983D01*
X71417Y54775D01*
X71583Y54483D01*
X71625Y54192D01*
X71583Y53900D01*
X71417Y53525D01*
X72500Y53650D01*
Y54775D01*
G01X85983Y70500D02*
Y73000D01*
X84983D01*
X84650Y72875D01*
X84400Y72583D01*
X84317Y72250D01*
X84400Y71917D01*
X84608Y71667D01*
X84983Y71542D01*
X85983D01*
G01X81133Y72792D02*
X81383Y72917D01*
X81675Y73000D01*
X82008D01*
X82383Y72875D01*
X82675Y72667D01*
X82883Y72417D01*
X83050Y72000D01*
X83092Y71625D01*
X83008Y71250D01*
X82883Y71000D01*
X82633Y70750D01*
X82342Y70583D01*
X82050Y70500D01*
X81758D01*
X81467Y70583D01*
X81217Y70708D01*
X81008Y70875D01*
G01X79742Y71542D02*
X79450Y71833D01*
X79200Y72000D01*
X78867Y72083D01*
X78575Y72000D01*
X78367Y71833D01*
X78200Y71583D01*
X78158Y71292D01*
X78200Y71042D01*
X78367Y70792D01*
X78617Y70583D01*
X78908Y70500D01*
X79242Y70583D01*
X79533Y70833D01*
X79700Y71208D01*
X79742Y71625D01*
X79658Y72167D01*
X79533Y72458D01*
X79325Y72750D01*
X79033Y72958D01*
X78742Y73000D01*
X78450Y72917D01*
X78242Y72708D01*
G01X75350Y70500D02*
Y73000D01*
X76892Y71208D01*
X74808D01*
G01X85983Y66500D02*
Y69000D01*
X84983D01*
X84650Y68875D01*
X84400Y68583D01*
X84317Y68250D01*
X84400Y67917D01*
X84608Y67667D01*
X84983Y67542D01*
X85983D01*
G01X82883Y66500D02*
Y69000D01*
X81842D01*
X81508Y68875D01*
X81300Y68708D01*
X81217Y68375D01*
X81300Y68042D01*
X81550Y67833D01*
X81842Y67708D01*
X82883D01*
G01X81842D02*
X81217Y66500D01*
G01X78950D02*
Y69000D01*
X79450Y68500D01*
G01Y66500D02*
X78450D01*
G01X75850Y69000D02*
X76183Y68917D01*
X76433Y68708D01*
X76600Y68458D01*
X76725Y68125D01*
X76767Y67750D01*
X76725Y67375D01*
X76600Y67042D01*
X76433Y66792D01*
X76183Y66583D01*
X75850Y66500D01*
X75517Y66583D01*
X75267Y66792D01*
X75100Y67042D01*
X74975Y67375D01*
X74933Y67750D01*
X74975Y68125D01*
X75100Y68458D01*
X75267Y68708D01*
X75517Y68917D01*
X75850Y69000D01*
G01X72750Y66500D02*
Y69000D01*
X73250Y68500D01*
G01Y66500D02*
X72250D01*
G01X82983Y62000D02*
Y64500D01*
X81983D01*
X81650Y64375D01*
X81400Y64083D01*
X81317Y63750D01*
X81400Y63417D01*
X81608Y63167D01*
X81983Y63042D01*
X82983D01*
G01X79883Y62000D02*
Y64500D01*
X78842D01*
X78508Y64375D01*
X78300Y64208D01*
X78217Y63875D01*
X78300Y63542D01*
X78550Y63333D01*
X78842Y63208D01*
X79883D01*
G01X78842D02*
X78217Y62000D01*
G01X76658Y62292D02*
X76367Y62083D01*
X76033Y62000D01*
X75700Y62083D01*
X75408Y62333D01*
X75200Y62708D01*
X75117Y63083D01*
Y63542D01*
X75200Y63917D01*
X75408Y64250D01*
X75658Y64417D01*
X75950Y64500D01*
X76283Y64417D01*
X76533Y64250D01*
X76700Y64000D01*
X76783Y63667D01*
X76700Y63375D01*
X76492Y63083D01*
X76242Y62917D01*
X75950Y62875D01*
X75617Y62958D01*
X75367Y63167D01*
X75117Y63542D01*
G01X73558Y62292D02*
X73267Y62083D01*
X72933Y62000D01*
X72600Y62083D01*
X72308Y62333D01*
X72100Y62708D01*
X72017Y63083D01*
Y63542D01*
X72100Y63917D01*
X72308Y64250D01*
X72558Y64417D01*
X72850Y64500D01*
X73183Y64417D01*
X73433Y64250D01*
X73600Y64000D01*
X73683Y63667D01*
X73600Y63375D01*
X73392Y63083D01*
X73142Y62917D01*
X72850Y62875D01*
X72517Y62958D01*
X72267Y63167D01*
X72017Y63542D01*
G01X85983Y74500D02*
Y77000D01*
X84983D01*
X84650Y76875D01*
X84400Y76583D01*
X84317Y76250D01*
X84400Y75917D01*
X84608Y75667D01*
X84983Y75542D01*
X85983D01*
G01X82883Y74500D02*
Y77000D01*
X81842D01*
X81508Y76875D01*
X81300Y76708D01*
X81217Y76375D01*
X81300Y76042D01*
X81550Y75833D01*
X81842Y75708D01*
X82883D01*
G01X81842D02*
X81217Y74500D01*
G01X78950D02*
X78658Y74542D01*
X78325Y74667D01*
X78117Y74875D01*
X78033Y75167D01*
X78117Y75458D01*
X78367Y75708D01*
X78742Y75833D01*
X79158D01*
X79408Y75917D01*
X79617Y76125D01*
X79700Y76417D01*
X79575Y76708D01*
X79283Y76917D01*
X78950Y77000D01*
X78617Y76917D01*
X78325Y76708D01*
X78200Y76417D01*
X78283Y76125D01*
X78492Y75917D01*
X78742Y75833D01*
X79158D01*
X79533Y75708D01*
X79783Y75458D01*
X79867Y75167D01*
X79783Y74875D01*
X79575Y74667D01*
X79242Y74542D01*
X78950Y74500D01*
G01X75350D02*
Y77000D01*
X76892Y75208D01*
X74808D01*
G01X72983Y70000D02*
Y72500D01*
X71942D01*
X71608Y72375D01*
X71400Y72208D01*
X71317Y71875D01*
X71400Y71542D01*
X71650Y71333D01*
X71942Y71208D01*
X72983D01*
G01X71942D02*
X71317Y70000D01*
G01X69967Y70500D02*
X69717Y70208D01*
X69383Y70042D01*
X69008Y70000D01*
X68675Y70042D01*
X68342Y70250D01*
X68133Y70500D01*
X68092Y70750D01*
X68175Y71042D01*
X68467Y71250D01*
X68758Y71333D01*
X69133D01*
G01X68758D02*
X68508Y71458D01*
X68300Y71667D01*
X68217Y71917D01*
X68300Y72167D01*
X68508Y72375D01*
X68883Y72500D01*
X69258Y72458D01*
X69633Y72292D01*
G01X66033Y70000D02*
X65950Y70542D01*
X65825Y71000D01*
X65658Y71417D01*
X65450Y71875D01*
X65117Y72500D01*
X66783D01*
G01X85983Y78500D02*
Y81000D01*
X84983D01*
X84650Y80875D01*
X84400Y80583D01*
X84317Y80250D01*
X84400Y79917D01*
X84608Y79667D01*
X84983Y79542D01*
X85983D01*
G01X82883Y78500D02*
Y81000D01*
X81842D01*
X81508Y80875D01*
X81300Y80708D01*
X81217Y80375D01*
X81300Y80042D01*
X81550Y79833D01*
X81842Y79708D01*
X82883D01*
G01X81842D02*
X81217Y78500D01*
G01X78950D02*
X78658Y78542D01*
X78325Y78667D01*
X78117Y78875D01*
X78033Y79167D01*
X78117Y79458D01*
X78367Y79708D01*
X78742Y79833D01*
X79158D01*
X79408Y79917D01*
X79617Y80125D01*
X79700Y80417D01*
X79575Y80708D01*
X79283Y80917D01*
X78950Y81000D01*
X78617Y80917D01*
X78325Y80708D01*
X78200Y80417D01*
X78283Y80125D01*
X78492Y79917D01*
X78742Y79833D01*
X79158D01*
X79533Y79708D01*
X79783Y79458D01*
X79867Y79167D01*
X79783Y78875D01*
X79575Y78667D01*
X79242Y78542D01*
X78950Y78500D01*
G01X75933D02*
X75850Y79042D01*
X75725Y79500D01*
X75558Y79917D01*
X75350Y80375D01*
X75017Y81000D01*
X76683D01*
G01X82483Y113000D02*
Y115500D01*
X81483D01*
X81150Y115375D01*
X80900Y115083D01*
X80817Y114750D01*
X80900Y114417D01*
X81108Y114167D01*
X81483Y114042D01*
X82483D01*
G01X79383Y113000D02*
Y115500D01*
X78342D01*
X78008Y115375D01*
X77800Y115208D01*
X77717Y114875D01*
X77800Y114542D01*
X78050Y114333D01*
X78342Y114208D01*
X79383D01*
G01X78342D02*
X77717Y113000D01*
G01X75450D02*
X75158Y113042D01*
X74825Y113167D01*
X74617Y113375D01*
X74533Y113667D01*
X74617Y113958D01*
X74867Y114208D01*
X75242Y114333D01*
X75658D01*
X75908Y114417D01*
X76117Y114625D01*
X76200Y114917D01*
X76075Y115208D01*
X75783Y115417D01*
X75450Y115500D01*
X75117Y115417D01*
X74825Y115208D01*
X74700Y114917D01*
X74783Y114625D01*
X74992Y114417D01*
X75242Y114333D01*
X75658D01*
X76033Y114208D01*
X76283Y113958D01*
X76367Y113667D01*
X76283Y113375D01*
X76075Y113167D01*
X75742Y113042D01*
X75450Y113000D01*
G01X73142Y114042D02*
X72850Y114333D01*
X72600Y114500D01*
X72267Y114583D01*
X71975Y114500D01*
X71767Y114333D01*
X71600Y114083D01*
X71558Y113792D01*
X71600Y113542D01*
X71767Y113292D01*
X72017Y113083D01*
X72308Y113000D01*
X72642Y113083D01*
X72933Y113333D01*
X73100Y113708D01*
X73142Y114125D01*
X73058Y114667D01*
X72933Y114958D01*
X72725Y115250D01*
X72433Y115458D01*
X72142Y115500D01*
X71850Y115417D01*
X71642Y115208D01*
G01X79033Y142500D02*
Y145000D01*
X78033D01*
X77700Y144875D01*
X77450Y144583D01*
X77367Y144250D01*
X77450Y143917D01*
X77658Y143667D01*
X78033Y143542D01*
X79033D01*
G01X74183Y144792D02*
X74433Y144917D01*
X74725Y145000D01*
X75058D01*
X75433Y144875D01*
X75725Y144667D01*
X75933Y144417D01*
X76100Y144000D01*
X76142Y143625D01*
X76058Y143250D01*
X75933Y143000D01*
X75683Y142750D01*
X75392Y142583D01*
X75100Y142500D01*
X74808D01*
X74517Y142583D01*
X74267Y142708D01*
X74058Y142875D01*
G01X72000Y142500D02*
Y145000D01*
X72500Y144500D01*
G01Y142500D02*
X71500D01*
G01X69817Y142875D02*
X69567Y142667D01*
X69275Y142542D01*
X68900Y142500D01*
X68525Y142583D01*
X68233Y142750D01*
X68025Y143042D01*
X67983Y143375D01*
X68067Y143708D01*
X68275Y143917D01*
X68567Y144083D01*
X68858Y144125D01*
X69150Y144083D01*
X69525Y143917D01*
X69400Y145000D01*
X68275D01*
G01X65800Y142500D02*
Y145000D01*
X66300Y144500D01*
G01Y142500D02*
X65300D01*
G01X79033Y150500D02*
Y153000D01*
X78033D01*
X77700Y152875D01*
X77450Y152583D01*
X77367Y152250D01*
X77450Y151917D01*
X77658Y151667D01*
X78033Y151542D01*
X79033D01*
G01X75933Y150500D02*
Y153000D01*
X74892D01*
X74558Y152875D01*
X74350Y152708D01*
X74267Y152375D01*
X74350Y152042D01*
X74600Y151833D01*
X74892Y151708D01*
X75933D01*
G01X74892D02*
X74267Y150500D01*
G01X72000D02*
Y153000D01*
X72500Y152500D01*
G01Y150500D02*
X71500D01*
G01X69608Y150792D02*
X69317Y150583D01*
X68983Y150500D01*
X68650Y150583D01*
X68358Y150833D01*
X68150Y151208D01*
X68067Y151583D01*
Y152042D01*
X68150Y152417D01*
X68358Y152750D01*
X68608Y152917D01*
X68900Y153000D01*
X69233Y152917D01*
X69483Y152750D01*
X69650Y152500D01*
X69733Y152167D01*
X69650Y151875D01*
X69442Y151583D01*
X69192Y151417D01*
X68900Y151375D01*
X68567Y151458D01*
X68317Y151667D01*
X68067Y152042D01*
G01X65800Y153000D02*
X66133Y152917D01*
X66383Y152708D01*
X66550Y152458D01*
X66675Y152125D01*
X66717Y151750D01*
X66675Y151375D01*
X66550Y151042D01*
X66383Y150792D01*
X66133Y150583D01*
X65800Y150500D01*
X65467Y150583D01*
X65217Y150792D01*
X65050Y151042D01*
X64925Y151375D01*
X64883Y151750D01*
X64925Y152125D01*
X65050Y152458D01*
X65217Y152708D01*
X65467Y152917D01*
X65800Y153000D01*
G01X79033Y146500D02*
Y149000D01*
X78033D01*
X77700Y148875D01*
X77450Y148583D01*
X77367Y148250D01*
X77450Y147917D01*
X77658Y147667D01*
X78033Y147542D01*
X79033D01*
G01X75933Y146500D02*
Y149000D01*
X74892D01*
X74558Y148875D01*
X74350Y148708D01*
X74267Y148375D01*
X74350Y148042D01*
X74600Y147833D01*
X74892Y147708D01*
X75933D01*
G01X74892D02*
X74267Y146500D01*
G01X72000D02*
Y149000D01*
X72500Y148500D01*
G01Y146500D02*
X71500D01*
G01X68900D02*
X68608Y146542D01*
X68275Y146667D01*
X68067Y146875D01*
X67983Y147167D01*
X68067Y147458D01*
X68317Y147708D01*
X68692Y147833D01*
X69108D01*
X69358Y147917D01*
X69567Y148125D01*
X69650Y148417D01*
X69525Y148708D01*
X69233Y148917D01*
X68900Y149000D01*
X68567Y148917D01*
X68275Y148708D01*
X68150Y148417D01*
X68233Y148125D01*
X68442Y147917D01*
X68692Y147833D01*
X69108D01*
X69483Y147708D01*
X69733Y147458D01*
X69817Y147167D01*
X69733Y146875D01*
X69525Y146667D01*
X69192Y146542D01*
X68900Y146500D01*
G01X66508Y146792D02*
X66217Y146583D01*
X65883Y146500D01*
X65550Y146583D01*
X65258Y146833D01*
X65050Y147208D01*
X64967Y147583D01*
Y148042D01*
X65050Y148417D01*
X65258Y148750D01*
X65508Y148917D01*
X65800Y149000D01*
X66133Y148917D01*
X66383Y148750D01*
X66550Y148500D01*
X66633Y148167D01*
X66550Y147875D01*
X66342Y147583D01*
X66092Y147417D01*
X65800Y147375D01*
X65467Y147458D01*
X65217Y147667D01*
X64967Y148042D01*
G01X69792Y163267D02*
X69917Y163017D01*
X70000Y162725D01*
Y162392D01*
X69875Y162017D01*
X69667Y161725D01*
X69417Y161517D01*
X69000Y161350D01*
X68625Y161308D01*
X68250Y161392D01*
X68000Y161517D01*
X67750Y161767D01*
X67583Y162058D01*
X67500Y162350D01*
Y162642D01*
X67583Y162933D01*
X67708Y163183D01*
X67875Y163392D01*
G01X69583Y164658D02*
X69833Y164908D01*
X69958Y165200D01*
X70000Y165533D01*
X69917Y165950D01*
X69708Y166242D01*
X69458Y166325D01*
X69208Y166283D01*
X69000Y166117D01*
X68583Y165283D01*
X68292Y164908D01*
X67875Y164658D01*
X67500Y164575D01*
Y166325D01*
G01Y169050D02*
X70000D01*
X68208Y167508D01*
Y169592D01*
G01X67500Y171567D02*
X68042Y171650D01*
X68500Y171775D01*
X68917Y171942D01*
X69375Y172150D01*
X70000Y172483D01*
Y170817D01*
G01X73500Y164400D02*
X73542Y164067D01*
X73708Y163775D01*
X73958Y163525D01*
X74250Y163358D01*
X74583Y163275D01*
X74917D01*
X75250Y163358D01*
X75542Y163525D01*
X75792Y163775D01*
X75958Y164067D01*
X76000Y164400D01*
X75958Y164733D01*
X75792Y165025D01*
X75542Y165275D01*
X75250Y165442D01*
X74917Y165525D01*
X74583D01*
X74250Y165442D01*
X73958Y165275D01*
X73708Y165025D01*
X73542Y164733D01*
X73500Y164400D01*
G01X74167Y164733D02*
X73500Y165233D01*
G01Y167500D02*
X76000D01*
X75500Y167000D01*
G01X73500D02*
Y168000D01*
G01Y170517D02*
X74042Y170600D01*
X74500Y170725D01*
X74917Y170892D01*
X75375Y171100D01*
X76000Y171433D01*
Y169767D01*
G01X81250Y180750D02*
Y177250D01*
X67750D01*
Y180750D01*
X81250D01*
G01X71500Y200517D02*
X74000D01*
Y201558D01*
X73875Y201892D01*
X73708Y202100D01*
X73375Y202183D01*
X73042Y202100D01*
X72833Y201850D01*
X72708Y201558D01*
Y200517D01*
G01Y201558D02*
X71500Y202183D01*
G01X71875Y203533D02*
X71667Y203783D01*
X71542Y204075D01*
X71500Y204450D01*
X71583Y204825D01*
X71750Y205117D01*
X72042Y205325D01*
X72375Y205367D01*
X72708Y205283D01*
X72917Y205075D01*
X73083Y204783D01*
X73125Y204492D01*
X73083Y204200D01*
X72917Y203825D01*
X74000Y203950D01*
Y205075D01*
G01Y207550D02*
X73917Y207217D01*
X73708Y206967D01*
X73458Y206800D01*
X73125Y206675D01*
X72750Y206633D01*
X72375Y206675D01*
X72042Y206800D01*
X71792Y206967D01*
X71583Y207217D01*
X71500Y207550D01*
X71583Y207883D01*
X71792Y208133D01*
X72042Y208300D01*
X72375Y208425D01*
X72750Y208467D01*
X73125Y208425D01*
X73458Y208300D01*
X73708Y208133D01*
X73917Y207883D01*
X74000Y207550D01*
G01Y210650D02*
X73917Y210317D01*
X73708Y210067D01*
X73458Y209900D01*
X73125Y209775D01*
X72750Y209733D01*
X72375Y209775D01*
X72042Y209900D01*
X71792Y210067D01*
X71583Y210317D01*
X71500Y210650D01*
X71583Y210983D01*
X71792Y211233D01*
X72042Y211400D01*
X72375Y211525D01*
X72750Y211567D01*
X73125Y211525D01*
X73458Y211400D01*
X73708Y211233D01*
X73917Y210983D01*
X74000Y210650D01*
G01X79000Y207517D02*
X81500D01*
Y208517D01*
X81375Y208850D01*
X81083Y209100D01*
X80750Y209183D01*
X80417Y209100D01*
X80167Y208892D01*
X80042Y208517D01*
Y207517D01*
G01X79000Y210617D02*
X81500D01*
Y211658D01*
X81375Y211992D01*
X81208Y212200D01*
X80875Y212283D01*
X80542Y212200D01*
X80333Y211950D01*
X80208Y211658D01*
Y210617D01*
G01Y211658D02*
X79000Y212283D01*
G01Y214467D02*
X79542Y214550D01*
X80000Y214675D01*
X80417Y214842D01*
X80875Y215050D01*
X81500Y215383D01*
Y213717D01*
G01X79000Y218150D02*
X81500D01*
X79708Y216608D01*
Y218692D01*
G01X75433Y217000D02*
Y219500D01*
X74433D01*
X74100Y219375D01*
X73850Y219083D01*
X73767Y218750D01*
X73850Y218417D01*
X74058Y218167D01*
X74433Y218042D01*
X75433D01*
G01X70583Y219292D02*
X70833Y219417D01*
X71125Y219500D01*
X71458D01*
X71833Y219375D01*
X72125Y219167D01*
X72333Y218917D01*
X72500Y218500D01*
X72542Y218125D01*
X72458Y217750D01*
X72333Y217500D01*
X72083Y217250D01*
X71792Y217083D01*
X71500Y217000D01*
X71208D01*
X70917Y217083D01*
X70667Y217208D01*
X70458Y217375D01*
G01X69192Y219083D02*
X68942Y219333D01*
X68650Y219458D01*
X68317Y219500D01*
X67900Y219417D01*
X67608Y219208D01*
X67525Y218958D01*
X67567Y218708D01*
X67733Y218500D01*
X68567Y218083D01*
X68942Y217792D01*
X69192Y217375D01*
X69275Y217000D01*
X67525D01*
G01X97292Y43267D02*
X97417Y43017D01*
X97500Y42725D01*
Y42392D01*
X97375Y42017D01*
X97167Y41725D01*
X96917Y41517D01*
X96500Y41350D01*
X96125Y41308D01*
X95750Y41392D01*
X95500Y41517D01*
X95250Y41767D01*
X95083Y42058D01*
X95000Y42350D01*
Y42642D01*
X95083Y42933D01*
X95208Y43183D01*
X95375Y43392D01*
G01X97083Y44658D02*
X97333Y44908D01*
X97458Y45200D01*
X97500Y45533D01*
X97417Y45950D01*
X97208Y46242D01*
X96958Y46325D01*
X96708Y46283D01*
X96500Y46117D01*
X96083Y45283D01*
X95792Y44908D01*
X95375Y44658D01*
X95000Y44575D01*
Y46325D01*
G01Y48467D02*
X95542Y48550D01*
X96000Y48675D01*
X96417Y48842D01*
X96875Y49050D01*
X97500Y49383D01*
Y47717D01*
G01X97083Y50858D02*
X97333Y51108D01*
X97458Y51400D01*
X97500Y51733D01*
X97417Y52150D01*
X97208Y52442D01*
X96958Y52525D01*
X96708Y52483D01*
X96500Y52317D01*
X96083Y51483D01*
X95792Y51108D01*
X95375Y50858D01*
X95000Y50775D01*
Y52525D01*
G01X93292Y43267D02*
X93417Y43017D01*
X93500Y42725D01*
Y42392D01*
X93375Y42017D01*
X93167Y41725D01*
X92917Y41517D01*
X92500Y41350D01*
X92125Y41308D01*
X91750Y41392D01*
X91500Y41517D01*
X91250Y41767D01*
X91083Y42058D01*
X91000Y42350D01*
Y42642D01*
X91083Y42933D01*
X91208Y43183D01*
X91375Y43392D01*
G01X93083Y44658D02*
X93333Y44908D01*
X93458Y45200D01*
X93500Y45533D01*
X93417Y45950D01*
X93208Y46242D01*
X92958Y46325D01*
X92708Y46283D01*
X92500Y46117D01*
X92083Y45283D01*
X91792Y44908D01*
X91375Y44658D01*
X91000Y44575D01*
Y46325D01*
G01Y48467D02*
X91542Y48550D01*
X92000Y48675D01*
X92417Y48842D01*
X92875Y49050D01*
X93500Y49383D01*
Y47717D01*
G01X91500Y50733D02*
X91208Y50983D01*
X91042Y51317D01*
X91000Y51692D01*
X91042Y52025D01*
X91250Y52358D01*
X91500Y52567D01*
X91750Y52608D01*
X92042Y52525D01*
X92250Y52233D01*
X92333Y51942D01*
Y51567D01*
G01Y51942D02*
X92458Y52192D01*
X92667Y52400D01*
X92917Y52483D01*
X93167Y52400D01*
X93375Y52192D01*
X93500Y51817D01*
X93458Y51442D01*
X93292Y51067D01*
G01X119000Y79000D02*
Y99000D01*
X102000D01*
Y101000D01*
X88000D01*
Y69500D01*
X105500D01*
Y66500D01*
X118500D01*
Y71500D01*
G01X100150Y68000D02*
Y65500D01*
G01X101108Y68000D02*
X99192D01*
G01X97883Y65500D02*
Y68000D01*
X96883D01*
X96550Y67875D01*
X96300Y67583D01*
X96217Y67250D01*
X96300Y66917D01*
X96508Y66667D01*
X96883Y66542D01*
X97883D01*
G01X94867Y65875D02*
X94617Y65667D01*
X94325Y65542D01*
X93950Y65500D01*
X93575Y65583D01*
X93283Y65750D01*
X93075Y66042D01*
X93033Y66375D01*
X93117Y66708D01*
X93325Y66917D01*
X93617Y67083D01*
X93908Y67125D01*
X94200Y67083D01*
X94575Y66917D01*
X94450Y68000D01*
X93325D01*
G01X90850D02*
X91183Y67917D01*
X91433Y67708D01*
X91600Y67458D01*
X91725Y67125D01*
X91767Y66750D01*
X91725Y66375D01*
X91600Y66042D01*
X91433Y65792D01*
X91183Y65583D01*
X90850Y65500D01*
X90517Y65583D01*
X90267Y65792D01*
X90100Y66042D01*
X89975Y66375D01*
X89933Y66750D01*
X89975Y67125D01*
X90100Y67458D01*
X90267Y67708D01*
X90517Y67917D01*
X90850Y68000D01*
G01X89500Y72517D02*
X92000D01*
Y73558D01*
X91875Y73892D01*
X91708Y74100D01*
X91375Y74183D01*
X91042Y74100D01*
X90833Y73850D01*
X90708Y73558D01*
Y72517D01*
G01Y73558D02*
X89500Y74183D01*
G01Y76950D02*
X92000D01*
X90208Y75408D01*
Y77492D01*
G01X90000Y78633D02*
X89708Y78883D01*
X89542Y79217D01*
X89500Y79592D01*
X89542Y79925D01*
X89750Y80258D01*
X90000Y80467D01*
X90250Y80508D01*
X90542Y80425D01*
X90750Y80133D01*
X90833Y79842D01*
Y79467D01*
G01Y79842D02*
X90958Y80092D01*
X91167Y80300D01*
X91417Y80383D01*
X91667Y80300D01*
X91875Y80092D01*
X92000Y79717D01*
X91958Y79342D01*
X91792Y78967D01*
G01X92000Y82650D02*
X91917Y82317D01*
X91708Y82067D01*
X91458Y81900D01*
X91125Y81775D01*
X90750Y81733D01*
X90375Y81775D01*
X90042Y81900D01*
X89792Y82067D01*
X89583Y82317D01*
X89500Y82650D01*
X89583Y82983D01*
X89792Y83233D01*
X90042Y83400D01*
X90375Y83525D01*
X90750Y83567D01*
X91125Y83525D01*
X91458Y83400D01*
X91708Y83233D01*
X91917Y82983D01*
X92000Y82650D01*
G01X93500Y72517D02*
X96000D01*
Y73558D01*
X95875Y73892D01*
X95708Y74100D01*
X95375Y74183D01*
X95042Y74100D01*
X94833Y73850D01*
X94708Y73558D01*
Y72517D01*
G01Y73558D02*
X93500Y74183D01*
G01Y76950D02*
X96000D01*
X94208Y75408D01*
Y77492D01*
G01X95583Y78758D02*
X95833Y79008D01*
X95958Y79300D01*
X96000Y79633D01*
X95917Y80050D01*
X95708Y80342D01*
X95458Y80425D01*
X95208Y80383D01*
X95000Y80217D01*
X94583Y79383D01*
X94292Y79008D01*
X93875Y78758D01*
X93500Y78675D01*
Y80425D01*
G01X93792Y81942D02*
X93583Y82233D01*
X93500Y82567D01*
X93583Y82900D01*
X93833Y83192D01*
X94208Y83400D01*
X94583Y83483D01*
X95042D01*
X95417Y83400D01*
X95750Y83192D01*
X95917Y82942D01*
X96000Y82650D01*
X95917Y82317D01*
X95750Y82067D01*
X95500Y81900D01*
X95167Y81817D01*
X94875Y81900D01*
X94583Y82108D01*
X94417Y82358D01*
X94375Y82650D01*
X94458Y82983D01*
X94667Y83233D01*
X95042Y83483D01*
G01X90000Y87517D02*
X92500D01*
Y88558D01*
X92375Y88892D01*
X92208Y89100D01*
X91875Y89183D01*
X91542Y89100D01*
X91333Y88850D01*
X91208Y88558D01*
Y87517D01*
G01Y88558D02*
X90000Y89183D01*
G01X90500Y90533D02*
X90208Y90783D01*
X90042Y91117D01*
X90000Y91492D01*
X90042Y91825D01*
X90250Y92158D01*
X90500Y92367D01*
X90750Y92408D01*
X91042Y92325D01*
X91250Y92033D01*
X91333Y91742D01*
Y91367D01*
G01Y91742D02*
X91458Y91992D01*
X91667Y92200D01*
X91917Y92283D01*
X92167Y92200D01*
X92375Y91992D01*
X92500Y91617D01*
X92458Y91242D01*
X92292Y90867D01*
G01X91042Y93758D02*
X91333Y94050D01*
X91500Y94300D01*
X91583Y94633D01*
X91500Y94925D01*
X91333Y95133D01*
X91083Y95300D01*
X90792Y95342D01*
X90542Y95300D01*
X90292Y95133D01*
X90083Y94883D01*
X90000Y94592D01*
X90083Y94258D01*
X90333Y93967D01*
X90708Y93800D01*
X91125Y93758D01*
X91667Y93842D01*
X91958Y93967D01*
X92250Y94175D01*
X92458Y94467D01*
X92500Y94758D01*
X92417Y95050D01*
X92208Y95258D01*
G01X90292Y96942D02*
X90083Y97233D01*
X90000Y97567D01*
X90083Y97900D01*
X90333Y98192D01*
X90708Y98400D01*
X91083Y98483D01*
X91542D01*
X91917Y98400D01*
X92250Y98192D01*
X92417Y97942D01*
X92500Y97650D01*
X92417Y97317D01*
X92250Y97067D01*
X92000Y96900D01*
X91667Y96817D01*
X91375Y96900D01*
X91083Y97108D01*
X90917Y97358D01*
X90875Y97650D01*
X90958Y97983D01*
X91167Y98233D01*
X91542Y98483D01*
G01X95483Y113000D02*
Y115500D01*
X94483D01*
X94150Y115375D01*
X93900Y115083D01*
X93817Y114750D01*
X93900Y114417D01*
X94108Y114167D01*
X94483Y114042D01*
X95483D01*
G01X90633Y115292D02*
X90883Y115417D01*
X91175Y115500D01*
X91508D01*
X91883Y115375D01*
X92175Y115167D01*
X92383Y114917D01*
X92550Y114500D01*
X92592Y114125D01*
X92508Y113750D01*
X92383Y113500D01*
X92133Y113250D01*
X91842Y113083D01*
X91550Y113000D01*
X91258D01*
X90967Y113083D01*
X90717Y113208D01*
X90508Y113375D01*
G01X89242Y114042D02*
X88950Y114333D01*
X88700Y114500D01*
X88367Y114583D01*
X88075Y114500D01*
X87867Y114333D01*
X87700Y114083D01*
X87658Y113792D01*
X87700Y113542D01*
X87867Y113292D01*
X88117Y113083D01*
X88408Y113000D01*
X88742Y113083D01*
X89033Y113333D01*
X89200Y113708D01*
X89242Y114125D01*
X89158Y114667D01*
X89033Y114958D01*
X88825Y115250D01*
X88533Y115458D01*
X88242Y115500D01*
X87950Y115417D01*
X87742Y115208D01*
G01X86267Y113500D02*
X86017Y113208D01*
X85683Y113042D01*
X85308Y113000D01*
X84975Y113042D01*
X84642Y113250D01*
X84433Y113500D01*
X84392Y113750D01*
X84475Y114042D01*
X84767Y114250D01*
X85058Y114333D01*
X85433D01*
G01X85058D02*
X84808Y114458D01*
X84600Y114667D01*
X84517Y114917D01*
X84600Y115167D01*
X84808Y115375D01*
X85183Y115500D01*
X85558Y115458D01*
X85933Y115292D01*
G01X92500Y120017D02*
X95000D01*
Y121017D01*
X94875Y121350D01*
X94583Y121600D01*
X94250Y121683D01*
X93917Y121600D01*
X93667Y121392D01*
X93542Y121017D01*
Y120017D01*
G01X94792Y124867D02*
X94917Y124617D01*
X95000Y124325D01*
Y123992D01*
X94875Y123617D01*
X94667Y123325D01*
X94417Y123117D01*
X94000Y122950D01*
X93625Y122908D01*
X93250Y122992D01*
X93000Y123117D01*
X92750Y123367D01*
X92583Y123658D01*
X92500Y123950D01*
Y124242D01*
X92583Y124533D01*
X92708Y124783D01*
X92875Y124992D01*
G01X92500Y127550D02*
X95000D01*
X93208Y126008D01*
Y128092D01*
G01X92500Y130067D02*
X93042Y130150D01*
X93500Y130275D01*
X93917Y130442D01*
X94375Y130650D01*
X95000Y130983D01*
Y129317D01*
G01X93533Y164500D02*
Y167000D01*
X92533D01*
X92200Y166875D01*
X91950Y166583D01*
X91867Y166250D01*
X91950Y165917D01*
X92158Y165667D01*
X92533Y165542D01*
X93533D01*
G01X88683Y166792D02*
X88933Y166917D01*
X89225Y167000D01*
X89558D01*
X89933Y166875D01*
X90225Y166667D01*
X90433Y166417D01*
X90600Y166000D01*
X90642Y165625D01*
X90558Y165250D01*
X90433Y165000D01*
X90183Y164750D01*
X89892Y164583D01*
X89600Y164500D01*
X89308D01*
X89017Y164583D01*
X88767Y164708D01*
X88558Y164875D01*
G01X86500Y164500D02*
Y167000D01*
X87000Y166500D01*
G01Y164500D02*
X86000D01*
G01X84317Y165000D02*
X84067Y164708D01*
X83733Y164542D01*
X83358Y164500D01*
X83025Y164542D01*
X82692Y164750D01*
X82483Y165000D01*
X82442Y165250D01*
X82525Y165542D01*
X82817Y165750D01*
X83108Y165833D01*
X83483D01*
G01X83108D02*
X82858Y165958D01*
X82650Y166167D01*
X82567Y166417D01*
X82650Y166667D01*
X82858Y166875D01*
X83233Y167000D01*
X83608Y166958D01*
X83983Y166792D01*
G01X81008Y164792D02*
X80717Y164583D01*
X80383Y164500D01*
X80050Y164583D01*
X79758Y164833D01*
X79550Y165208D01*
X79467Y165583D01*
Y166042D01*
X79550Y166417D01*
X79758Y166750D01*
X80008Y166917D01*
X80300Y167000D01*
X80633Y166917D01*
X80883Y166750D01*
X81050Y166500D01*
X81133Y166167D01*
X81050Y165875D01*
X80842Y165583D01*
X80592Y165417D01*
X80300Y165375D01*
X79967Y165458D01*
X79717Y165667D01*
X79467Y166042D01*
G01X93533Y168500D02*
Y171000D01*
X92533D01*
X92200Y170875D01*
X91950Y170583D01*
X91867Y170250D01*
X91950Y169917D01*
X92158Y169667D01*
X92533Y169542D01*
X93533D01*
G01X88683Y170792D02*
X88933Y170917D01*
X89225Y171000D01*
X89558D01*
X89933Y170875D01*
X90225Y170667D01*
X90433Y170417D01*
X90600Y170000D01*
X90642Y169625D01*
X90558Y169250D01*
X90433Y169000D01*
X90183Y168750D01*
X89892Y168583D01*
X89600Y168500D01*
X89308D01*
X89017Y168583D01*
X88767Y168708D01*
X88558Y168875D01*
G01X86500Y168500D02*
Y171000D01*
X87000Y170500D01*
G01Y168500D02*
X86000D01*
G01X84317Y169000D02*
X84067Y168708D01*
X83733Y168542D01*
X83358Y168500D01*
X83025Y168542D01*
X82692Y168750D01*
X82483Y169000D01*
X82442Y169250D01*
X82525Y169542D01*
X82817Y169750D01*
X83108Y169833D01*
X83483D01*
G01X83108D02*
X82858Y169958D01*
X82650Y170167D01*
X82567Y170417D01*
X82650Y170667D01*
X82858Y170875D01*
X83233Y171000D01*
X83608Y170958D01*
X83983Y170792D01*
G01X81217Y169000D02*
X80967Y168708D01*
X80633Y168542D01*
X80258Y168500D01*
X79925Y168542D01*
X79592Y168750D01*
X79383Y169000D01*
X79342Y169250D01*
X79425Y169542D01*
X79717Y169750D01*
X80008Y169833D01*
X80383D01*
G01X80008D02*
X79758Y169958D01*
X79550Y170167D01*
X79467Y170417D01*
X79550Y170667D01*
X79758Y170875D01*
X80133Y171000D01*
X80508Y170958D01*
X80883Y170792D01*
G01X85000Y187467D02*
X87500D01*
Y188467D01*
X87375Y188800D01*
X87083Y189050D01*
X86750Y189133D01*
X86417Y189050D01*
X86167Y188842D01*
X86042Y188467D01*
Y187467D01*
G01X85000Y190567D02*
X87500D01*
Y191608D01*
X87375Y191942D01*
X87208Y192150D01*
X86875Y192233D01*
X86542Y192150D01*
X86333Y191900D01*
X86208Y191608D01*
Y190567D01*
G01Y191608D02*
X85000Y192233D01*
G01Y194500D02*
X87500D01*
X87000Y194000D01*
G01X85000D02*
Y195000D01*
G01Y197517D02*
X85542Y197600D01*
X86000Y197725D01*
X86417Y197892D01*
X86875Y198100D01*
X87500Y198433D01*
Y196767D01*
G01X85292Y199992D02*
X85083Y200283D01*
X85000Y200617D01*
X85083Y200950D01*
X85333Y201242D01*
X85708Y201450D01*
X86083Y201533D01*
X86542D01*
X86917Y201450D01*
X87250Y201242D01*
X87417Y200992D01*
X87500Y200700D01*
X87417Y200367D01*
X87250Y200117D01*
X87000Y199950D01*
X86667Y199867D01*
X86375Y199950D01*
X86083Y200158D01*
X85917Y200408D01*
X85875Y200700D01*
X85958Y201033D01*
X86167Y201283D01*
X86542Y201533D01*
G01X89000Y187467D02*
X91500D01*
Y188467D01*
X91375Y188800D01*
X91083Y189050D01*
X90750Y189133D01*
X90417Y189050D01*
X90167Y188842D01*
X90042Y188467D01*
Y187467D01*
G01X91292Y192317D02*
X91417Y192067D01*
X91500Y191775D01*
Y191442D01*
X91375Y191067D01*
X91167Y190775D01*
X90917Y190567D01*
X90500Y190400D01*
X90125Y190358D01*
X89750Y190442D01*
X89500Y190567D01*
X89250Y190817D01*
X89083Y191108D01*
X89000Y191400D01*
Y191692D01*
X89083Y191983D01*
X89208Y192233D01*
X89375Y192442D01*
G01X89000Y194500D02*
X91500D01*
X91000Y194000D01*
G01X89000D02*
Y195000D01*
G01X91083Y196808D02*
X91333Y197058D01*
X91458Y197350D01*
X91500Y197683D01*
X91417Y198100D01*
X91208Y198392D01*
X90958Y198475D01*
X90708Y198433D01*
X90500Y198267D01*
X90083Y197433D01*
X89792Y197058D01*
X89375Y196808D01*
X89000Y196725D01*
Y198475D01*
G01Y200700D02*
X89042Y200992D01*
X89167Y201325D01*
X89375Y201533D01*
X89667Y201617D01*
X89958Y201533D01*
X90208Y201283D01*
X90333Y200908D01*
Y200492D01*
X90417Y200242D01*
X90625Y200033D01*
X90917Y199950D01*
X91208Y200075D01*
X91417Y200367D01*
X91500Y200700D01*
X91417Y201033D01*
X91208Y201325D01*
X90917Y201450D01*
X90625Y201367D01*
X90417Y201158D01*
X90333Y200908D01*
Y200492D01*
X90208Y200117D01*
X89958Y199867D01*
X89667Y199783D01*
X89375Y199867D01*
X89167Y200075D01*
X89042Y200408D01*
X89000Y200700D01*
G01X92000Y234567D02*
X94500D01*
Y235567D01*
X94375Y235900D01*
X94083Y236150D01*
X93750Y236233D01*
X93417Y236150D01*
X93167Y235942D01*
X93042Y235567D01*
Y234567D01*
G01X94292Y239417D02*
X94417Y239167D01*
X94500Y238875D01*
Y238542D01*
X94375Y238167D01*
X94167Y237875D01*
X93917Y237667D01*
X93500Y237500D01*
X93125Y237458D01*
X92750Y237542D01*
X92500Y237667D01*
X92250Y237917D01*
X92083Y238208D01*
X92000Y238500D01*
Y238792D01*
X92083Y239083D01*
X92208Y239333D01*
X92375Y239542D01*
G01Y240683D02*
X92167Y240933D01*
X92042Y241225D01*
X92000Y241600D01*
X92083Y241975D01*
X92250Y242267D01*
X92542Y242475D01*
X92875Y242517D01*
X93208Y242433D01*
X93417Y242225D01*
X93583Y241933D01*
X93625Y241642D01*
X93583Y241350D01*
X93417Y240975D01*
X94500Y241100D01*
Y242225D01*
G01X91000Y245517D02*
X93500D01*
Y246517D01*
X93375Y246850D01*
X93083Y247100D01*
X92750Y247183D01*
X92417Y247100D01*
X92167Y246892D01*
X92042Y246517D01*
Y245517D01*
G01X91000Y248617D02*
X93500D01*
Y249658D01*
X93375Y249992D01*
X93208Y250200D01*
X92875Y250283D01*
X92542Y250200D01*
X92333Y249950D01*
X92208Y249658D01*
Y248617D01*
G01Y249658D02*
X91000Y250283D01*
G01X93083Y251758D02*
X93333Y252008D01*
X93458Y252300D01*
X93500Y252633D01*
X93417Y253050D01*
X93208Y253342D01*
X92958Y253425D01*
X92708Y253383D01*
X92500Y253217D01*
X92083Y252383D01*
X91792Y252008D01*
X91375Y251758D01*
X91000Y251675D01*
Y253425D01*
G01X93083Y254858D02*
X93333Y255108D01*
X93458Y255400D01*
X93500Y255733D01*
X93417Y256150D01*
X93208Y256442D01*
X92958Y256525D01*
X92708Y256483D01*
X92500Y256317D01*
X92083Y255483D01*
X91792Y255108D01*
X91375Y254858D01*
X91000Y254775D01*
Y256525D01*
G01X95000Y245517D02*
X97500D01*
Y246517D01*
X97375Y246850D01*
X97083Y247100D01*
X96750Y247183D01*
X96417Y247100D01*
X96167Y246892D01*
X96042Y246517D01*
Y245517D01*
G01X95000Y248617D02*
X97500D01*
Y249658D01*
X97375Y249992D01*
X97208Y250200D01*
X96875Y250283D01*
X96542Y250200D01*
X96333Y249950D01*
X96208Y249658D01*
Y248617D01*
G01Y249658D02*
X95000Y250283D01*
G01X97083Y251758D02*
X97333Y252008D01*
X97458Y252300D01*
X97500Y252633D01*
X97417Y253050D01*
X97208Y253342D01*
X96958Y253425D01*
X96708Y253383D01*
X96500Y253217D01*
X96083Y252383D01*
X95792Y252008D01*
X95375Y251758D01*
X95000Y251675D01*
Y253425D01*
G01Y255650D02*
X97500D01*
X97000Y255150D01*
G01X95000D02*
Y256150D01*
G01X110233Y44292D02*
X110483Y44417D01*
X110775Y44500D01*
X111108D01*
X111483Y44375D01*
X111775Y44167D01*
X111983Y43917D01*
X112150Y43500D01*
X112192Y43125D01*
X112108Y42750D01*
X111983Y42500D01*
X111733Y42250D01*
X111442Y42083D01*
X111150Y42000D01*
X110858D01*
X110567Y42083D01*
X110317Y42208D01*
X110108Y42375D01*
G01X108842Y44083D02*
X108592Y44333D01*
X108300Y44458D01*
X107967Y44500D01*
X107550Y44417D01*
X107258Y44208D01*
X107175Y43958D01*
X107217Y43708D01*
X107383Y43500D01*
X108217Y43083D01*
X108592Y42792D01*
X108842Y42375D01*
X108925Y42000D01*
X107175D01*
G01X105033D02*
X104950Y42542D01*
X104825Y43000D01*
X104658Y43417D01*
X104450Y43875D01*
X104117Y44500D01*
X105783D01*
G01X101850Y42000D02*
Y44500D01*
X102350Y44000D01*
G01Y42000D02*
X101350D01*
G01X102000Y72017D02*
X104500D01*
Y73058D01*
X104375Y73392D01*
X104208Y73600D01*
X103875Y73683D01*
X103542Y73600D01*
X103333Y73350D01*
X103208Y73058D01*
Y72017D01*
G01Y73058D02*
X102000Y73683D01*
G01Y76450D02*
X104500D01*
X102708Y74908D01*
Y76992D01*
G01X104083Y78258D02*
X104333Y78508D01*
X104458Y78800D01*
X104500Y79133D01*
X104417Y79550D01*
X104208Y79842D01*
X103958Y79925D01*
X103708Y79883D01*
X103500Y79717D01*
X103083Y78883D01*
X102792Y78508D01*
X102375Y78258D01*
X102000Y78175D01*
Y79925D01*
G01Y82067D02*
X102542Y82150D01*
X103000Y82275D01*
X103417Y82442D01*
X103875Y82650D01*
X104500Y82983D01*
Y81317D01*
G01X110000Y69017D02*
X112500D01*
Y70058D01*
X112375Y70392D01*
X112208Y70600D01*
X111875Y70683D01*
X111542Y70600D01*
X111333Y70350D01*
X111208Y70058D01*
Y69017D01*
G01Y70058D02*
X110000Y70683D01*
G01Y73450D02*
X112500D01*
X110708Y71908D01*
Y73992D01*
G01X112083Y75258D02*
X112333Y75508D01*
X112458Y75800D01*
X112500Y76133D01*
X112417Y76550D01*
X112208Y76842D01*
X111958Y76925D01*
X111708Y76883D01*
X111500Y76717D01*
X111083Y75883D01*
X110792Y75508D01*
X110375Y75258D01*
X110000Y75175D01*
Y76925D01*
G01X111042Y78358D02*
X111333Y78650D01*
X111500Y78900D01*
X111583Y79233D01*
X111500Y79525D01*
X111333Y79733D01*
X111083Y79900D01*
X110792Y79942D01*
X110542Y79900D01*
X110292Y79733D01*
X110083Y79483D01*
X110000Y79192D01*
X110083Y78858D01*
X110333Y78567D01*
X110708Y78400D01*
X111125Y78358D01*
X111667Y78442D01*
X111958Y78567D01*
X112250Y78775D01*
X112458Y79067D01*
X112500Y79358D01*
X112417Y79650D01*
X112208Y79858D01*
G01X98000Y72017D02*
X100500D01*
Y73058D01*
X100375Y73392D01*
X100208Y73600D01*
X99875Y73683D01*
X99542Y73600D01*
X99333Y73350D01*
X99208Y73058D01*
Y72017D01*
G01Y73058D02*
X98000Y73683D01*
G01Y76450D02*
X100500D01*
X98708Y74908D01*
Y76992D01*
G01X100083Y78258D02*
X100333Y78508D01*
X100458Y78800D01*
X100500Y79133D01*
X100417Y79550D01*
X100208Y79842D01*
X99958Y79925D01*
X99708Y79883D01*
X99500Y79717D01*
X99083Y78883D01*
X98792Y78508D01*
X98375Y78258D01*
X98000Y78175D01*
Y79925D01*
G01Y82150D02*
X98042Y82442D01*
X98167Y82775D01*
X98375Y82983D01*
X98667Y83067D01*
X98958Y82983D01*
X99208Y82733D01*
X99333Y82358D01*
Y81942D01*
X99417Y81692D01*
X99625Y81483D01*
X99917Y81400D01*
X100208Y81525D01*
X100417Y81817D01*
X100500Y82150D01*
X100417Y82483D01*
X100208Y82775D01*
X99917Y82900D01*
X99625Y82817D01*
X99417Y82608D01*
X99333Y82358D01*
Y81942D01*
X99208Y81567D01*
X98958Y81317D01*
X98667Y81233D01*
X98375Y81317D01*
X98167Y81525D01*
X98042Y81858D01*
X98000Y82150D01*
G01X109500Y86017D02*
X112000D01*
Y87058D01*
X111875Y87392D01*
X111708Y87600D01*
X111375Y87683D01*
X111042Y87600D01*
X110833Y87350D01*
X110708Y87058D01*
Y86017D01*
G01Y87058D02*
X109500Y87683D01*
G01Y90450D02*
X112000D01*
X110208Y88908D01*
Y90992D01*
G01X111583Y92258D02*
X111833Y92508D01*
X111958Y92800D01*
X112000Y93133D01*
X111917Y93550D01*
X111708Y93842D01*
X111458Y93925D01*
X111208Y93883D01*
X111000Y93717D01*
X110583Y92883D01*
X110292Y92508D01*
X109875Y92258D01*
X109500Y92175D01*
Y93925D01*
G01X112000Y96150D02*
X111917Y95817D01*
X111708Y95567D01*
X111458Y95400D01*
X111125Y95275D01*
X110750Y95233D01*
X110375Y95275D01*
X110042Y95400D01*
X109792Y95567D01*
X109583Y95817D01*
X109500Y96150D01*
X109583Y96483D01*
X109792Y96733D01*
X110042Y96900D01*
X110375Y97025D01*
X110750Y97067D01*
X111125Y97025D01*
X111458Y96900D01*
X111708Y96733D01*
X111917Y96483D01*
X112000Y96150D01*
G01X97000Y84517D02*
X99500D01*
Y85558D01*
X99375Y85892D01*
X99208Y86100D01*
X98875Y86183D01*
X98542Y86100D01*
X98333Y85850D01*
X98208Y85558D01*
Y84517D01*
G01Y85558D02*
X97000Y86183D01*
G01X97500Y87533D02*
X97208Y87783D01*
X97042Y88117D01*
X97000Y88492D01*
X97042Y88825D01*
X97250Y89158D01*
X97500Y89367D01*
X97750Y89408D01*
X98042Y89325D01*
X98250Y89033D01*
X98333Y88742D01*
Y88367D01*
G01Y88742D02*
X98458Y88992D01*
X98667Y89200D01*
X98917Y89283D01*
X99167Y89200D01*
X99375Y88992D01*
X99500Y88617D01*
X99458Y88242D01*
X99292Y87867D01*
G01X98042Y90758D02*
X98333Y91050D01*
X98500Y91300D01*
X98583Y91633D01*
X98500Y91925D01*
X98333Y92133D01*
X98083Y92300D01*
X97792Y92342D01*
X97542Y92300D01*
X97292Y92133D01*
X97083Y91883D01*
X97000Y91592D01*
X97083Y91258D01*
X97333Y90967D01*
X97708Y90800D01*
X98125Y90758D01*
X98667Y90842D01*
X98958Y90967D01*
X99250Y91175D01*
X99458Y91467D01*
X99500Y91758D01*
X99417Y92050D01*
X99208Y92258D01*
G01X97000Y94650D02*
X97042Y94942D01*
X97167Y95275D01*
X97375Y95483D01*
X97667Y95567D01*
X97958Y95483D01*
X98208Y95233D01*
X98333Y94858D01*
Y94442D01*
X98417Y94192D01*
X98625Y93983D01*
X98917Y93900D01*
X99208Y94025D01*
X99417Y94317D01*
X99500Y94650D01*
X99417Y94983D01*
X99208Y95275D01*
X98917Y95400D01*
X98625Y95317D01*
X98417Y95108D01*
X98333Y94858D01*
Y94442D01*
X98208Y94067D01*
X97958Y93817D01*
X97667Y93733D01*
X97375Y93817D01*
X97167Y94025D01*
X97042Y94358D01*
X97000Y94650D01*
G01X105000Y86517D02*
X107500D01*
Y87558D01*
X107375Y87892D01*
X107208Y88100D01*
X106875Y88183D01*
X106542Y88100D01*
X106333Y87850D01*
X106208Y87558D01*
Y86517D01*
G01Y87558D02*
X105000Y88183D01*
G01X105500Y89533D02*
X105208Y89783D01*
X105042Y90117D01*
X105000Y90492D01*
X105042Y90825D01*
X105250Y91158D01*
X105500Y91367D01*
X105750Y91408D01*
X106042Y91325D01*
X106250Y91033D01*
X106333Y90742D01*
Y90367D01*
G01Y90742D02*
X106458Y90992D01*
X106667Y91200D01*
X106917Y91283D01*
X107167Y91200D01*
X107375Y90992D01*
X107500Y90617D01*
X107458Y90242D01*
X107292Y89867D01*
G01X105375Y92633D02*
X105167Y92883D01*
X105042Y93175D01*
X105000Y93550D01*
X105083Y93925D01*
X105250Y94217D01*
X105542Y94425D01*
X105875Y94467D01*
X106208Y94383D01*
X106417Y94175D01*
X106583Y93883D01*
X106625Y93592D01*
X106583Y93300D01*
X106417Y92925D01*
X107500Y93050D01*
Y94175D01*
G01X105000Y96650D02*
X107500D01*
X107000Y96150D01*
G01X105000D02*
Y97150D01*
G01X101000Y86517D02*
X103500D01*
Y87558D01*
X103375Y87892D01*
X103208Y88100D01*
X102875Y88183D01*
X102542Y88100D01*
X102333Y87850D01*
X102208Y87558D01*
Y86517D01*
G01Y87558D02*
X101000Y88183D01*
G01X101500Y89533D02*
X101208Y89783D01*
X101042Y90117D01*
X101000Y90492D01*
X101042Y90825D01*
X101250Y91158D01*
X101500Y91367D01*
X101750Y91408D01*
X102042Y91325D01*
X102250Y91033D01*
X102333Y90742D01*
Y90367D01*
G01Y90742D02*
X102458Y90992D01*
X102667Y91200D01*
X102917Y91283D01*
X103167Y91200D01*
X103375Y90992D01*
X103500Y90617D01*
X103458Y90242D01*
X103292Y89867D01*
G01X101375Y92633D02*
X101167Y92883D01*
X101042Y93175D01*
X101000Y93550D01*
X101083Y93925D01*
X101250Y94217D01*
X101542Y94425D01*
X101875Y94467D01*
X102208Y94383D01*
X102417Y94175D01*
X102583Y93883D01*
X102625Y93592D01*
X102583Y93300D01*
X102417Y92925D01*
X103500Y93050D01*
Y94175D01*
G01X101375Y95733D02*
X101167Y95983D01*
X101042Y96275D01*
X101000Y96650D01*
X101083Y97025D01*
X101250Y97317D01*
X101542Y97525D01*
X101875Y97567D01*
X102208Y97483D01*
X102417Y97275D01*
X102583Y96983D01*
X102625Y96692D01*
X102583Y96400D01*
X102417Y96025D01*
X103500Y96150D01*
Y97275D01*
G01X96500Y120017D02*
X99000D01*
Y121017D01*
X98875Y121350D01*
X98583Y121600D01*
X98250Y121683D01*
X97917Y121600D01*
X97667Y121392D01*
X97542Y121017D01*
Y120017D01*
G01X98792Y124867D02*
X98917Y124617D01*
X99000Y124325D01*
Y123992D01*
X98875Y123617D01*
X98667Y123325D01*
X98417Y123117D01*
X98000Y122950D01*
X97625Y122908D01*
X97250Y122992D01*
X97000Y123117D01*
X96750Y123367D01*
X96583Y123658D01*
X96500Y123950D01*
Y124242D01*
X96583Y124533D01*
X96708Y124783D01*
X96875Y124992D01*
G01X96500Y127550D02*
X99000D01*
X97208Y126008D01*
Y128092D01*
G01X98583Y129358D02*
X98833Y129608D01*
X98958Y129900D01*
X99000Y130233D01*
X98917Y130650D01*
X98708Y130942D01*
X98458Y131025D01*
X98208Y130983D01*
X98000Y130817D01*
X97583Y129983D01*
X97292Y129608D01*
X96875Y129358D01*
X96500Y129275D01*
Y131025D01*
G01X122533Y149500D02*
Y152000D01*
X121533D01*
X121200Y151875D01*
X120950Y151583D01*
X120867Y151250D01*
X120950Y150917D01*
X121158Y150667D01*
X121533Y150542D01*
X122533D01*
G01X119433Y149500D02*
Y152000D01*
X118392D01*
X118058Y151875D01*
X117850Y151708D01*
X117767Y151375D01*
X117850Y151042D01*
X118100Y150833D01*
X118392Y150708D01*
X119433D01*
G01X118392D02*
X117767Y149500D01*
G01X115500D02*
Y152000D01*
X116000Y151500D01*
G01Y149500D02*
X115000D01*
G01X112400D02*
X112108Y149542D01*
X111775Y149667D01*
X111567Y149875D01*
X111483Y150167D01*
X111567Y150458D01*
X111817Y150708D01*
X112192Y150833D01*
X112608D01*
X112858Y150917D01*
X113067Y151125D01*
X113150Y151417D01*
X113025Y151708D01*
X112733Y151917D01*
X112400Y152000D01*
X112067Y151917D01*
X111775Y151708D01*
X111650Y151417D01*
X111733Y151125D01*
X111942Y150917D01*
X112192Y150833D01*
X112608D01*
X112983Y150708D01*
X113233Y150458D01*
X113317Y150167D01*
X113233Y149875D01*
X113025Y149667D01*
X112692Y149542D01*
X112400Y149500D01*
G01X109383D02*
X109300Y150042D01*
X109175Y150500D01*
X109008Y150917D01*
X108800Y151375D01*
X108467Y152000D01*
X110133D01*
G01X98500Y147967D02*
X101000D01*
Y148967D01*
X100875Y149300D01*
X100583Y149550D01*
X100250Y149633D01*
X99917Y149550D01*
X99667Y149342D01*
X99542Y148967D01*
Y147967D01*
G01X100792Y152817D02*
X100917Y152567D01*
X101000Y152275D01*
Y151942D01*
X100875Y151567D01*
X100667Y151275D01*
X100417Y151067D01*
X100000Y150900D01*
X99625Y150858D01*
X99250Y150942D01*
X99000Y151067D01*
X98750Y151317D01*
X98583Y151608D01*
X98500Y151900D01*
Y152192D01*
X98583Y152483D01*
X98708Y152733D01*
X98875Y152942D01*
G01X98500Y155000D02*
X101000D01*
X100500Y154500D01*
G01X98500D02*
Y155500D01*
G01X99000Y157183D02*
X98708Y157433D01*
X98542Y157767D01*
X98500Y158142D01*
X98542Y158475D01*
X98750Y158808D01*
X99000Y159017D01*
X99250Y159058D01*
X99542Y158975D01*
X99750Y158683D01*
X99833Y158392D01*
Y158017D01*
G01Y158392D02*
X99958Y158642D01*
X100167Y158850D01*
X100417Y158933D01*
X100667Y158850D01*
X100875Y158642D01*
X101000Y158267D01*
X100958Y157892D01*
X100792Y157517D01*
G01X98500Y161700D02*
X101000D01*
X99208Y160158D01*
Y162242D01*
G01X103000Y147967D02*
X105500D01*
Y148967D01*
X105375Y149300D01*
X105083Y149550D01*
X104750Y149633D01*
X104417Y149550D01*
X104167Y149342D01*
X104042Y148967D01*
Y147967D01*
G01X105292Y152817D02*
X105417Y152567D01*
X105500Y152275D01*
Y151942D01*
X105375Y151567D01*
X105167Y151275D01*
X104917Y151067D01*
X104500Y150900D01*
X104125Y150858D01*
X103750Y150942D01*
X103500Y151067D01*
X103250Y151317D01*
X103083Y151608D01*
X103000Y151900D01*
Y152192D01*
X103083Y152483D01*
X103208Y152733D01*
X103375Y152942D01*
G01X103000Y155000D02*
X105500D01*
X105000Y154500D01*
G01X103000D02*
Y155500D01*
G01Y158600D02*
X105500D01*
X103708Y157058D01*
Y159142D01*
G01X103000Y161200D02*
X105500D01*
X105000Y160700D01*
G01X103000D02*
Y161700D01*
G01X122533Y157000D02*
Y159500D01*
X121533D01*
X121200Y159375D01*
X120950Y159083D01*
X120867Y158750D01*
X120950Y158417D01*
X121158Y158167D01*
X121533Y158042D01*
X122533D01*
G01X117683Y159292D02*
X117933Y159417D01*
X118225Y159500D01*
X118558D01*
X118933Y159375D01*
X119225Y159167D01*
X119433Y158917D01*
X119600Y158500D01*
X119642Y158125D01*
X119558Y157750D01*
X119433Y157500D01*
X119183Y157250D01*
X118892Y157083D01*
X118600Y157000D01*
X118308D01*
X118017Y157083D01*
X117767Y157208D01*
X117558Y157375D01*
G01X115500Y157000D02*
Y159500D01*
X116000Y159000D01*
G01Y157000D02*
X115000D01*
G01X113317Y157500D02*
X113067Y157208D01*
X112733Y157042D01*
X112358Y157000D01*
X112025Y157042D01*
X111692Y157250D01*
X111483Y157500D01*
X111442Y157750D01*
X111525Y158042D01*
X111817Y158250D01*
X112108Y158333D01*
X112483D01*
G01X112108D02*
X111858Y158458D01*
X111650Y158667D01*
X111567Y158917D01*
X111650Y159167D01*
X111858Y159375D01*
X112233Y159500D01*
X112608Y159458D01*
X112983Y159292D01*
G01X109300Y157000D02*
X109008Y157042D01*
X108675Y157167D01*
X108467Y157375D01*
X108383Y157667D01*
X108467Y157958D01*
X108717Y158208D01*
X109092Y158333D01*
X109508D01*
X109758Y158417D01*
X109967Y158625D01*
X110050Y158917D01*
X109925Y159208D01*
X109633Y159417D01*
X109300Y159500D01*
X108967Y159417D01*
X108675Y159208D01*
X108550Y158917D01*
X108633Y158625D01*
X108842Y158417D01*
X109092Y158333D01*
X109508D01*
X109883Y158208D01*
X110133Y157958D01*
X110217Y157667D01*
X110133Y157375D01*
X109925Y157167D01*
X109592Y157042D01*
X109300Y157000D01*
G01X110983Y204000D02*
Y206500D01*
X109983D01*
X109650Y206375D01*
X109400Y206083D01*
X109317Y205750D01*
X109400Y205417D01*
X109608Y205167D01*
X109983Y205042D01*
X110983D01*
G01X107967Y206500D02*
Y204708D01*
X107800Y204333D01*
X107467Y204083D01*
X107050Y204000D01*
X106633Y204083D01*
X106300Y204333D01*
X106133Y204708D01*
Y206500D01*
G01X103950Y204000D02*
Y206500D01*
X104450Y206000D01*
G01Y204000D02*
X103450D01*
G01X100350D02*
Y206500D01*
X101892Y204708D01*
X99808D01*
G01X98500Y216517D02*
X101000D01*
Y217517D01*
X100875Y217850D01*
X100583Y218100D01*
X100250Y218183D01*
X99917Y218100D01*
X99667Y217892D01*
X99542Y217517D01*
Y216517D01*
G01X100792Y221367D02*
X100917Y221117D01*
X101000Y220825D01*
Y220492D01*
X100875Y220117D01*
X100667Y219825D01*
X100417Y219617D01*
X100000Y219450D01*
X99625Y219408D01*
X99250Y219492D01*
X99000Y219617D01*
X98750Y219867D01*
X98583Y220158D01*
X98500Y220450D01*
Y220742D01*
X98583Y221033D01*
X98708Y221283D01*
X98875Y221492D01*
G01X99542Y222758D02*
X99833Y223050D01*
X100000Y223300D01*
X100083Y223633D01*
X100000Y223925D01*
X99833Y224133D01*
X99583Y224300D01*
X99292Y224342D01*
X99042Y224300D01*
X98792Y224133D01*
X98583Y223883D01*
X98500Y223592D01*
X98583Y223258D01*
X98833Y222967D01*
X99208Y222800D01*
X99625Y222758D01*
X100167Y222842D01*
X100458Y222967D01*
X100750Y223175D01*
X100958Y223467D01*
X101000Y223758D01*
X100917Y224050D01*
X100708Y224258D01*
G01X98875Y225733D02*
X98667Y225983D01*
X98542Y226275D01*
X98500Y226650D01*
X98583Y227025D01*
X98750Y227317D01*
X99042Y227525D01*
X99375Y227567D01*
X99708Y227483D01*
X99917Y227275D01*
X100083Y226983D01*
X100125Y226692D01*
X100083Y226400D01*
X99917Y226025D01*
X101000Y226150D01*
Y227275D01*
G01X102300Y216517D02*
X104800D01*
Y217517D01*
X104675Y217850D01*
X104383Y218100D01*
X104050Y218183D01*
X103717Y218100D01*
X103467Y217892D01*
X103342Y217517D01*
Y216517D01*
G01X102300Y219617D02*
X104800D01*
Y220658D01*
X104675Y220992D01*
X104508Y221200D01*
X104175Y221283D01*
X103842Y221200D01*
X103633Y220950D01*
X103508Y220658D01*
Y219617D01*
G01Y220658D02*
X102300Y221283D01*
G01X103342Y222758D02*
X103633Y223050D01*
X103800Y223300D01*
X103883Y223633D01*
X103800Y223925D01*
X103633Y224133D01*
X103383Y224300D01*
X103092Y224342D01*
X102842Y224300D01*
X102592Y224133D01*
X102383Y223883D01*
X102300Y223592D01*
X102383Y223258D01*
X102633Y222967D01*
X103008Y222800D01*
X103425Y222758D01*
X103967Y222842D01*
X104258Y222967D01*
X104550Y223175D01*
X104758Y223467D01*
X104800Y223758D01*
X104717Y224050D01*
X104508Y224258D01*
G01X103342Y225858D02*
X103633Y226150D01*
X103800Y226400D01*
X103883Y226733D01*
X103800Y227025D01*
X103633Y227233D01*
X103383Y227400D01*
X103092Y227442D01*
X102842Y227400D01*
X102592Y227233D01*
X102383Y226983D01*
X102300Y226692D01*
X102383Y226358D01*
X102633Y226067D01*
X103008Y225900D01*
X103425Y225858D01*
X103967Y225942D01*
X104258Y226067D01*
X104550Y226275D01*
X104758Y226567D01*
X104800Y226858D01*
X104717Y227150D01*
X104508Y227358D01*
G01X110000Y234067D02*
X112500D01*
Y235067D01*
X112375Y235400D01*
X112083Y235650D01*
X111750Y235733D01*
X111417Y235650D01*
X111167Y235442D01*
X111042Y235067D01*
Y234067D01*
G01X110000Y237167D02*
X112500D01*
Y238208D01*
X112375Y238542D01*
X112208Y238750D01*
X111875Y238833D01*
X111542Y238750D01*
X111333Y238500D01*
X111208Y238208D01*
Y237167D01*
G01Y238208D02*
X110000Y238833D01*
G01X112083Y240308D02*
X112333Y240558D01*
X112458Y240850D01*
X112500Y241183D01*
X112417Y241600D01*
X112208Y241892D01*
X111958Y241975D01*
X111708Y241933D01*
X111500Y241767D01*
X111083Y240933D01*
X110792Y240558D01*
X110375Y240308D01*
X110000Y240225D01*
Y241975D01*
G01X107733Y239000D02*
Y241500D01*
X106733D01*
X106400Y241375D01*
X106150Y241083D01*
X106067Y240750D01*
X106150Y240417D01*
X106358Y240167D01*
X106733Y240042D01*
X107733D01*
G01X102883Y241292D02*
X103133Y241417D01*
X103425Y241500D01*
X103758D01*
X104133Y241375D01*
X104425Y241167D01*
X104633Y240917D01*
X104800Y240500D01*
X104842Y240125D01*
X104758Y239750D01*
X104633Y239500D01*
X104383Y239250D01*
X104092Y239083D01*
X103800Y239000D01*
X103508D01*
X103217Y239083D01*
X102967Y239208D01*
X102758Y239375D01*
G01X100700Y239000D02*
Y241500D01*
X101200Y241000D01*
G01Y239000D02*
X100200D01*
G01X107483Y235000D02*
Y237500D01*
X106483D01*
X106150Y237375D01*
X105900Y237083D01*
X105817Y236750D01*
X105900Y236417D01*
X106108Y236167D01*
X106483Y236042D01*
X107483D01*
G01X104383Y235000D02*
Y237500D01*
X103342D01*
X103008Y237375D01*
X102800Y237208D01*
X102717Y236875D01*
X102800Y236542D01*
X103050Y236333D01*
X103342Y236208D01*
X104383D01*
G01X103342D02*
X102717Y235000D01*
G01X100450D02*
Y237500D01*
X100950Y237000D01*
G01Y235000D02*
X99950D01*
G01X96850D02*
Y237500D01*
X98392Y235708D01*
X96308D01*
G01X99000Y245517D02*
X101500D01*
Y246517D01*
X101375Y246850D01*
X101083Y247100D01*
X100750Y247183D01*
X100417Y247100D01*
X100167Y246892D01*
X100042Y246517D01*
Y245517D01*
G01X99000Y248617D02*
X101500D01*
Y249658D01*
X101375Y249992D01*
X101208Y250200D01*
X100875Y250283D01*
X100542Y250200D01*
X100333Y249950D01*
X100208Y249658D01*
Y248617D01*
G01Y249658D02*
X99000Y250283D01*
G01X101083Y251758D02*
X101333Y252008D01*
X101458Y252300D01*
X101500Y252633D01*
X101417Y253050D01*
X101208Y253342D01*
X100958Y253425D01*
X100708Y253383D01*
X100500Y253217D01*
X100083Y252383D01*
X99792Y252008D01*
X99375Y251758D01*
X99000Y251675D01*
Y253425D01*
G01X100042Y254858D02*
X100333Y255150D01*
X100500Y255400D01*
X100583Y255733D01*
X100500Y256025D01*
X100333Y256233D01*
X100083Y256400D01*
X99792Y256442D01*
X99542Y256400D01*
X99292Y256233D01*
X99083Y255983D01*
X99000Y255692D01*
X99083Y255358D01*
X99333Y255067D01*
X99708Y254900D01*
X100125Y254858D01*
X100667Y254942D01*
X100958Y255067D01*
X101250Y255275D01*
X101458Y255567D01*
X101500Y255858D01*
X101417Y256150D01*
X101208Y256358D01*
G01X123233Y44292D02*
X123483Y44417D01*
X123775Y44500D01*
X124108D01*
X124483Y44375D01*
X124775Y44167D01*
X124983Y43917D01*
X125150Y43500D01*
X125192Y43125D01*
X125108Y42750D01*
X124983Y42500D01*
X124733Y42250D01*
X124442Y42083D01*
X124150Y42000D01*
X123858D01*
X123567Y42083D01*
X123317Y42208D01*
X123108Y42375D01*
G01X121842Y44083D02*
X121592Y44333D01*
X121300Y44458D01*
X120967Y44500D01*
X120550Y44417D01*
X120258Y44208D01*
X120175Y43958D01*
X120217Y43708D01*
X120383Y43500D01*
X121217Y43083D01*
X121592Y42792D01*
X121842Y42375D01*
X121925Y42000D01*
X120175D01*
G01X118033D02*
X117950Y42542D01*
X117825Y43000D01*
X117658Y43417D01*
X117450Y43875D01*
X117117Y44500D01*
X118783D01*
G01X114850D02*
X115183Y44417D01*
X115433Y44208D01*
X115600Y43958D01*
X115725Y43625D01*
X115767Y43250D01*
X115725Y42875D01*
X115600Y42542D01*
X115433Y42292D01*
X115183Y42083D01*
X114850Y42000D01*
X114517Y42083D01*
X114267Y42292D01*
X114100Y42542D01*
X113975Y42875D01*
X113933Y43250D01*
X113975Y43625D01*
X114100Y43958D01*
X114267Y44208D01*
X114517Y44417D01*
X114850Y44500D01*
G01X149500Y56500D02*
X114500D01*
Y66500D01*
X112000Y64000D01*
X117000D01*
X114500Y66500D01*
G01X130983Y58500D02*
Y61000D01*
X129942D01*
X129608Y60875D01*
X129400Y60708D01*
X129317Y60375D01*
X129400Y60042D01*
X129650Y59833D01*
X129942Y59708D01*
X130983D01*
G01X129942D02*
X129317Y58500D01*
G01X126550D02*
Y61000D01*
X128092Y59208D01*
X126008D01*
G01X124867Y59000D02*
X124617Y58708D01*
X124283Y58542D01*
X123908Y58500D01*
X123575Y58542D01*
X123242Y58750D01*
X123033Y59000D01*
X122992Y59250D01*
X123075Y59542D01*
X123367Y59750D01*
X123658Y59833D01*
X124033D01*
G01X123658D02*
X123408Y59958D01*
X123200Y60167D01*
X123117Y60417D01*
X123200Y60667D01*
X123408Y60875D01*
X123783Y61000D01*
X124158Y60958D01*
X124533Y60792D01*
G01X121642Y59542D02*
X121350Y59833D01*
X121100Y60000D01*
X120767Y60083D01*
X120475Y60000D01*
X120267Y59833D01*
X120100Y59583D01*
X120058Y59292D01*
X120100Y59042D01*
X120267Y58792D01*
X120517Y58583D01*
X120808Y58500D01*
X121142Y58583D01*
X121433Y58833D01*
X121600Y59208D01*
X121642Y59625D01*
X121558Y60167D01*
X121433Y60458D01*
X121225Y60750D01*
X120933Y60958D01*
X120642Y61000D01*
X120350Y60917D01*
X120142Y60708D01*
G01X130983Y62500D02*
Y65000D01*
X129942D01*
X129608Y64875D01*
X129400Y64708D01*
X129317Y64375D01*
X129400Y64042D01*
X129650Y63833D01*
X129942Y63708D01*
X130983D01*
G01X129942D02*
X129317Y62500D01*
G01X126550D02*
Y65000D01*
X128092Y63208D01*
X126008D01*
G01X124867Y63000D02*
X124617Y62708D01*
X124283Y62542D01*
X123908Y62500D01*
X123575Y62542D01*
X123242Y62750D01*
X123033Y63000D01*
X122992Y63250D01*
X123075Y63542D01*
X123367Y63750D01*
X123658Y63833D01*
X124033D01*
G01X123658D02*
X123408Y63958D01*
X123200Y64167D01*
X123117Y64417D01*
X123200Y64667D01*
X123408Y64875D01*
X123783Y65000D01*
X124158Y64958D01*
X124533Y64792D01*
G01X121767Y62875D02*
X121517Y62667D01*
X121225Y62542D01*
X120850Y62500D01*
X120475Y62583D01*
X120183Y62750D01*
X119975Y63042D01*
X119933Y63375D01*
X120017Y63708D01*
X120225Y63917D01*
X120517Y64083D01*
X120808Y64125D01*
X121100Y64083D01*
X121475Y63917D01*
X121350Y65000D01*
X120225D01*
G01X114000Y69017D02*
X116500D01*
Y70058D01*
X116375Y70392D01*
X116208Y70600D01*
X115875Y70683D01*
X115542Y70600D01*
X115333Y70350D01*
X115208Y70058D01*
Y69017D01*
G01Y70058D02*
X114000Y70683D01*
G01Y73450D02*
X116500D01*
X114708Y71908D01*
Y73992D01*
G01X116083Y75258D02*
X116333Y75508D01*
X116458Y75800D01*
X116500Y76133D01*
X116417Y76550D01*
X116208Y76842D01*
X115958Y76925D01*
X115708Y76883D01*
X115500Y76717D01*
X115083Y75883D01*
X114792Y75508D01*
X114375Y75258D01*
X114000Y75175D01*
Y76925D01*
G01X114375Y78233D02*
X114167Y78483D01*
X114042Y78775D01*
X114000Y79150D01*
X114083Y79525D01*
X114250Y79817D01*
X114542Y80025D01*
X114875Y80067D01*
X115208Y79983D01*
X115417Y79775D01*
X115583Y79483D01*
X115625Y79192D01*
X115583Y78900D01*
X115417Y78525D01*
X116500Y78650D01*
Y79775D01*
G01X113500Y86017D02*
X116000D01*
Y87058D01*
X115875Y87392D01*
X115708Y87600D01*
X115375Y87683D01*
X115042Y87600D01*
X114833Y87350D01*
X114708Y87058D01*
Y86017D01*
G01Y87058D02*
X113500Y87683D01*
G01Y90450D02*
X116000D01*
X114208Y88908D01*
Y90992D01*
G01X113500Y93050D02*
X116000D01*
X115500Y92550D01*
G01X113500D02*
Y93550D01*
G01X113792Y95442D02*
X113583Y95733D01*
X113500Y96067D01*
X113583Y96400D01*
X113833Y96692D01*
X114208Y96900D01*
X114583Y96983D01*
X115042D01*
X115417Y96900D01*
X115750Y96692D01*
X115917Y96442D01*
X116000Y96150D01*
X115917Y95817D01*
X115750Y95567D01*
X115500Y95400D01*
X115167Y95317D01*
X114875Y95400D01*
X114583Y95608D01*
X114417Y95858D01*
X114375Y96150D01*
X114458Y96483D01*
X114667Y96733D01*
X115042Y96983D01*
G01X126000Y84517D02*
X128500D01*
Y85558D01*
X128375Y85892D01*
X128208Y86100D01*
X127875Y86183D01*
X127542Y86100D01*
X127333Y85850D01*
X127208Y85558D01*
Y84517D01*
G01Y85558D02*
X126000Y86183D01*
G01Y88950D02*
X128500D01*
X126708Y87408D01*
Y89492D01*
G01X128083Y90758D02*
X128333Y91008D01*
X128458Y91300D01*
X128500Y91633D01*
X128417Y92050D01*
X128208Y92342D01*
X127958Y92425D01*
X127708Y92383D01*
X127500Y92217D01*
X127083Y91383D01*
X126792Y91008D01*
X126375Y90758D01*
X126000Y90675D01*
Y92425D01*
G01Y95150D02*
X128500D01*
X126708Y93608D01*
Y95692D01*
G01X121500Y97467D02*
X124000D01*
Y98467D01*
X123875Y98800D01*
X123583Y99050D01*
X123250Y99133D01*
X122917Y99050D01*
X122667Y98842D01*
X122542Y98467D01*
Y97467D01*
G01X121500Y100567D02*
X124000D01*
Y101608D01*
X123875Y101942D01*
X123708Y102150D01*
X123375Y102233D01*
X123042Y102150D01*
X122833Y101900D01*
X122708Y101608D01*
Y100567D01*
G01Y101608D02*
X121500Y102233D01*
G01Y104500D02*
X124000D01*
X123500Y104000D01*
G01X121500D02*
Y105000D01*
G01X124000Y107600D02*
X123917Y107267D01*
X123708Y107017D01*
X123458Y106850D01*
X123125Y106725D01*
X122750Y106683D01*
X122375Y106725D01*
X122042Y106850D01*
X121792Y107017D01*
X121583Y107267D01*
X121500Y107600D01*
X121583Y107933D01*
X121792Y108183D01*
X122042Y108350D01*
X122375Y108475D01*
X122750Y108517D01*
X123125Y108475D01*
X123458Y108350D01*
X123708Y108183D01*
X123917Y107933D01*
X124000Y107600D01*
G01X123583Y109908D02*
X123833Y110158D01*
X123958Y110450D01*
X124000Y110783D01*
X123917Y111200D01*
X123708Y111492D01*
X123458Y111575D01*
X123208Y111533D01*
X123000Y111367D01*
X122583Y110533D01*
X122292Y110158D01*
X121875Y109908D01*
X121500Y109825D01*
Y111575D01*
G01X122483Y115000D02*
Y117500D01*
X121442D01*
X121108Y117375D01*
X120900Y117208D01*
X120817Y116875D01*
X120900Y116542D01*
X121150Y116333D01*
X121442Y116208D01*
X122483D01*
G01X121442D02*
X120817Y115000D01*
G01X119342Y117083D02*
X119092Y117333D01*
X118800Y117458D01*
X118467Y117500D01*
X118050Y117417D01*
X117758Y117208D01*
X117675Y116958D01*
X117717Y116708D01*
X117883Y116500D01*
X118717Y116083D01*
X119092Y115792D01*
X119342Y115375D01*
X119425Y115000D01*
X117675D01*
G01X115533D02*
X115450Y115542D01*
X115325Y116000D01*
X115158Y116417D01*
X114950Y116875D01*
X114617Y117500D01*
X116283D01*
G01X113267Y115500D02*
X113017Y115208D01*
X112683Y115042D01*
X112308Y115000D01*
X111975Y115042D01*
X111642Y115250D01*
X111433Y115500D01*
X111392Y115750D01*
X111475Y116042D01*
X111767Y116250D01*
X112058Y116333D01*
X112433D01*
G01X112058D02*
X111808Y116458D01*
X111600Y116667D01*
X111517Y116917D01*
X111600Y117167D01*
X111808Y117375D01*
X112183Y117500D01*
X112558Y117458D01*
X112933Y117292D01*
G01X128650Y138500D02*
Y136000D01*
G01X129608Y138500D02*
X127692D01*
G01X126383Y136000D02*
Y138500D01*
X125383D01*
X125050Y138375D01*
X124800Y138083D01*
X124717Y137750D01*
X124800Y137417D01*
X125008Y137167D01*
X125383Y137042D01*
X126383D01*
G01X123242D02*
X122950Y137333D01*
X122700Y137500D01*
X122367Y137583D01*
X122075Y137500D01*
X121867Y137333D01*
X121700Y137083D01*
X121658Y136792D01*
X121700Y136542D01*
X121867Y136292D01*
X122117Y136083D01*
X122408Y136000D01*
X122742Y136083D01*
X123033Y136333D01*
X123200Y136708D01*
X123242Y137125D01*
X123158Y137667D01*
X123033Y137958D01*
X122825Y138250D01*
X122533Y138458D01*
X122242Y138500D01*
X121950Y138417D01*
X121742Y138208D01*
G01X119350Y136000D02*
Y138500D01*
X119850Y138000D01*
G01Y136000D02*
X118850D01*
G01X124483Y124000D02*
Y126500D01*
X123442D01*
X123108Y126375D01*
X122900Y126208D01*
X122817Y125875D01*
X122900Y125542D01*
X123150Y125333D01*
X123442Y125208D01*
X124483D01*
G01X123442D02*
X122817Y124000D01*
G01X120050D02*
Y126500D01*
X121592Y124708D01*
X119508D01*
G01X118158Y124292D02*
X117867Y124083D01*
X117533Y124000D01*
X117200Y124083D01*
X116908Y124333D01*
X116700Y124708D01*
X116617Y125083D01*
Y125542D01*
X116700Y125917D01*
X116908Y126250D01*
X117158Y126417D01*
X117450Y126500D01*
X117783Y126417D01*
X118033Y126250D01*
X118200Y126000D01*
X118283Y125667D01*
X118200Y125375D01*
X117992Y125083D01*
X117742Y124917D01*
X117450Y124875D01*
X117117Y124958D01*
X116867Y125167D01*
X116617Y125542D01*
G01X114350Y126500D02*
X114683Y126417D01*
X114933Y126208D01*
X115100Y125958D01*
X115225Y125625D01*
X115267Y125250D01*
X115225Y124875D01*
X115100Y124542D01*
X114933Y124292D01*
X114683Y124083D01*
X114350Y124000D01*
X114017Y124083D01*
X113767Y124292D01*
X113600Y124542D01*
X113475Y124875D01*
X113433Y125250D01*
X113475Y125625D01*
X113600Y125958D01*
X113767Y126208D01*
X114017Y126417D01*
X114350Y126500D01*
G01X139033Y151000D02*
Y153500D01*
X138033D01*
X137700Y153375D01*
X137450Y153083D01*
X137367Y152750D01*
X137450Y152417D01*
X137658Y152167D01*
X138033Y152042D01*
X139033D01*
G01X134183Y153292D02*
X134433Y153417D01*
X134725Y153500D01*
X135058D01*
X135433Y153375D01*
X135725Y153167D01*
X135933Y152917D01*
X136100Y152500D01*
X136142Y152125D01*
X136058Y151750D01*
X135933Y151500D01*
X135683Y151250D01*
X135392Y151083D01*
X135100Y151000D01*
X134808D01*
X134517Y151083D01*
X134267Y151208D01*
X134058Y151375D01*
G01X132000Y151000D02*
Y153500D01*
X132500Y153000D01*
G01Y151000D02*
X131500D01*
G01X129817Y151500D02*
X129567Y151208D01*
X129233Y151042D01*
X128858Y151000D01*
X128525Y151042D01*
X128192Y151250D01*
X127983Y151500D01*
X127942Y151750D01*
X128025Y152042D01*
X128317Y152250D01*
X128608Y152333D01*
X128983D01*
G01X128608D02*
X128358Y152458D01*
X128150Y152667D01*
X128067Y152917D01*
X128150Y153167D01*
X128358Y153375D01*
X128733Y153500D01*
X129108Y153458D01*
X129483Y153292D01*
G01X125883Y151000D02*
X125800Y151542D01*
X125675Y152000D01*
X125508Y152417D01*
X125300Y152875D01*
X124967Y153500D01*
X126633D01*
G01X139033Y147000D02*
Y149500D01*
X138033D01*
X137700Y149375D01*
X137450Y149083D01*
X137367Y148750D01*
X137450Y148417D01*
X137658Y148167D01*
X138033Y148042D01*
X139033D01*
G01X135933Y147000D02*
Y149500D01*
X134892D01*
X134558Y149375D01*
X134350Y149208D01*
X134267Y148875D01*
X134350Y148542D01*
X134600Y148333D01*
X134892Y148208D01*
X135933D01*
G01X134892D02*
X134267Y147000D01*
G01X132000D02*
Y149500D01*
X132500Y149000D01*
G01Y147000D02*
X131500D01*
G01X128900D02*
X128608Y147042D01*
X128275Y147167D01*
X128067Y147375D01*
X127983Y147667D01*
X128067Y147958D01*
X128317Y148208D01*
X128692Y148333D01*
X129108D01*
X129358Y148417D01*
X129567Y148625D01*
X129650Y148917D01*
X129525Y149208D01*
X129233Y149417D01*
X128900Y149500D01*
X128567Y149417D01*
X128275Y149208D01*
X128150Y148917D01*
X128233Y148625D01*
X128442Y148417D01*
X128692Y148333D01*
X129108D01*
X129483Y148208D01*
X129733Y147958D01*
X129817Y147667D01*
X129733Y147375D01*
X129525Y147167D01*
X129192Y147042D01*
X128900Y147000D01*
G01X126592Y148042D02*
X126300Y148333D01*
X126050Y148500D01*
X125717Y148583D01*
X125425Y148500D01*
X125217Y148333D01*
X125050Y148083D01*
X125008Y147792D01*
X125050Y147542D01*
X125217Y147292D01*
X125467Y147083D01*
X125758Y147000D01*
X126092Y147083D01*
X126383Y147333D01*
X126550Y147708D01*
X126592Y148125D01*
X126508Y148667D01*
X126383Y148958D01*
X126175Y149250D01*
X125883Y149458D01*
X125592Y149500D01*
X125300Y149417D01*
X125092Y149208D01*
G01X139033Y155000D02*
Y157500D01*
X138033D01*
X137700Y157375D01*
X137450Y157083D01*
X137367Y156750D01*
X137450Y156417D01*
X137658Y156167D01*
X138033Y156042D01*
X139033D01*
G01X135933Y155000D02*
Y157500D01*
X134892D01*
X134558Y157375D01*
X134350Y157208D01*
X134267Y156875D01*
X134350Y156542D01*
X134600Y156333D01*
X134892Y156208D01*
X135933D01*
G01X134892D02*
X134267Y155000D01*
G01X132000D02*
Y157500D01*
X132500Y157000D01*
G01Y155000D02*
X131500D01*
G01X128900D02*
X128608Y155042D01*
X128275Y155167D01*
X128067Y155375D01*
X127983Y155667D01*
X128067Y155958D01*
X128317Y156208D01*
X128692Y156333D01*
X129108D01*
X129358Y156417D01*
X129567Y156625D01*
X129650Y156917D01*
X129525Y157208D01*
X129233Y157417D01*
X128900Y157500D01*
X128567Y157417D01*
X128275Y157208D01*
X128150Y156917D01*
X128233Y156625D01*
X128442Y156417D01*
X128692Y156333D01*
X129108D01*
X129483Y156208D01*
X129733Y155958D01*
X129817Y155667D01*
X129733Y155375D01*
X129525Y155167D01*
X129192Y155042D01*
X128900Y155000D01*
G01X126717Y155375D02*
X126467Y155167D01*
X126175Y155042D01*
X125800Y155000D01*
X125425Y155083D01*
X125133Y155250D01*
X124925Y155542D01*
X124883Y155875D01*
X124967Y156208D01*
X125175Y156417D01*
X125467Y156583D01*
X125758Y156625D01*
X126050Y156583D01*
X126425Y156417D01*
X126300Y157500D01*
X125175D01*
G01X126000Y218967D02*
X128500D01*
Y219967D01*
X128375Y220300D01*
X128083Y220550D01*
X127750Y220633D01*
X127417Y220550D01*
X127167Y220342D01*
X127042Y219967D01*
Y218967D01*
G01X126000Y222067D02*
X128500D01*
Y223108D01*
X128375Y223442D01*
X128208Y223650D01*
X127875Y223733D01*
X127542Y223650D01*
X127333Y223400D01*
X127208Y223108D01*
Y222067D01*
G01Y223108D02*
X126000Y223733D01*
G01Y226000D02*
X128500D01*
X128000Y225500D01*
G01X126000D02*
Y226500D01*
G01Y229017D02*
X126542Y229100D01*
X127000Y229225D01*
X127417Y229392D01*
X127875Y229600D01*
X128500Y229933D01*
Y228267D01*
G01X126000Y232117D02*
X126542Y232200D01*
X127000Y232325D01*
X127417Y232492D01*
X127875Y232700D01*
X128500Y233033D01*
Y231367D01*
G01X122200Y234017D02*
X124700D01*
Y235017D01*
X124575Y235350D01*
X124283Y235600D01*
X123950Y235683D01*
X123617Y235600D01*
X123367Y235392D01*
X123242Y235017D01*
Y234017D01*
G01X122200Y237117D02*
X124700D01*
Y238158D01*
X124575Y238492D01*
X124408Y238700D01*
X124075Y238783D01*
X123742Y238700D01*
X123533Y238450D01*
X123408Y238158D01*
Y237117D01*
G01Y238158D02*
X122200Y238783D01*
G01X124283Y240258D02*
X124533Y240508D01*
X124658Y240800D01*
X124700Y241133D01*
X124617Y241550D01*
X124408Y241842D01*
X124158Y241925D01*
X123908Y241883D01*
X123700Y241717D01*
X123283Y240883D01*
X122992Y240508D01*
X122575Y240258D01*
X122200Y240175D01*
Y241925D01*
G01Y244067D02*
X122742Y244150D01*
X123200Y244275D01*
X123617Y244442D01*
X124075Y244650D01*
X124700Y244983D01*
Y243317D01*
G01X114000Y234067D02*
X116500D01*
Y235067D01*
X116375Y235400D01*
X116083Y235650D01*
X115750Y235733D01*
X115417Y235650D01*
X115167Y235442D01*
X115042Y235067D01*
Y234067D01*
G01X116292Y238917D02*
X116417Y238667D01*
X116500Y238375D01*
Y238042D01*
X116375Y237667D01*
X116167Y237375D01*
X115917Y237167D01*
X115500Y237000D01*
X115125Y236958D01*
X114750Y237042D01*
X114500Y237167D01*
X114250Y237417D01*
X114083Y237708D01*
X114000Y238000D01*
Y238292D01*
X114083Y238583D01*
X114208Y238833D01*
X114375Y239042D01*
G01X114500Y240183D02*
X114208Y240433D01*
X114042Y240767D01*
X114000Y241142D01*
X114042Y241475D01*
X114250Y241808D01*
X114500Y242017D01*
X114750Y242058D01*
X115042Y241975D01*
X115250Y241683D01*
X115333Y241392D01*
Y241017D01*
G01Y241392D02*
X115458Y241642D01*
X115667Y241850D01*
X115917Y241933D01*
X116167Y241850D01*
X116375Y241642D01*
X116500Y241267D01*
X116458Y240892D01*
X116292Y240517D01*
G01X118200Y234017D02*
X120700D01*
Y235017D01*
X120575Y235350D01*
X120283Y235600D01*
X119950Y235683D01*
X119617Y235600D01*
X119367Y235392D01*
X119242Y235017D01*
Y234017D01*
G01X120492Y238867D02*
X120617Y238617D01*
X120700Y238325D01*
Y237992D01*
X120575Y237617D01*
X120367Y237325D01*
X120117Y237117D01*
X119700Y236950D01*
X119325Y236908D01*
X118950Y236992D01*
X118700Y237117D01*
X118450Y237367D01*
X118283Y237658D01*
X118200Y237950D01*
Y238242D01*
X118283Y238533D01*
X118408Y238783D01*
X118575Y238992D01*
G01X118200Y241050D02*
X120700D01*
X120200Y240550D01*
G01X118200D02*
Y241550D01*
G01Y244650D02*
X120700D01*
X118908Y243108D01*
Y245192D01*
G01X112500Y245017D02*
X115000D01*
Y246058D01*
X114875Y246392D01*
X114708Y246600D01*
X114375Y246683D01*
X114042Y246600D01*
X113833Y246350D01*
X113708Y246058D01*
Y245017D01*
G01Y246058D02*
X112500Y246683D01*
G01Y249450D02*
X115000D01*
X113208Y247908D01*
Y249992D01*
G01X112792Y251342D02*
X112583Y251633D01*
X112500Y251967D01*
X112583Y252300D01*
X112833Y252592D01*
X113208Y252800D01*
X113583Y252883D01*
X114042D01*
X114417Y252800D01*
X114750Y252592D01*
X114917Y252342D01*
X115000Y252050D01*
X114917Y251717D01*
X114750Y251467D01*
X114500Y251300D01*
X114167Y251217D01*
X113875Y251300D01*
X113583Y251508D01*
X113417Y251758D01*
X113375Y252050D01*
X113458Y252383D01*
X113667Y252633D01*
X114042Y252883D01*
G01X113542Y254358D02*
X113833Y254650D01*
X114000Y254900D01*
X114083Y255233D01*
X114000Y255525D01*
X113833Y255733D01*
X113583Y255900D01*
X113292Y255942D01*
X113042Y255900D01*
X112792Y255733D01*
X112583Y255483D01*
X112500Y255192D01*
X112583Y254858D01*
X112833Y254567D01*
X113208Y254400D01*
X113625Y254358D01*
X114167Y254442D01*
X114458Y254567D01*
X114750Y254775D01*
X114958Y255067D01*
X115000Y255358D01*
X114917Y255650D01*
X114708Y255858D01*
G01X141233Y44292D02*
X141483Y44417D01*
X141775Y44500D01*
X142108D01*
X142483Y44375D01*
X142775Y44167D01*
X142983Y43917D01*
X143150Y43500D01*
X143192Y43125D01*
X143108Y42750D01*
X142983Y42500D01*
X142733Y42250D01*
X142442Y42083D01*
X142150Y42000D01*
X141858D01*
X141567Y42083D01*
X141317Y42208D01*
X141108Y42375D01*
G01X139842Y44083D02*
X139592Y44333D01*
X139300Y44458D01*
X138967Y44500D01*
X138550Y44417D01*
X138258Y44208D01*
X138175Y43958D01*
X138217Y43708D01*
X138383Y43500D01*
X139217Y43083D01*
X139592Y42792D01*
X139842Y42375D01*
X139925Y42000D01*
X138175D01*
G01X136742Y43042D02*
X136450Y43333D01*
X136200Y43500D01*
X135867Y43583D01*
X135575Y43500D01*
X135367Y43333D01*
X135200Y43083D01*
X135158Y42792D01*
X135200Y42542D01*
X135367Y42292D01*
X135617Y42083D01*
X135908Y42000D01*
X136242Y42083D01*
X136533Y42333D01*
X136700Y42708D01*
X136742Y43125D01*
X136658Y43667D01*
X136533Y43958D01*
X136325Y44250D01*
X136033Y44458D01*
X135742Y44500D01*
X135450Y44417D01*
X135242Y44208D01*
G01X132850Y42000D02*
X132558Y42042D01*
X132225Y42167D01*
X132017Y42375D01*
X131933Y42667D01*
X132017Y42958D01*
X132267Y43208D01*
X132642Y43333D01*
X133058D01*
X133308Y43417D01*
X133517Y43625D01*
X133600Y43917D01*
X133475Y44208D01*
X133183Y44417D01*
X132850Y44500D01*
X132517Y44417D01*
X132225Y44208D01*
X132100Y43917D01*
X132183Y43625D01*
X132392Y43417D01*
X132642Y43333D01*
X133058D01*
X133433Y43208D01*
X133683Y42958D01*
X133767Y42667D01*
X133683Y42375D01*
X133475Y42167D01*
X133142Y42042D01*
X132850Y42000D01*
G01X129292Y45767D02*
X129417Y45517D01*
X129500Y45225D01*
Y44892D01*
X129375Y44517D01*
X129167Y44225D01*
X128917Y44017D01*
X128500Y43850D01*
X128125Y43808D01*
X127750Y43892D01*
X127500Y44017D01*
X127250Y44267D01*
X127083Y44558D01*
X127000Y44850D01*
Y45142D01*
X127083Y45433D01*
X127208Y45683D01*
X127375Y45892D01*
G01X129083Y47158D02*
X129333Y47408D01*
X129458Y47700D01*
X129500Y48033D01*
X129417Y48450D01*
X129208Y48742D01*
X128958Y48825D01*
X128708Y48783D01*
X128500Y48617D01*
X128083Y47783D01*
X127792Y47408D01*
X127375Y47158D01*
X127000Y47075D01*
Y48825D01*
G01X128042Y50258D02*
X128333Y50550D01*
X128500Y50800D01*
X128583Y51133D01*
X128500Y51425D01*
X128333Y51633D01*
X128083Y51800D01*
X127792Y51842D01*
X127542Y51800D01*
X127292Y51633D01*
X127083Y51383D01*
X127000Y51092D01*
X127083Y50758D01*
X127333Y50467D01*
X127708Y50300D01*
X128125Y50258D01*
X128667Y50342D01*
X128958Y50467D01*
X129250Y50675D01*
X129458Y50967D01*
X129500Y51258D01*
X129417Y51550D01*
X129208Y51758D01*
G01X127292Y53442D02*
X127083Y53733D01*
X127000Y54067D01*
X127083Y54400D01*
X127333Y54692D01*
X127708Y54900D01*
X128083Y54983D01*
X128542D01*
X128917Y54900D01*
X129250Y54692D01*
X129417Y54442D01*
X129500Y54150D01*
X129417Y53817D01*
X129250Y53567D01*
X129000Y53400D01*
X128667Y53317D01*
X128375Y53400D01*
X128083Y53608D01*
X127917Y53858D01*
X127875Y54150D01*
X127958Y54483D01*
X128167Y54733D01*
X128542Y54983D01*
G01X140983Y86500D02*
Y89000D01*
X139942D01*
X139608Y88875D01*
X139400Y88708D01*
X139317Y88375D01*
X139400Y88042D01*
X139650Y87833D01*
X139942Y87708D01*
X140983D01*
G01X139942D02*
X139317Y86500D01*
G01X137967Y87000D02*
X137717Y86708D01*
X137383Y86542D01*
X137008Y86500D01*
X136675Y86542D01*
X136342Y86750D01*
X136133Y87000D01*
X136092Y87250D01*
X136175Y87542D01*
X136467Y87750D01*
X136758Y87833D01*
X137133D01*
G01X136758D02*
X136508Y87958D01*
X136300Y88167D01*
X136217Y88417D01*
X136300Y88667D01*
X136508Y88875D01*
X136883Y89000D01*
X137258Y88958D01*
X137633Y88792D01*
G01X134867Y86875D02*
X134617Y86667D01*
X134325Y86542D01*
X133950Y86500D01*
X133575Y86583D01*
X133283Y86750D01*
X133075Y87042D01*
X133033Y87375D01*
X133117Y87708D01*
X133325Y87917D01*
X133617Y88083D01*
X133908Y88125D01*
X134200Y88083D01*
X134575Y87917D01*
X134450Y89000D01*
X133325D01*
G01X130350Y86500D02*
Y89000D01*
X131892Y87208D01*
X129808D01*
G01X138500Y96017D02*
X141000D01*
Y97058D01*
X140875Y97392D01*
X140708Y97600D01*
X140375Y97683D01*
X140042Y97600D01*
X139833Y97350D01*
X139708Y97058D01*
Y96017D01*
G01Y97058D02*
X138500Y97683D01*
G01Y100450D02*
X141000D01*
X139208Y98908D01*
Y100992D01*
G01X138500Y103050D02*
X141000D01*
X140500Y102550D01*
G01X138500D02*
Y103550D01*
G01Y106150D02*
X138542Y106442D01*
X138667Y106775D01*
X138875Y106983D01*
X139167Y107067D01*
X139458Y106983D01*
X139708Y106733D01*
X139833Y106358D01*
Y105942D01*
X139917Y105692D01*
X140125Y105483D01*
X140417Y105400D01*
X140708Y105525D01*
X140917Y105817D01*
X141000Y106150D01*
X140917Y106483D01*
X140708Y106775D01*
X140417Y106900D01*
X140125Y106817D01*
X139917Y106608D01*
X139833Y106358D01*
Y105942D01*
X139708Y105567D01*
X139458Y105317D01*
X139167Y105233D01*
X138875Y105317D01*
X138667Y105525D01*
X138542Y105858D01*
X138500Y106150D01*
G01X140983Y91000D02*
Y93500D01*
X139942D01*
X139608Y93375D01*
X139400Y93208D01*
X139317Y92875D01*
X139400Y92542D01*
X139650Y92333D01*
X139942Y92208D01*
X140983D01*
G01X139942D02*
X139317Y91000D01*
G01X137967Y91500D02*
X137717Y91208D01*
X137383Y91042D01*
X137008Y91000D01*
X136675Y91042D01*
X136342Y91250D01*
X136133Y91500D01*
X136092Y91750D01*
X136175Y92042D01*
X136467Y92250D01*
X136758Y92333D01*
X137133D01*
G01X136758D02*
X136508Y92458D01*
X136300Y92667D01*
X136217Y92917D01*
X136300Y93167D01*
X136508Y93375D01*
X136883Y93500D01*
X137258Y93458D01*
X137633Y93292D01*
G01X133450Y91000D02*
Y93500D01*
X134992Y91708D01*
X132908D01*
G01X131558Y91292D02*
X131267Y91083D01*
X130933Y91000D01*
X130600Y91083D01*
X130308Y91333D01*
X130100Y91708D01*
X130017Y92083D01*
Y92542D01*
X130100Y92917D01*
X130308Y93250D01*
X130558Y93417D01*
X130850Y93500D01*
X131183Y93417D01*
X131433Y93250D01*
X131600Y93000D01*
X131683Y92667D01*
X131600Y92375D01*
X131392Y92083D01*
X131142Y91917D01*
X130850Y91875D01*
X130517Y91958D01*
X130267Y92167D01*
X130017Y92542D01*
G01X142733Y117792D02*
X142983Y117917D01*
X143275Y118000D01*
X143608D01*
X143983Y117875D01*
X144275Y117667D01*
X144483Y117417D01*
X144650Y117000D01*
X144692Y116625D01*
X144608Y116250D01*
X144483Y116000D01*
X144233Y115750D01*
X143942Y115583D01*
X143650Y115500D01*
X143358D01*
X143067Y115583D01*
X142817Y115708D01*
X142608Y115875D01*
G01X141467Y116000D02*
X141217Y115708D01*
X140883Y115542D01*
X140508Y115500D01*
X140175Y115542D01*
X139842Y115750D01*
X139633Y116000D01*
X139592Y116250D01*
X139675Y116542D01*
X139967Y116750D01*
X140258Y116833D01*
X140633D01*
G01X140258D02*
X140008Y116958D01*
X139800Y117167D01*
X139717Y117417D01*
X139800Y117667D01*
X140008Y117875D01*
X140383Y118000D01*
X140758Y117958D01*
X141133Y117792D01*
G01X137450Y118000D02*
X137783Y117917D01*
X138033Y117708D01*
X138200Y117458D01*
X138325Y117125D01*
X138367Y116750D01*
X138325Y116375D01*
X138200Y116042D01*
X138033Y115792D01*
X137783Y115583D01*
X137450Y115500D01*
X137117Y115583D01*
X136867Y115792D01*
X136700Y116042D01*
X136575Y116375D01*
X136533Y116750D01*
X136575Y117125D01*
X136700Y117458D01*
X136867Y117708D01*
X137117Y117917D01*
X137450Y118000D01*
G01X135058Y115792D02*
X134767Y115583D01*
X134433Y115500D01*
X134100Y115583D01*
X133808Y115833D01*
X133600Y116208D01*
X133517Y116583D01*
Y117042D01*
X133600Y117417D01*
X133808Y117750D01*
X134058Y117917D01*
X134350Y118000D01*
X134683Y117917D01*
X134933Y117750D01*
X135100Y117500D01*
X135183Y117167D01*
X135100Y116875D01*
X134892Y116583D01*
X134642Y116417D01*
X134350Y116375D01*
X134017Y116458D01*
X133767Y116667D01*
X133517Y117042D01*
G01X144483Y119500D02*
Y122000D01*
X143442D01*
X143108Y121875D01*
X142900Y121708D01*
X142817Y121375D01*
X142900Y121042D01*
X143150Y120833D01*
X143442Y120708D01*
X144483D01*
G01X143442D02*
X142817Y119500D01*
G01X140050D02*
Y122000D01*
X141592Y120208D01*
X139508D01*
G01X138367Y119875D02*
X138117Y119667D01*
X137825Y119542D01*
X137450Y119500D01*
X137075Y119583D01*
X136783Y119750D01*
X136575Y120042D01*
X136533Y120375D01*
X136617Y120708D01*
X136825Y120917D01*
X137117Y121083D01*
X137408Y121125D01*
X137700Y121083D01*
X138075Y120917D01*
X137950Y122000D01*
X136825D01*
G01X135267Y120000D02*
X135017Y119708D01*
X134683Y119542D01*
X134308Y119500D01*
X133975Y119542D01*
X133642Y119750D01*
X133433Y120000D01*
X133392Y120250D01*
X133475Y120542D01*
X133767Y120750D01*
X134058Y120833D01*
X134433D01*
G01X134058D02*
X133808Y120958D01*
X133600Y121167D01*
X133517Y121417D01*
X133600Y121667D01*
X133808Y121875D01*
X134183Y122000D01*
X134558Y121958D01*
X134933Y121792D01*
G01X144483Y123500D02*
Y126000D01*
X143442D01*
X143108Y125875D01*
X142900Y125708D01*
X142817Y125375D01*
X142900Y125042D01*
X143150Y124833D01*
X143442Y124708D01*
X144483D01*
G01X143442D02*
X142817Y123500D01*
G01X140050D02*
Y126000D01*
X141592Y124208D01*
X139508D01*
G01X136950Y123500D02*
Y126000D01*
X138492Y124208D01*
X136408D01*
G01X135058Y123792D02*
X134767Y123583D01*
X134433Y123500D01*
X134100Y123583D01*
X133808Y123833D01*
X133600Y124208D01*
X133517Y124583D01*
Y125042D01*
X133600Y125417D01*
X133808Y125750D01*
X134058Y125917D01*
X134350Y126000D01*
X134683Y125917D01*
X134933Y125750D01*
X135100Y125500D01*
X135183Y125167D01*
X135100Y124875D01*
X134892Y124583D01*
X134642Y124417D01*
X134350Y124375D01*
X134017Y124458D01*
X133767Y124667D01*
X133517Y125042D01*
G01X151500Y159500D02*
X132500D01*
Y166000D01*
X133500D01*
G01Y177000D02*
Y181000D01*
G01X132000Y192000D02*
Y195000D01*
X140000D01*
Y197500D01*
X148500D01*
Y216500D01*
X175000D01*
Y220500D01*
X173000Y218500D01*
X177000D01*
X175000Y220500D01*
G01X133000Y203467D02*
X135500D01*
Y204467D01*
X135375Y204800D01*
X135083Y205050D01*
X134750Y205133D01*
X134417Y205050D01*
X134167Y204842D01*
X134042Y204467D01*
Y203467D01*
G01X135292Y208317D02*
X135417Y208067D01*
X135500Y207775D01*
Y207442D01*
X135375Y207067D01*
X135167Y206775D01*
X134917Y206567D01*
X134500Y206400D01*
X134125Y206358D01*
X133750Y206442D01*
X133500Y206567D01*
X133250Y206817D01*
X133083Y207108D01*
X133000Y207400D01*
Y207692D01*
X133083Y207983D01*
X133208Y208233D01*
X133375Y208442D01*
G01X133000Y210500D02*
X135500D01*
X135000Y210000D01*
G01X133000D02*
Y211000D01*
G01X133500Y212683D02*
X133208Y212933D01*
X133042Y213267D01*
X133000Y213642D01*
X133042Y213975D01*
X133250Y214308D01*
X133500Y214517D01*
X133750Y214558D01*
X134042Y214475D01*
X134250Y214183D01*
X134333Y213892D01*
Y213517D01*
G01Y213892D02*
X134458Y214142D01*
X134667Y214350D01*
X134917Y214433D01*
X135167Y214350D01*
X135375Y214142D01*
X135500Y213767D01*
X135458Y213392D01*
X135292Y213017D01*
G01X133000Y216700D02*
X135500D01*
X135000Y216200D01*
G01X133000D02*
Y217200D01*
G01X138500Y203517D02*
X141000D01*
Y204558D01*
X140875Y204892D01*
X140708Y205100D01*
X140375Y205183D01*
X140042Y205100D01*
X139833Y204850D01*
X139708Y204558D01*
Y203517D01*
G01Y204558D02*
X138500Y205183D01*
G01X140583Y206658D02*
X140833Y206908D01*
X140958Y207200D01*
X141000Y207533D01*
X140917Y207950D01*
X140708Y208242D01*
X140458Y208325D01*
X140208Y208283D01*
X140000Y208117D01*
X139583Y207283D01*
X139292Y206908D01*
X138875Y206658D01*
X138500Y206575D01*
Y208325D01*
G01X138875Y209633D02*
X138667Y209883D01*
X138542Y210175D01*
X138500Y210550D01*
X138583Y210925D01*
X138750Y211217D01*
X139042Y211425D01*
X139375Y211467D01*
X139708Y211383D01*
X139917Y211175D01*
X140083Y210883D01*
X140125Y210592D01*
X140083Y210300D01*
X139917Y209925D01*
X141000Y210050D01*
Y211175D01*
G01X140583Y212858D02*
X140833Y213108D01*
X140958Y213400D01*
X141000Y213733D01*
X140917Y214150D01*
X140708Y214442D01*
X140458Y214525D01*
X140208Y214483D01*
X140000Y214317D01*
X139583Y213483D01*
X139292Y213108D01*
X138875Y212858D01*
X138500Y212775D01*
Y214525D01*
G01X130000Y218967D02*
X132500D01*
Y219967D01*
X132375Y220300D01*
X132083Y220550D01*
X131750Y220633D01*
X131417Y220550D01*
X131167Y220342D01*
X131042Y219967D01*
Y218967D01*
G01X130000Y222067D02*
X132500D01*
Y223108D01*
X132375Y223442D01*
X132208Y223650D01*
X131875Y223733D01*
X131542Y223650D01*
X131333Y223400D01*
X131208Y223108D01*
Y222067D01*
G01Y223108D02*
X130000Y223733D01*
G01Y226000D02*
X132500D01*
X132000Y225500D01*
G01X130000D02*
Y226500D01*
G01Y229017D02*
X130542Y229100D01*
X131000Y229225D01*
X131417Y229392D01*
X131875Y229600D01*
X132500Y229933D01*
Y228267D01*
G01X130000Y232200D02*
X130042Y232492D01*
X130167Y232825D01*
X130375Y233033D01*
X130667Y233117D01*
X130958Y233033D01*
X131208Y232783D01*
X131333Y232408D01*
Y231992D01*
X131417Y231742D01*
X131625Y231533D01*
X131917Y231450D01*
X132208Y231575D01*
X132417Y231867D01*
X132500Y232200D01*
X132417Y232533D01*
X132208Y232825D01*
X131917Y232950D01*
X131625Y232867D01*
X131417Y232658D01*
X131333Y232408D01*
Y231992D01*
X131208Y231617D01*
X130958Y231367D01*
X130667Y231283D01*
X130375Y231367D01*
X130167Y231575D01*
X130042Y231908D01*
X130000Y232200D01*
G01X134000Y218967D02*
X136500D01*
Y219967D01*
X136375Y220300D01*
X136083Y220550D01*
X135750Y220633D01*
X135417Y220550D01*
X135167Y220342D01*
X135042Y219967D01*
Y218967D01*
G01X136292Y223817D02*
X136417Y223567D01*
X136500Y223275D01*
Y222942D01*
X136375Y222567D01*
X136167Y222275D01*
X135917Y222067D01*
X135500Y221900D01*
X135125Y221858D01*
X134750Y221942D01*
X134500Y222067D01*
X134250Y222317D01*
X134083Y222608D01*
X134000Y222900D01*
Y223192D01*
X134083Y223483D01*
X134208Y223733D01*
X134375Y223942D01*
G01X134000Y226000D02*
X136500D01*
X136000Y225500D01*
G01X134000D02*
Y226500D01*
G01X136083Y228308D02*
X136333Y228558D01*
X136458Y228850D01*
X136500Y229183D01*
X136417Y229600D01*
X136208Y229892D01*
X135958Y229975D01*
X135708Y229933D01*
X135500Y229767D01*
X135083Y228933D01*
X134792Y228558D01*
X134375Y228308D01*
X134000Y228225D01*
Y229975D01*
G01X134375Y231283D02*
X134167Y231533D01*
X134042Y231825D01*
X134000Y232200D01*
X134083Y232575D01*
X134250Y232867D01*
X134542Y233075D01*
X134875Y233117D01*
X135208Y233033D01*
X135417Y232825D01*
X135583Y232533D01*
X135625Y232242D01*
X135583Y231950D01*
X135417Y231575D01*
X136500Y231700D01*
Y232825D01*
G01X155792Y44267D02*
X155917Y44017D01*
X156000Y43725D01*
Y43392D01*
X155875Y43017D01*
X155667Y42725D01*
X155417Y42517D01*
X155000Y42350D01*
X154625Y42308D01*
X154250Y42392D01*
X154000Y42517D01*
X153750Y42767D01*
X153583Y43058D01*
X153500Y43350D01*
Y43642D01*
X153583Y43933D01*
X153708Y44183D01*
X153875Y44392D01*
G01X155583Y45658D02*
X155833Y45908D01*
X155958Y46200D01*
X156000Y46533D01*
X155917Y46950D01*
X155708Y47242D01*
X155458Y47325D01*
X155208Y47283D01*
X155000Y47117D01*
X154583Y46283D01*
X154292Y45908D01*
X153875Y45658D01*
X153500Y45575D01*
Y47325D01*
G01X154542Y48758D02*
X154833Y49050D01*
X155000Y49300D01*
X155083Y49633D01*
X155000Y49925D01*
X154833Y50133D01*
X154583Y50300D01*
X154292Y50342D01*
X154042Y50300D01*
X153792Y50133D01*
X153583Y49883D01*
X153500Y49592D01*
X153583Y49258D01*
X153833Y48967D01*
X154208Y48800D01*
X154625Y48758D01*
X155167Y48842D01*
X155458Y48967D01*
X155750Y49175D01*
X155958Y49467D01*
X156000Y49758D01*
X155917Y50050D01*
X155708Y50258D01*
G01X153500Y52567D02*
X154042Y52650D01*
X154500Y52775D01*
X154917Y52942D01*
X155375Y53150D01*
X156000Y53483D01*
Y51817D01*
G01X168500Y69500D02*
X153000D01*
Y65000D01*
X149500Y61500D01*
Y55000D01*
X195500D01*
G01X146000Y76517D02*
X148500D01*
Y77558D01*
X148375Y77892D01*
X148208Y78100D01*
X147875Y78183D01*
X147542Y78100D01*
X147333Y77850D01*
X147208Y77558D01*
Y76517D01*
G01Y77558D02*
X146000Y78183D01*
G01Y80950D02*
X148500D01*
X146708Y79408D01*
Y81492D01*
G01X146375Y82633D02*
X146167Y82883D01*
X146042Y83175D01*
X146000Y83550D01*
X146083Y83925D01*
X146250Y84217D01*
X146542Y84425D01*
X146875Y84467D01*
X147208Y84383D01*
X147417Y84175D01*
X147583Y83883D01*
X147625Y83592D01*
X147583Y83300D01*
X147417Y82925D01*
X148500Y83050D01*
Y84175D01*
G01X146000Y86650D02*
X148500D01*
X148000Y86150D01*
G01X146000D02*
Y87150D01*
G01X150000Y76017D02*
X152500D01*
Y77058D01*
X152375Y77392D01*
X152208Y77600D01*
X151875Y77683D01*
X151542Y77600D01*
X151333Y77350D01*
X151208Y77058D01*
Y76017D01*
G01Y77058D02*
X150000Y77683D01*
G01Y80450D02*
X152500D01*
X150708Y78908D01*
Y80992D01*
G01X150375Y82133D02*
X150167Y82383D01*
X150042Y82675D01*
X150000Y83050D01*
X150083Y83425D01*
X150250Y83717D01*
X150542Y83925D01*
X150875Y83967D01*
X151208Y83883D01*
X151417Y83675D01*
X151583Y83383D01*
X151625Y83092D01*
X151583Y82800D01*
X151417Y82425D01*
X152500Y82550D01*
Y83675D01*
G01X152083Y85358D02*
X152333Y85608D01*
X152458Y85900D01*
X152500Y86233D01*
X152417Y86650D01*
X152208Y86942D01*
X151958Y87025D01*
X151708Y86983D01*
X151500Y86817D01*
X151083Y85983D01*
X150792Y85608D01*
X150375Y85358D01*
X150000Y85275D01*
Y87025D01*
G01X152500Y95483D02*
X150708D01*
X150333Y95650D01*
X150083Y95983D01*
X150000Y96400D01*
X150083Y96817D01*
X150333Y97150D01*
X150708Y97317D01*
X152500D01*
G01X152083Y98708D02*
X152333Y98958D01*
X152458Y99250D01*
X152500Y99583D01*
X152417Y100000D01*
X152208Y100292D01*
X151958Y100375D01*
X151708Y100333D01*
X151500Y100167D01*
X151083Y99333D01*
X150792Y98958D01*
X150375Y98708D01*
X150000Y98625D01*
Y100375D01*
G01Y102600D02*
X150042Y102892D01*
X150167Y103225D01*
X150375Y103433D01*
X150667Y103517D01*
X150958Y103433D01*
X151208Y103183D01*
X151333Y102808D01*
Y102392D01*
X151417Y102142D01*
X151625Y101933D01*
X151917Y101850D01*
X152208Y101975D01*
X152417Y102267D01*
X152500Y102600D01*
X152417Y102933D01*
X152208Y103225D01*
X151917Y103350D01*
X151625Y103267D01*
X151417Y103058D01*
X151333Y102808D01*
Y102392D01*
X151208Y102017D01*
X150958Y101767D01*
X150667Y101683D01*
X150375Y101767D01*
X150167Y101975D01*
X150042Y102308D01*
X150000Y102600D01*
G01X150792Y116767D02*
X150917Y116517D01*
X151000Y116225D01*
Y115892D01*
X150875Y115517D01*
X150667Y115225D01*
X150417Y115017D01*
X150000Y114850D01*
X149625Y114808D01*
X149250Y114892D01*
X149000Y115017D01*
X148750Y115267D01*
X148583Y115558D01*
X148500Y115850D01*
Y116142D01*
X148583Y116433D01*
X148708Y116683D01*
X148875Y116892D01*
G01X148500Y118950D02*
X151000D01*
X150500Y118450D01*
G01X148500D02*
Y119450D01*
G01Y122050D02*
X151000D01*
X150500Y121550D01*
G01X148500D02*
Y122550D01*
G01Y125650D02*
X151000D01*
X149208Y124108D01*
Y126192D01*
G01X162983Y129500D02*
Y132000D01*
X161942D01*
X161608Y131875D01*
X161400Y131708D01*
X161317Y131375D01*
X161400Y131042D01*
X161650Y130833D01*
X161942Y130708D01*
X162983D01*
G01X161942D02*
X161317Y129500D01*
G01X158550D02*
Y132000D01*
X160092Y130208D01*
X158008D01*
G01X156867Y130000D02*
X156617Y129708D01*
X156283Y129542D01*
X155908Y129500D01*
X155575Y129542D01*
X155242Y129750D01*
X155033Y130000D01*
X154992Y130250D01*
X155075Y130542D01*
X155367Y130750D01*
X155658Y130833D01*
X156033D01*
G01X155658D02*
X155408Y130958D01*
X155200Y131167D01*
X155117Y131417D01*
X155200Y131667D01*
X155408Y131875D01*
X155783Y132000D01*
X156158Y131958D01*
X156533Y131792D01*
G01X153642Y131583D02*
X153392Y131833D01*
X153100Y131958D01*
X152767Y132000D01*
X152350Y131917D01*
X152058Y131708D01*
X151975Y131458D01*
X152017Y131208D01*
X152183Y131000D01*
X153017Y130583D01*
X153392Y130292D01*
X153642Y129875D01*
X153725Y129500D01*
X151975D01*
G01X203500Y141500D02*
Y144833D01*
G01Y143917D02*
X203250Y144333D01*
X202833Y144667D01*
X202250Y144833D01*
X201667Y144667D01*
X201250Y144333D01*
X201000Y143917D01*
Y141500D01*
G01Y143917D02*
X200750Y144333D01*
X200333Y144667D01*
X199750Y144833D01*
X199167Y144667D01*
X198750Y144333D01*
X198500Y143833D01*
Y141500D01*
G01X197150Y142167D02*
X196483Y141750D01*
X195733Y141500D01*
X195067D01*
X194400Y141750D01*
X193900Y142167D01*
X193650Y142750D01*
X193817Y143333D01*
X194233Y143833D01*
X194983Y144167D01*
X195983Y144333D01*
X196567Y144667D01*
X196817Y145250D01*
X196650Y145833D01*
X196233Y146250D01*
X195650Y146500D01*
X195067D01*
X194483Y146333D01*
X193983Y145917D01*
G01X191883Y141500D02*
X189800Y146500D01*
X187717Y141500D01*
G01X188467Y143250D02*
X191133D01*
G01X184200Y146500D02*
Y141500D01*
G01X186117Y146500D02*
X182283D01*
G01X180683Y141500D02*
X178600Y146500D01*
X176517Y141500D01*
G01X177267Y143250D02*
X179933D01*
G01X165567Y146083D02*
X166067Y146333D01*
X166650Y146500D01*
X167317D01*
X168067Y146250D01*
X168650Y145833D01*
X169067Y145333D01*
X169400Y144500D01*
X169483Y143750D01*
X169317Y143000D01*
X169067Y142500D01*
X168567Y142000D01*
X167983Y141667D01*
X167400Y141500D01*
X166817D01*
X166233Y141667D01*
X165733Y141917D01*
X165317Y142250D01*
G01X161800Y141500D02*
X162467Y141583D01*
X163050Y141917D01*
X163550Y142417D01*
X163883Y143000D01*
X164050Y143667D01*
Y144333D01*
X163883Y145000D01*
X163550Y145583D01*
X163050Y146083D01*
X162467Y146417D01*
X161800Y146500D01*
X161133Y146417D01*
X160550Y146083D01*
X160050Y145583D01*
X159717Y145000D01*
X159550Y144333D01*
Y143667D01*
X159717Y143000D01*
X160050Y142417D01*
X160550Y141917D01*
X161133Y141583D01*
X161800Y141500D01*
G01X158117D02*
Y146500D01*
X154283Y141500D01*
Y146500D01*
G01X152517Y141500D02*
Y146500D01*
X148683Y141500D01*
Y146500D01*
G01X162433Y153000D02*
Y150500D01*
X160767D01*
G01X158500D02*
Y153000D01*
X159000Y152500D01*
G01Y150500D02*
X158000D01*
G01X156317Y151000D02*
X156067Y150708D01*
X155733Y150542D01*
X155358Y150500D01*
X155025Y150542D01*
X154692Y150750D01*
X154483Y151000D01*
X154442Y151250D01*
X154525Y151542D01*
X154817Y151750D01*
X155108Y151833D01*
X155483D01*
G01X155108D02*
X154858Y151958D01*
X154650Y152167D01*
X154567Y152417D01*
X154650Y152667D01*
X154858Y152875D01*
X155233Y153000D01*
X155608Y152958D01*
X155983Y152792D01*
G01X156000Y243017D02*
X158500D01*
Y244017D01*
X158375Y244350D01*
X158083Y244600D01*
X157750Y244683D01*
X157417Y244600D01*
X157167Y244392D01*
X157042Y244017D01*
Y243017D01*
G01X156000Y246117D02*
X158500D01*
Y247158D01*
X158375Y247492D01*
X158208Y247700D01*
X157875Y247783D01*
X157542Y247700D01*
X157333Y247450D01*
X157208Y247158D01*
Y246117D01*
G01Y247158D02*
X156000Y247783D01*
G01X156500Y249133D02*
X156208Y249383D01*
X156042Y249717D01*
X156000Y250092D01*
X156042Y250425D01*
X156250Y250758D01*
X156500Y250967D01*
X156750Y251008D01*
X157042Y250925D01*
X157250Y250633D01*
X157333Y250342D01*
Y249967D01*
G01Y250342D02*
X157458Y250592D01*
X157667Y250800D01*
X157917Y250883D01*
X158167Y250800D01*
X158375Y250592D01*
X158500Y250217D01*
X158458Y249842D01*
X158292Y249467D01*
G01X156375Y252233D02*
X156167Y252483D01*
X156042Y252775D01*
X156000Y253150D01*
X156083Y253525D01*
X156250Y253817D01*
X156542Y254025D01*
X156875Y254067D01*
X157208Y253983D01*
X157417Y253775D01*
X157583Y253483D01*
X157625Y253192D01*
X157583Y252900D01*
X157417Y252525D01*
X158500Y252650D01*
Y253775D01*
G01X151500Y243017D02*
X154000D01*
Y244017D01*
X153875Y244350D01*
X153583Y244600D01*
X153250Y244683D01*
X152917Y244600D01*
X152667Y244392D01*
X152542Y244017D01*
Y243017D01*
G01X151500Y246117D02*
X154000D01*
Y247158D01*
X153875Y247492D01*
X153708Y247700D01*
X153375Y247783D01*
X153042Y247700D01*
X152833Y247450D01*
X152708Y247158D01*
Y246117D01*
G01Y247158D02*
X151500Y247783D01*
G01Y250050D02*
X154000D01*
X153500Y249550D01*
G01X151500D02*
Y250550D01*
G01Y253150D02*
X154000D01*
X153500Y252650D01*
G01X151500D02*
Y253650D01*
G01X159792Y44267D02*
X159917Y44017D01*
X160000Y43725D01*
Y43392D01*
X159875Y43017D01*
X159667Y42725D01*
X159417Y42517D01*
X159000Y42350D01*
X158625Y42308D01*
X158250Y42392D01*
X158000Y42517D01*
X157750Y42767D01*
X157583Y43058D01*
X157500Y43350D01*
Y43642D01*
X157583Y43933D01*
X157708Y44183D01*
X157875Y44392D01*
G01X159583Y45658D02*
X159833Y45908D01*
X159958Y46200D01*
X160000Y46533D01*
X159917Y46950D01*
X159708Y47242D01*
X159458Y47325D01*
X159208Y47283D01*
X159000Y47117D01*
X158583Y46283D01*
X158292Y45908D01*
X157875Y45658D01*
X157500Y45575D01*
Y47325D01*
G01X158542Y48758D02*
X158833Y49050D01*
X159000Y49300D01*
X159083Y49633D01*
X159000Y49925D01*
X158833Y50133D01*
X158583Y50300D01*
X158292Y50342D01*
X158042Y50300D01*
X157792Y50133D01*
X157583Y49883D01*
X157500Y49592D01*
X157583Y49258D01*
X157833Y48967D01*
X158208Y48800D01*
X158625Y48758D01*
X159167Y48842D01*
X159458Y48967D01*
X159750Y49175D01*
X159958Y49467D01*
X160000Y49758D01*
X159917Y50050D01*
X159708Y50258D01*
G01X158542Y51858D02*
X158833Y52150D01*
X159000Y52400D01*
X159083Y52733D01*
X159000Y53025D01*
X158833Y53233D01*
X158583Y53400D01*
X158292Y53442D01*
X158042Y53400D01*
X157792Y53233D01*
X157583Y52983D01*
X157500Y52692D01*
X157583Y52358D01*
X157833Y52067D01*
X158208Y51900D01*
X158625Y51858D01*
X159167Y51942D01*
X159458Y52067D01*
X159750Y52275D01*
X159958Y52567D01*
X160000Y52858D01*
X159917Y53150D01*
X159708Y53358D01*
G01X171792Y44267D02*
X171917Y44017D01*
X172000Y43725D01*
Y43392D01*
X171875Y43017D01*
X171667Y42725D01*
X171417Y42517D01*
X171000Y42350D01*
X170625Y42308D01*
X170250Y42392D01*
X170000Y42517D01*
X169750Y42767D01*
X169583Y43058D01*
X169500Y43350D01*
Y43642D01*
X169583Y43933D01*
X169708Y44183D01*
X169875Y44392D01*
G01X171583Y45658D02*
X171833Y45908D01*
X171958Y46200D01*
X172000Y46533D01*
X171917Y46950D01*
X171708Y47242D01*
X171458Y47325D01*
X171208Y47283D01*
X171000Y47117D01*
X170583Y46283D01*
X170292Y45908D01*
X169875Y45658D01*
X169500Y45575D01*
Y47325D01*
G01X170542Y48758D02*
X170833Y49050D01*
X171000Y49300D01*
X171083Y49633D01*
X171000Y49925D01*
X170833Y50133D01*
X170583Y50300D01*
X170292Y50342D01*
X170042Y50300D01*
X169792Y50133D01*
X169583Y49883D01*
X169500Y49592D01*
X169583Y49258D01*
X169833Y48967D01*
X170208Y48800D01*
X170625Y48758D01*
X171167Y48842D01*
X171458Y48967D01*
X171750Y49175D01*
X171958Y49467D01*
X172000Y49758D01*
X171917Y50050D01*
X171708Y50258D01*
G01X169875Y51733D02*
X169667Y51983D01*
X169542Y52275D01*
X169500Y52650D01*
X169583Y53025D01*
X169750Y53317D01*
X170042Y53525D01*
X170375Y53567D01*
X170708Y53483D01*
X170917Y53275D01*
X171083Y52983D01*
X171125Y52692D01*
X171083Y52400D01*
X170917Y52025D01*
X172000Y52150D01*
Y53275D01*
G01X205500Y77300D02*
X157100D01*
Y97900D01*
X205500D01*
Y90200D01*
G01X172000Y116517D02*
X174500D01*
Y117558D01*
X174375Y117892D01*
X174208Y118100D01*
X173875Y118183D01*
X173542Y118100D01*
X173333Y117850D01*
X173208Y117558D01*
Y116517D01*
G01Y117558D02*
X172000Y118183D01*
G01Y120950D02*
X174500D01*
X172708Y119408D01*
Y121492D01*
G01X172000Y124050D02*
X174500D01*
X172708Y122508D01*
Y124592D01*
G01X173042Y125858D02*
X173333Y126150D01*
X173500Y126400D01*
X173583Y126733D01*
X173500Y127025D01*
X173333Y127233D01*
X173083Y127400D01*
X172792Y127442D01*
X172542Y127400D01*
X172292Y127233D01*
X172083Y126983D01*
X172000Y126692D01*
X172083Y126358D01*
X172333Y126067D01*
X172708Y125900D01*
X173125Y125858D01*
X173667Y125942D01*
X173958Y126067D01*
X174250Y126275D01*
X174458Y126567D01*
X174500Y126858D01*
X174417Y127150D01*
X174208Y127358D01*
G01X162000Y116017D02*
X164500D01*
Y117058D01*
X164375Y117392D01*
X164208Y117600D01*
X163875Y117683D01*
X163542Y117600D01*
X163333Y117350D01*
X163208Y117058D01*
Y116017D01*
G01Y117058D02*
X162000Y117683D01*
G01X162500Y119033D02*
X162208Y119283D01*
X162042Y119617D01*
X162000Y119992D01*
X162042Y120325D01*
X162250Y120658D01*
X162500Y120867D01*
X162750Y120908D01*
X163042Y120825D01*
X163250Y120533D01*
X163333Y120242D01*
Y119867D01*
G01Y120242D02*
X163458Y120492D01*
X163667Y120700D01*
X163917Y120783D01*
X164167Y120700D01*
X164375Y120492D01*
X164500Y120117D01*
X164458Y119742D01*
X164292Y119367D01*
G01X164083Y122258D02*
X164333Y122508D01*
X164458Y122800D01*
X164500Y123133D01*
X164417Y123550D01*
X164208Y123842D01*
X163958Y123925D01*
X163708Y123883D01*
X163500Y123717D01*
X163083Y122883D01*
X162792Y122508D01*
X162375Y122258D01*
X162000Y122175D01*
Y123925D01*
G01Y126150D02*
X162042Y126442D01*
X162167Y126775D01*
X162375Y126983D01*
X162667Y127067D01*
X162958Y126983D01*
X163208Y126733D01*
X163333Y126358D01*
Y125942D01*
X163417Y125692D01*
X163625Y125483D01*
X163917Y125400D01*
X164208Y125525D01*
X164417Y125817D01*
X164500Y126150D01*
X164417Y126483D01*
X164208Y126775D01*
X163917Y126900D01*
X163625Y126817D01*
X163417Y126608D01*
X163333Y126358D01*
Y125942D01*
X163208Y125567D01*
X162958Y125317D01*
X162667Y125233D01*
X162375Y125317D01*
X162167Y125525D01*
X162042Y125858D01*
X162000Y126150D01*
G01X166000Y116017D02*
X168500D01*
Y117058D01*
X168375Y117392D01*
X168208Y117600D01*
X167875Y117683D01*
X167542Y117600D01*
X167333Y117350D01*
X167208Y117058D01*
Y116017D01*
G01Y117058D02*
X166000Y117683D01*
G01X166500Y119033D02*
X166208Y119283D01*
X166042Y119617D01*
X166000Y119992D01*
X166042Y120325D01*
X166250Y120658D01*
X166500Y120867D01*
X166750Y120908D01*
X167042Y120825D01*
X167250Y120533D01*
X167333Y120242D01*
Y119867D01*
G01Y120242D02*
X167458Y120492D01*
X167667Y120700D01*
X167917Y120783D01*
X168167Y120700D01*
X168375Y120492D01*
X168500Y120117D01*
X168458Y119742D01*
X168292Y119367D01*
G01X168083Y122258D02*
X168333Y122508D01*
X168458Y122800D01*
X168500Y123133D01*
X168417Y123550D01*
X168208Y123842D01*
X167958Y123925D01*
X167708Y123883D01*
X167500Y123717D01*
X167083Y122883D01*
X166792Y122508D01*
X166375Y122258D01*
X166000Y122175D01*
Y123925D01*
G01Y126067D02*
X166542Y126150D01*
X167000Y126275D01*
X167417Y126442D01*
X167875Y126650D01*
X168500Y126983D01*
Y125317D01*
G01X175983Y129500D02*
Y132000D01*
X174942D01*
X174608Y131875D01*
X174400Y131708D01*
X174317Y131375D01*
X174400Y131042D01*
X174650Y130833D01*
X174942Y130708D01*
X175983D01*
G01X174942D02*
X174317Y129500D01*
G01X171550D02*
Y132000D01*
X173092Y130208D01*
X171008D01*
G01X169867Y130000D02*
X169617Y129708D01*
X169283Y129542D01*
X168908Y129500D01*
X168575Y129542D01*
X168242Y129750D01*
X168033Y130000D01*
X167992Y130250D01*
X168075Y130542D01*
X168367Y130750D01*
X168658Y130833D01*
X169033D01*
G01X168658D02*
X168408Y130958D01*
X168200Y131167D01*
X168117Y131417D01*
X168200Y131667D01*
X168408Y131875D01*
X168783Y132000D01*
X169158Y131958D01*
X169533Y131792D01*
G01X165850Y129500D02*
Y132000D01*
X166350Y131500D01*
G01Y129500D02*
X165350D01*
G01X156500Y160500D02*
Y174000D01*
X159500D01*
Y178500D01*
X163000D01*
Y182500D01*
G01X177517Y176500D02*
Y174708D01*
X177350Y174333D01*
X177017Y174083D01*
X176600Y174000D01*
X176183Y174083D01*
X175850Y174333D01*
X175683Y174708D01*
Y176500D01*
G01X173500Y174000D02*
Y176500D01*
X174000Y176000D01*
G01Y174000D02*
X173000D01*
G01X171192Y175042D02*
X170900Y175333D01*
X170650Y175500D01*
X170317Y175583D01*
X170025Y175500D01*
X169817Y175333D01*
X169650Y175083D01*
X169608Y174792D01*
X169650Y174542D01*
X169817Y174292D01*
X170067Y174083D01*
X170358Y174000D01*
X170692Y174083D01*
X170983Y174333D01*
X171150Y174708D01*
X171192Y175125D01*
X171108Y175667D01*
X170983Y175958D01*
X170775Y176250D01*
X170483Y176458D01*
X170192Y176500D01*
X169900Y176417D01*
X169692Y176208D01*
G01X163500Y206500D02*
Y200500D01*
X160000D01*
Y198500D01*
X157500D01*
Y195500D01*
G01Y191500D02*
Y189500D01*
X161500D01*
G01X163000Y188000D02*
Y186500D01*
G01X159000Y216500D02*
Y210500D01*
X160500D01*
G01X164000Y245000D02*
Y254000D01*
X170000D01*
Y258000D01*
X195000D01*
Y263500D01*
X205000D01*
Y238500D01*
X190000D01*
Y223000D01*
X183500D01*
Y220500D01*
X170500D01*
Y236500D01*
X165500D01*
G01X166000Y238467D02*
X168500D01*
Y239467D01*
X168375Y239800D01*
X168083Y240050D01*
X167750Y240133D01*
X167417Y240050D01*
X167167Y239842D01*
X167042Y239467D01*
Y238467D01*
G01X168292Y243317D02*
X168417Y243067D01*
X168500Y242775D01*
Y242442D01*
X168375Y242067D01*
X168167Y241775D01*
X167917Y241567D01*
X167500Y241400D01*
X167125Y241358D01*
X166750Y241442D01*
X166500Y241567D01*
X166250Y241817D01*
X166083Y242108D01*
X166000Y242400D01*
Y242692D01*
X166083Y242983D01*
X166208Y243233D01*
X166375Y243442D01*
G01X166000Y245500D02*
X168500D01*
X168000Y245000D01*
G01X166000D02*
Y246000D01*
G01X166500Y247683D02*
X166208Y247933D01*
X166042Y248267D01*
X166000Y248642D01*
X166042Y248975D01*
X166250Y249308D01*
X166500Y249517D01*
X166750Y249558D01*
X167042Y249475D01*
X167250Y249183D01*
X167333Y248892D01*
Y248517D01*
G01Y248892D02*
X167458Y249142D01*
X167667Y249350D01*
X167917Y249433D01*
X168167Y249350D01*
X168375Y249142D01*
X168500Y248767D01*
X168458Y248392D01*
X168292Y248017D01*
G01X168083Y250908D02*
X168333Y251158D01*
X168458Y251450D01*
X168500Y251783D01*
X168417Y252200D01*
X168208Y252492D01*
X167958Y252575D01*
X167708Y252533D01*
X167500Y252367D01*
X167083Y251533D01*
X166792Y251158D01*
X166375Y250908D01*
X166000Y250825D01*
Y252575D01*
G01X170500Y238467D02*
X173000D01*
Y239467D01*
X172875Y239800D01*
X172583Y240050D01*
X172250Y240133D01*
X171917Y240050D01*
X171667Y239842D01*
X171542Y239467D01*
Y238467D01*
G01X170500Y241567D02*
X173000D01*
Y242608D01*
X172875Y242942D01*
X172708Y243150D01*
X172375Y243233D01*
X172042Y243150D01*
X171833Y242900D01*
X171708Y242608D01*
Y241567D01*
G01Y242608D02*
X170500Y243233D01*
G01Y245500D02*
X173000D01*
X172500Y245000D01*
G01X170500D02*
Y246000D01*
G01Y248600D02*
X170542Y248892D01*
X170667Y249225D01*
X170875Y249433D01*
X171167Y249517D01*
X171458Y249433D01*
X171708Y249183D01*
X171833Y248808D01*
Y248392D01*
X171917Y248142D01*
X172125Y247933D01*
X172417Y247850D01*
X172708Y247975D01*
X172917Y248267D01*
X173000Y248600D01*
X172917Y248933D01*
X172708Y249225D01*
X172417Y249350D01*
X172125Y249267D01*
X171917Y249058D01*
X171833Y248808D01*
Y248392D01*
X171708Y248017D01*
X171458Y247767D01*
X171167Y247683D01*
X170875Y247767D01*
X170667Y247975D01*
X170542Y248308D01*
X170500Y248600D01*
G01X172583Y250908D02*
X172833Y251158D01*
X172958Y251450D01*
X173000Y251783D01*
X172917Y252200D01*
X172708Y252492D01*
X172458Y252575D01*
X172208Y252533D01*
X172000Y252367D01*
X171583Y251533D01*
X171292Y251158D01*
X170875Y250908D01*
X170500Y250825D01*
Y252575D01*
G01X175792Y44267D02*
X175917Y44017D01*
X176000Y43725D01*
Y43392D01*
X175875Y43017D01*
X175667Y42725D01*
X175417Y42517D01*
X175000Y42350D01*
X174625Y42308D01*
X174250Y42392D01*
X174000Y42517D01*
X173750Y42767D01*
X173583Y43058D01*
X173500Y43350D01*
Y43642D01*
X173583Y43933D01*
X173708Y44183D01*
X173875Y44392D01*
G01X175583Y45658D02*
X175833Y45908D01*
X175958Y46200D01*
X176000Y46533D01*
X175917Y46950D01*
X175708Y47242D01*
X175458Y47325D01*
X175208Y47283D01*
X175000Y47117D01*
X174583Y46283D01*
X174292Y45908D01*
X173875Y45658D01*
X173500Y45575D01*
Y47325D01*
G01X174542Y48758D02*
X174833Y49050D01*
X175000Y49300D01*
X175083Y49633D01*
X175000Y49925D01*
X174833Y50133D01*
X174583Y50300D01*
X174292Y50342D01*
X174042Y50300D01*
X173792Y50133D01*
X173583Y49883D01*
X173500Y49592D01*
X173583Y49258D01*
X173833Y48967D01*
X174208Y48800D01*
X174625Y48758D01*
X175167Y48842D01*
X175458Y48967D01*
X175750Y49175D01*
X175958Y49467D01*
X176000Y49758D01*
X175917Y50050D01*
X175708Y50258D01*
G01X173500Y53150D02*
X176000D01*
X174208Y51608D01*
Y53692D01*
G01X187292Y44267D02*
X187417Y44017D01*
X187500Y43725D01*
Y43392D01*
X187375Y43017D01*
X187167Y42725D01*
X186917Y42517D01*
X186500Y42350D01*
X186125Y42308D01*
X185750Y42392D01*
X185500Y42517D01*
X185250Y42767D01*
X185083Y43058D01*
X185000Y43350D01*
Y43642D01*
X185083Y43933D01*
X185208Y44183D01*
X185375Y44392D01*
G01X187083Y45658D02*
X187333Y45908D01*
X187458Y46200D01*
X187500Y46533D01*
X187417Y46950D01*
X187208Y47242D01*
X186958Y47325D01*
X186708Y47283D01*
X186500Y47117D01*
X186083Y46283D01*
X185792Y45908D01*
X185375Y45658D01*
X185000Y45575D01*
Y47325D01*
G01X186042Y48758D02*
X186333Y49050D01*
X186500Y49300D01*
X186583Y49633D01*
X186500Y49925D01*
X186333Y50133D01*
X186083Y50300D01*
X185792Y50342D01*
X185542Y50300D01*
X185292Y50133D01*
X185083Y49883D01*
X185000Y49592D01*
X185083Y49258D01*
X185333Y48967D01*
X185708Y48800D01*
X186125Y48758D01*
X186667Y48842D01*
X186958Y48967D01*
X187250Y49175D01*
X187458Y49467D01*
X187500Y49758D01*
X187417Y50050D01*
X187208Y50258D01*
G01X185500Y51733D02*
X185208Y51983D01*
X185042Y52317D01*
X185000Y52692D01*
X185042Y53025D01*
X185250Y53358D01*
X185500Y53567D01*
X185750Y53608D01*
X186042Y53525D01*
X186250Y53233D01*
X186333Y52942D01*
Y52567D01*
G01Y52942D02*
X186458Y53192D01*
X186667Y53400D01*
X186917Y53483D01*
X187167Y53400D01*
X187375Y53192D01*
X187500Y52817D01*
X187458Y52442D01*
X187292Y52067D01*
G01X195500Y55000D02*
Y69500D01*
X176500D01*
G01X176000Y116517D02*
X178500D01*
Y117558D01*
X178375Y117892D01*
X178208Y118100D01*
X177875Y118183D01*
X177542Y118100D01*
X177333Y117850D01*
X177208Y117558D01*
Y116517D01*
G01Y117558D02*
X176000Y118183D01*
G01Y120950D02*
X178500D01*
X176708Y119408D01*
Y121492D01*
G01X176500Y122633D02*
X176208Y122883D01*
X176042Y123217D01*
X176000Y123592D01*
X176042Y123925D01*
X176250Y124258D01*
X176500Y124467D01*
X176750Y124508D01*
X177042Y124425D01*
X177250Y124133D01*
X177333Y123842D01*
Y123467D01*
G01Y123842D02*
X177458Y124092D01*
X177667Y124300D01*
X177917Y124383D01*
X178167Y124300D01*
X178375Y124092D01*
X178500Y123717D01*
X178458Y123342D01*
X178292Y122967D01*
G01X176000Y126567D02*
X176542Y126650D01*
X177000Y126775D01*
X177417Y126942D01*
X177875Y127150D01*
X178500Y127483D01*
Y125817D01*
G01X180000Y116517D02*
X182500D01*
Y117558D01*
X182375Y117892D01*
X182208Y118100D01*
X181875Y118183D01*
X181542Y118100D01*
X181333Y117850D01*
X181208Y117558D01*
Y116517D01*
G01Y117558D02*
X180000Y118183D01*
G01Y120950D02*
X182500D01*
X180708Y119408D01*
Y121492D01*
G01X180500Y122633D02*
X180208Y122883D01*
X180042Y123217D01*
X180000Y123592D01*
X180042Y123925D01*
X180250Y124258D01*
X180500Y124467D01*
X180750Y124508D01*
X181042Y124425D01*
X181250Y124133D01*
X181333Y123842D01*
Y123467D01*
G01Y123842D02*
X181458Y124092D01*
X181667Y124300D01*
X181917Y124383D01*
X182167Y124300D01*
X182375Y124092D01*
X182500Y123717D01*
X182458Y123342D01*
X182292Y122967D01*
G01X180000Y126650D02*
X180042Y126942D01*
X180167Y127275D01*
X180375Y127483D01*
X180667Y127567D01*
X180958Y127483D01*
X181208Y127233D01*
X181333Y126858D01*
Y126442D01*
X181417Y126192D01*
X181625Y125983D01*
X181917Y125900D01*
X182208Y126025D01*
X182417Y126317D01*
X182500Y126650D01*
X182417Y126983D01*
X182208Y127275D01*
X181917Y127400D01*
X181625Y127317D01*
X181417Y127108D01*
X181333Y126858D01*
Y126442D01*
X181208Y126067D01*
X180958Y125817D01*
X180667Y125733D01*
X180375Y125817D01*
X180167Y126025D01*
X180042Y126358D01*
X180000Y126650D01*
G01X183500Y116017D02*
X186000D01*
Y117058D01*
X185875Y117392D01*
X185708Y117600D01*
X185375Y117683D01*
X185042Y117600D01*
X184833Y117350D01*
X184708Y117058D01*
Y116017D01*
G01Y117058D02*
X183500Y117683D01*
G01Y120450D02*
X186000D01*
X184208Y118908D01*
Y120992D01*
G01X183500Y123550D02*
X186000D01*
X184208Y122008D01*
Y124092D01*
G01X183500Y126067D02*
X184042Y126150D01*
X184500Y126275D01*
X184917Y126442D01*
X185375Y126650D01*
X186000Y126983D01*
Y125317D01*
G01X187500Y123017D02*
X190000D01*
Y124058D01*
X189875Y124392D01*
X189708Y124600D01*
X189375Y124683D01*
X189042Y124600D01*
X188833Y124350D01*
X188708Y124058D01*
Y123017D01*
G01Y124058D02*
X187500Y124683D01*
G01Y127450D02*
X190000D01*
X188208Y125908D01*
Y127992D01*
G01X187875Y129133D02*
X187667Y129383D01*
X187542Y129675D01*
X187500Y130050D01*
X187583Y130425D01*
X187750Y130717D01*
X188042Y130925D01*
X188375Y130967D01*
X188708Y130883D01*
X188917Y130675D01*
X189083Y130383D01*
X189125Y130092D01*
X189083Y129800D01*
X188917Y129425D01*
X190000Y129550D01*
Y130675D01*
G01Y133150D02*
X189917Y132817D01*
X189708Y132567D01*
X189458Y132400D01*
X189125Y132275D01*
X188750Y132233D01*
X188375Y132275D01*
X188042Y132400D01*
X187792Y132567D01*
X187583Y132817D01*
X187500Y133150D01*
X187583Y133483D01*
X187792Y133733D01*
X188042Y133900D01*
X188375Y134025D01*
X188750Y134067D01*
X189125Y134025D01*
X189458Y133900D01*
X189708Y133733D01*
X189917Y133483D01*
X190000Y133150D01*
G01X185000Y209017D02*
X187500D01*
Y210058D01*
X187375Y210392D01*
X187208Y210600D01*
X186875Y210683D01*
X186542Y210600D01*
X186333Y210350D01*
X186208Y210058D01*
Y209017D01*
G01Y210058D02*
X185000Y210683D01*
G01Y212950D02*
X187500D01*
X187000Y212450D01*
G01X185000D02*
Y213450D01*
G01X187083Y215258D02*
X187333Y215508D01*
X187458Y215800D01*
X187500Y216133D01*
X187417Y216550D01*
X187208Y216842D01*
X186958Y216925D01*
X186708Y216883D01*
X186500Y216717D01*
X186083Y215883D01*
X185792Y215508D01*
X185375Y215258D01*
X185000Y215175D01*
Y216925D01*
G01X186042Y218358D02*
X186333Y218650D01*
X186500Y218900D01*
X186583Y219233D01*
X186500Y219525D01*
X186333Y219733D01*
X186083Y219900D01*
X185792Y219942D01*
X185542Y219900D01*
X185292Y219733D01*
X185083Y219483D01*
X185000Y219192D01*
X185083Y218858D01*
X185333Y218567D01*
X185708Y218400D01*
X186125Y218358D01*
X186667Y218442D01*
X186958Y218567D01*
X187250Y218775D01*
X187458Y219067D01*
X187500Y219358D01*
X187417Y219650D01*
X187208Y219858D01*
G01X186683Y231792D02*
X186933Y231917D01*
X187225Y232000D01*
X187558D01*
X187933Y231875D01*
X188225Y231667D01*
X188433Y231417D01*
X188600Y231000D01*
X188642Y230625D01*
X188558Y230250D01*
X188433Y230000D01*
X188183Y229750D01*
X187892Y229583D01*
X187600Y229500D01*
X187308D01*
X187017Y229583D01*
X186767Y229708D01*
X186558Y229875D01*
G01X185292Y230542D02*
X185000Y230833D01*
X184750Y231000D01*
X184417Y231083D01*
X184125Y231000D01*
X183917Y230833D01*
X183750Y230583D01*
X183708Y230292D01*
X183750Y230042D01*
X183917Y229792D01*
X184167Y229583D01*
X184458Y229500D01*
X184792Y229583D01*
X185083Y229833D01*
X185250Y230208D01*
X185292Y230625D01*
X185208Y231167D01*
X185083Y231458D01*
X184875Y231750D01*
X184583Y231958D01*
X184292Y232000D01*
X184000Y231917D01*
X183792Y231708D01*
G01X182317Y229875D02*
X182067Y229667D01*
X181775Y229542D01*
X181400Y229500D01*
X181025Y229583D01*
X180733Y229750D01*
X180525Y230042D01*
X180483Y230375D01*
X180567Y230708D01*
X180775Y230917D01*
X181067Y231083D01*
X181358Y231125D01*
X181650Y231083D01*
X182025Y230917D01*
X181900Y232000D01*
X180775D01*
G01X174000Y226575D02*
X176500Y228325D01*
G01Y226575D02*
X174000Y228325D01*
G01X176083Y229758D02*
X176333Y230008D01*
X176458Y230300D01*
X176500Y230633D01*
X176417Y231050D01*
X176208Y231342D01*
X175958Y231425D01*
X175708Y231383D01*
X175500Y231217D01*
X175083Y230383D01*
X174792Y230008D01*
X174375Y229758D01*
X174000Y229675D01*
Y231425D01*
G01X188433Y225500D02*
Y228000D01*
X187392D01*
X187058Y227875D01*
X186850Y227708D01*
X186767Y227375D01*
X186850Y227042D01*
X187100Y226833D01*
X187392Y226708D01*
X188433D01*
G01X187392D02*
X186767Y225500D01*
G01X184500D02*
Y228000D01*
X185000Y227500D01*
G01Y225500D02*
X184000D01*
G01X180900D02*
Y228000D01*
X182442Y226208D01*
X180358D01*
G01X186683Y240292D02*
X186933Y240417D01*
X187225Y240500D01*
X187558D01*
X187933Y240375D01*
X188225Y240167D01*
X188433Y239917D01*
X188600Y239500D01*
X188642Y239125D01*
X188558Y238750D01*
X188433Y238500D01*
X188183Y238250D01*
X187892Y238083D01*
X187600Y238000D01*
X187308D01*
X187017Y238083D01*
X186767Y238208D01*
X186558Y238375D01*
G01X185292Y239042D02*
X185000Y239333D01*
X184750Y239500D01*
X184417Y239583D01*
X184125Y239500D01*
X183917Y239333D01*
X183750Y239083D01*
X183708Y238792D01*
X183750Y238542D01*
X183917Y238292D01*
X184167Y238083D01*
X184458Y238000D01*
X184792Y238083D01*
X185083Y238333D01*
X185250Y238708D01*
X185292Y239125D01*
X185208Y239667D01*
X185083Y239958D01*
X184875Y240250D01*
X184583Y240458D01*
X184292Y240500D01*
X184000Y240417D01*
X183792Y240208D01*
G01X182192Y239042D02*
X181900Y239333D01*
X181650Y239500D01*
X181317Y239583D01*
X181025Y239500D01*
X180817Y239333D01*
X180650Y239083D01*
X180608Y238792D01*
X180650Y238542D01*
X180817Y238292D01*
X181067Y238083D01*
X181358Y238000D01*
X181692Y238083D01*
X181983Y238333D01*
X182150Y238708D01*
X182192Y239125D01*
X182108Y239667D01*
X181983Y239958D01*
X181775Y240250D01*
X181483Y240458D01*
X181192Y240500D01*
X180900Y240417D01*
X180692Y240208D01*
G01X177500Y238117D02*
X175000D01*
Y239783D01*
G01X177083Y241258D02*
X177333Y241508D01*
X177458Y241800D01*
X177500Y242133D01*
X177417Y242550D01*
X177208Y242842D01*
X176958Y242925D01*
X176708Y242883D01*
X176500Y242717D01*
X176083Y241883D01*
X175792Y241508D01*
X175375Y241258D01*
X175000Y241175D01*
Y242925D01*
G01X188483Y233500D02*
Y236000D01*
X187442D01*
X187108Y235875D01*
X186900Y235708D01*
X186817Y235375D01*
X186900Y235042D01*
X187150Y234833D01*
X187442Y234708D01*
X188483D01*
G01X187442D02*
X186817Y233500D01*
G01X184550D02*
Y236000D01*
X185050Y235500D01*
G01Y233500D02*
X184050D01*
G01X182242Y235583D02*
X181992Y235833D01*
X181700Y235958D01*
X181367Y236000D01*
X180950Y235917D01*
X180658Y235708D01*
X180575Y235458D01*
X180617Y235208D01*
X180783Y235000D01*
X181617Y234583D01*
X181992Y234292D01*
X182242Y233875D01*
X182325Y233500D01*
X180575D01*
G01X179267Y233875D02*
X179017Y233667D01*
X178725Y233542D01*
X178350Y233500D01*
X177975Y233583D01*
X177683Y233750D01*
X177475Y234042D01*
X177433Y234375D01*
X177517Y234708D01*
X177725Y234917D01*
X178017Y235083D01*
X178308Y235125D01*
X178600Y235083D01*
X178975Y234917D01*
X178850Y236000D01*
X177725D01*
G01X190983Y250300D02*
Y252800D01*
X189942D01*
X189608Y252675D01*
X189400Y252508D01*
X189317Y252175D01*
X189400Y251842D01*
X189650Y251633D01*
X189942Y251508D01*
X190983D01*
G01X189942D02*
X189317Y250300D01*
G01X187050D02*
Y252800D01*
X187550Y252300D01*
G01Y250300D02*
X186550D01*
G01X184742Y252383D02*
X184492Y252633D01*
X184200Y252758D01*
X183867Y252800D01*
X183450Y252717D01*
X183158Y252508D01*
X183075Y252258D01*
X183117Y252008D01*
X183283Y251800D01*
X184117Y251383D01*
X184492Y251092D01*
X184742Y250675D01*
X184825Y250300D01*
X183075D01*
G01X180850D02*
X180558Y250342D01*
X180225Y250467D01*
X180017Y250675D01*
X179933Y250967D01*
X180017Y251258D01*
X180267Y251508D01*
X180642Y251633D01*
X181058D01*
X181308Y251717D01*
X181517Y251925D01*
X181600Y252217D01*
X181475Y252508D01*
X181183Y252717D01*
X180850Y252800D01*
X180517Y252717D01*
X180225Y252508D01*
X180100Y252217D01*
X180183Y251925D01*
X180392Y251717D01*
X180642Y251633D01*
X181058D01*
X181433Y251508D01*
X181683Y251258D01*
X181767Y250967D01*
X181683Y250675D01*
X181475Y250467D01*
X181142Y250342D01*
X180850Y250300D01*
G01X190983Y254300D02*
Y256800D01*
X189942D01*
X189608Y256675D01*
X189400Y256508D01*
X189317Y256175D01*
X189400Y255842D01*
X189650Y255633D01*
X189942Y255508D01*
X190983D01*
G01X189942D02*
X189317Y254300D01*
G01X187050D02*
Y256800D01*
X187550Y256300D01*
G01Y254300D02*
X186550D01*
G01X184742Y256383D02*
X184492Y256633D01*
X184200Y256758D01*
X183867Y256800D01*
X183450Y256717D01*
X183158Y256508D01*
X183075Y256258D01*
X183117Y256008D01*
X183283Y255800D01*
X184117Y255383D01*
X184492Y255092D01*
X184742Y254675D01*
X184825Y254300D01*
X183075D01*
G01X181558Y254592D02*
X181267Y254383D01*
X180933Y254300D01*
X180600Y254383D01*
X180308Y254633D01*
X180100Y255008D01*
X180017Y255383D01*
Y255842D01*
X180100Y256217D01*
X180308Y256550D01*
X180558Y256717D01*
X180850Y256800D01*
X181183Y256717D01*
X181433Y256550D01*
X181600Y256300D01*
X181683Y255967D01*
X181600Y255675D01*
X181392Y255383D01*
X181142Y255217D01*
X180850Y255175D01*
X180517Y255258D01*
X180267Y255467D01*
X180017Y255842D01*
G01X175000Y245517D02*
X177500D01*
Y246558D01*
X177375Y246892D01*
X177208Y247100D01*
X176875Y247183D01*
X176542Y247100D01*
X176333Y246850D01*
X176208Y246558D01*
Y245517D01*
G01Y246558D02*
X175000Y247183D01*
G01Y249450D02*
X177500D01*
X177000Y248950D01*
G01X175000D02*
Y249950D01*
G01X175500Y251633D02*
X175208Y251883D01*
X175042Y252217D01*
X175000Y252592D01*
X175042Y252925D01*
X175250Y253258D01*
X175500Y253467D01*
X175750Y253508D01*
X176042Y253425D01*
X176250Y253133D01*
X176333Y252842D01*
Y252467D01*
G01Y252842D02*
X176458Y253092D01*
X176667Y253300D01*
X176917Y253383D01*
X177167Y253300D01*
X177375Y253092D01*
X177500Y252717D01*
X177458Y252342D01*
X177292Y251967D01*
G01X175000Y255567D02*
X175542Y255650D01*
X176000Y255775D01*
X176417Y255942D01*
X176875Y256150D01*
X177500Y256483D01*
Y254817D01*
G01X190983Y246000D02*
Y248500D01*
X189942D01*
X189608Y248375D01*
X189400Y248208D01*
X189317Y247875D01*
X189400Y247542D01*
X189650Y247333D01*
X189942Y247208D01*
X190983D01*
G01X189942D02*
X189317Y246000D01*
G01X187050D02*
Y248500D01*
X187550Y248000D01*
G01Y246000D02*
X186550D01*
G01X184742Y248083D02*
X184492Y248333D01*
X184200Y248458D01*
X183867Y248500D01*
X183450Y248417D01*
X183158Y248208D01*
X183075Y247958D01*
X183117Y247708D01*
X183283Y247500D01*
X184117Y247083D01*
X184492Y246792D01*
X184742Y246375D01*
X184825Y246000D01*
X183075D01*
G01X180933D02*
X180850Y246542D01*
X180725Y247000D01*
X180558Y247417D01*
X180350Y247875D01*
X180017Y248500D01*
X181683D01*
G01X191292Y44267D02*
X191417Y44017D01*
X191500Y43725D01*
Y43392D01*
X191375Y43017D01*
X191167Y42725D01*
X190917Y42517D01*
X190500Y42350D01*
X190125Y42308D01*
X189750Y42392D01*
X189500Y42517D01*
X189250Y42767D01*
X189083Y43058D01*
X189000Y43350D01*
Y43642D01*
X189083Y43933D01*
X189208Y44183D01*
X189375Y44392D01*
G01X191083Y45658D02*
X191333Y45908D01*
X191458Y46200D01*
X191500Y46533D01*
X191417Y46950D01*
X191208Y47242D01*
X190958Y47325D01*
X190708Y47283D01*
X190500Y47117D01*
X190083Y46283D01*
X189792Y45908D01*
X189375Y45658D01*
X189000Y45575D01*
Y47325D01*
G01X190042Y48758D02*
X190333Y49050D01*
X190500Y49300D01*
X190583Y49633D01*
X190500Y49925D01*
X190333Y50133D01*
X190083Y50300D01*
X189792Y50342D01*
X189542Y50300D01*
X189292Y50133D01*
X189083Y49883D01*
X189000Y49592D01*
X189083Y49258D01*
X189333Y48967D01*
X189708Y48800D01*
X190125Y48758D01*
X190667Y48842D01*
X190958Y48967D01*
X191250Y49175D01*
X191458Y49467D01*
X191500Y49758D01*
X191417Y50050D01*
X191208Y50258D01*
G01X191083Y51858D02*
X191333Y52108D01*
X191458Y52400D01*
X191500Y52733D01*
X191417Y53150D01*
X191208Y53442D01*
X190958Y53525D01*
X190708Y53483D01*
X190500Y53317D01*
X190083Y52483D01*
X189792Y52108D01*
X189375Y51858D01*
X189000Y51775D01*
Y53525D01*
G01X205983Y44000D02*
Y46500D01*
X204942D01*
X204608Y46375D01*
X204400Y46208D01*
X204317Y45875D01*
X204400Y45542D01*
X204650Y45333D01*
X204942Y45208D01*
X205983D01*
G01X204942D02*
X204317Y44000D01*
G01X201550D02*
Y46500D01*
X203092Y44708D01*
X201008D01*
G01X198950Y44000D02*
Y46500D01*
X199450Y46000D01*
G01Y44000D02*
X198450D01*
G01X196767Y44500D02*
X196517Y44208D01*
X196183Y44042D01*
X195808Y44000D01*
X195475Y44042D01*
X195142Y44250D01*
X194933Y44500D01*
X194892Y44750D01*
X194975Y45042D01*
X195267Y45250D01*
X195558Y45333D01*
X195933D01*
G01X195558D02*
X195308Y45458D01*
X195100Y45667D01*
X195017Y45917D01*
X195100Y46167D01*
X195308Y46375D01*
X195683Y46500D01*
X196058Y46458D01*
X196433Y46292D01*
G01X202792Y53767D02*
X202917Y53517D01*
X203000Y53225D01*
Y52892D01*
X202875Y52517D01*
X202667Y52225D01*
X202417Y52017D01*
X202000Y51850D01*
X201625Y51808D01*
X201250Y51892D01*
X201000Y52017D01*
X200750Y52267D01*
X200583Y52558D01*
X200500Y52850D01*
Y53142D01*
X200583Y53433D01*
X200708Y53683D01*
X200875Y53892D01*
G01X202583Y55158D02*
X202833Y55408D01*
X202958Y55700D01*
X203000Y56033D01*
X202917Y56450D01*
X202708Y56742D01*
X202458Y56825D01*
X202208Y56783D01*
X202000Y56617D01*
X201583Y55783D01*
X201292Y55408D01*
X200875Y55158D01*
X200500Y55075D01*
Y56825D01*
G01X203000Y59050D02*
X202917Y58717D01*
X202708Y58467D01*
X202458Y58300D01*
X202125Y58175D01*
X201750Y58133D01*
X201375Y58175D01*
X201042Y58300D01*
X200792Y58467D01*
X200583Y58717D01*
X200500Y59050D01*
X200583Y59383D01*
X200792Y59633D01*
X201042Y59800D01*
X201375Y59925D01*
X201750Y59967D01*
X202125Y59925D01*
X202458Y59800D01*
X202708Y59633D01*
X202917Y59383D01*
X203000Y59050D01*
G01X200792Y61442D02*
X200583Y61733D01*
X200500Y62067D01*
X200583Y62400D01*
X200833Y62692D01*
X201208Y62900D01*
X201583Y62983D01*
X202042D01*
X202417Y62900D01*
X202750Y62692D01*
X202917Y62442D01*
X203000Y62150D01*
X202917Y61817D01*
X202750Y61567D01*
X202500Y61400D01*
X202167Y61317D01*
X201875Y61400D01*
X201583Y61608D01*
X201417Y61858D01*
X201375Y62150D01*
X201458Y62483D01*
X201667Y62733D01*
X202042Y62983D01*
G01X198792Y60767D02*
X198917Y60517D01*
X199000Y60225D01*
Y59892D01*
X198875Y59517D01*
X198667Y59225D01*
X198417Y59017D01*
X198000Y58850D01*
X197625Y58808D01*
X197250Y58892D01*
X197000Y59017D01*
X196750Y59267D01*
X196583Y59558D01*
X196500Y59850D01*
Y60142D01*
X196583Y60433D01*
X196708Y60683D01*
X196875Y60892D01*
G01X198583Y62158D02*
X198833Y62408D01*
X198958Y62700D01*
X199000Y63033D01*
X198917Y63450D01*
X198708Y63742D01*
X198458Y63825D01*
X198208Y63783D01*
X198000Y63617D01*
X197583Y62783D01*
X197292Y62408D01*
X196875Y62158D01*
X196500Y62075D01*
Y63825D01*
G01X199000Y66050D02*
X198917Y65717D01*
X198708Y65467D01*
X198458Y65300D01*
X198125Y65175D01*
X197750Y65133D01*
X197375Y65175D01*
X197042Y65300D01*
X196792Y65467D01*
X196583Y65717D01*
X196500Y66050D01*
X196583Y66383D01*
X196792Y66633D01*
X197042Y66800D01*
X197375Y66925D01*
X197750Y66967D01*
X198125Y66925D01*
X198458Y66800D01*
X198708Y66633D01*
X198917Y66383D01*
X199000Y66050D01*
G01X196500Y69150D02*
X199000D01*
X198500Y68650D01*
G01X196500D02*
Y69650D01*
G01X203933Y129500D02*
Y132000D01*
X202892D01*
X202558Y131875D01*
X202350Y131708D01*
X202267Y131375D01*
X202350Y131042D01*
X202600Y130833D01*
X202892Y130708D01*
X203933D01*
G01X202892D02*
X202267Y129500D01*
G01X200917Y130000D02*
X200667Y129708D01*
X200333Y129542D01*
X199958Y129500D01*
X199625Y129542D01*
X199292Y129750D01*
X199083Y130000D01*
X199042Y130250D01*
X199125Y130542D01*
X199417Y130750D01*
X199708Y130833D01*
X200083D01*
G01X199708D02*
X199458Y130958D01*
X199250Y131167D01*
X199167Y131417D01*
X199250Y131667D01*
X199458Y131875D01*
X199833Y132000D01*
X200208Y131958D01*
X200583Y131792D01*
G01X197692Y130542D02*
X197400Y130833D01*
X197150Y131000D01*
X196817Y131083D01*
X196525Y131000D01*
X196317Y130833D01*
X196150Y130583D01*
X196108Y130292D01*
X196150Y130042D01*
X196317Y129792D01*
X196567Y129583D01*
X196858Y129500D01*
X197192Y129583D01*
X197483Y129833D01*
X197650Y130208D01*
X197692Y130625D01*
X197608Y131167D01*
X197483Y131458D01*
X197275Y131750D01*
X196983Y131958D01*
X196692Y132000D01*
X196400Y131917D01*
X196192Y131708D01*
G01X193800Y129500D02*
Y132000D01*
X194300Y131500D01*
G01Y129500D02*
X193300D01*
G01X202183Y127792D02*
X202433Y127917D01*
X202725Y128000D01*
X203058D01*
X203433Y127875D01*
X203725Y127667D01*
X203933Y127417D01*
X204100Y127000D01*
X204142Y126625D01*
X204058Y126250D01*
X203933Y126000D01*
X203683Y125750D01*
X203392Y125583D01*
X203100Y125500D01*
X202808D01*
X202517Y125583D01*
X202267Y125708D01*
X202058Y125875D01*
G01X200792Y127583D02*
X200542Y127833D01*
X200250Y127958D01*
X199917Y128000D01*
X199500Y127917D01*
X199208Y127708D01*
X199125Y127458D01*
X199167Y127208D01*
X199333Y127000D01*
X200167Y126583D01*
X200542Y126292D01*
X200792Y125875D01*
X200875Y125500D01*
X199125D01*
G01X197692Y127583D02*
X197442Y127833D01*
X197150Y127958D01*
X196817Y128000D01*
X196400Y127917D01*
X196108Y127708D01*
X196025Y127458D01*
X196067Y127208D01*
X196233Y127000D01*
X197067Y126583D01*
X197442Y126292D01*
X197692Y125875D01*
X197775Y125500D01*
X196025D01*
G01X193883D02*
X193800Y126042D01*
X193675Y126500D01*
X193508Y126917D01*
X193300Y127375D01*
X192967Y128000D01*
X194633D01*
G01X203933Y136000D02*
Y133500D01*
X202267D01*
G01X200000D02*
Y136000D01*
X200500Y135500D01*
G01Y133500D02*
X199500D01*
G01X196900Y136000D02*
X197233Y135917D01*
X197483Y135708D01*
X197650Y135458D01*
X197775Y135125D01*
X197817Y134750D01*
X197775Y134375D01*
X197650Y134042D01*
X197483Y133792D01*
X197233Y133583D01*
X196900Y133500D01*
X196567Y133583D01*
X196317Y133792D01*
X196150Y134042D01*
X196025Y134375D01*
X195983Y134750D01*
X196025Y135125D01*
X196150Y135458D01*
X196317Y135708D01*
X196567Y135917D01*
X196900Y136000D01*
G01X191792Y158817D02*
X191917Y158567D01*
X192000Y158275D01*
Y157942D01*
X191875Y157567D01*
X191667Y157275D01*
X191417Y157067D01*
X191000Y156900D01*
X190625Y156858D01*
X190250Y156942D01*
X190000Y157067D01*
X189750Y157317D01*
X189583Y157608D01*
X189500Y157900D01*
Y158192D01*
X189583Y158483D01*
X189708Y158733D01*
X189875Y158942D01*
G01X191583Y160208D02*
X191833Y160458D01*
X191958Y160750D01*
X192000Y161083D01*
X191917Y161500D01*
X191708Y161792D01*
X191458Y161875D01*
X191208Y161833D01*
X191000Y161667D01*
X190583Y160833D01*
X190292Y160458D01*
X189875Y160208D01*
X189500Y160125D01*
Y161875D01*
G01Y164017D02*
X190042Y164100D01*
X190500Y164225D01*
X190917Y164392D01*
X191375Y164600D01*
X192000Y164933D01*
Y163267D01*
G01X203792Y158267D02*
X203917Y158017D01*
X204000Y157725D01*
Y157392D01*
X203875Y157017D01*
X203667Y156725D01*
X203417Y156517D01*
X203000Y156350D01*
X202625Y156308D01*
X202250Y156392D01*
X202000Y156517D01*
X201750Y156767D01*
X201583Y157058D01*
X201500Y157350D01*
Y157642D01*
X201583Y157933D01*
X201708Y158183D01*
X201875Y158392D01*
G01X201500Y160950D02*
X204000D01*
X202208Y159408D01*
Y161492D01*
G01X201500Y163550D02*
X204000D01*
X203500Y163050D01*
G01X201500D02*
Y164050D01*
G01X199792Y158317D02*
X199917Y158067D01*
X200000Y157775D01*
Y157442D01*
X199875Y157067D01*
X199667Y156775D01*
X199417Y156567D01*
X199000Y156400D01*
X198625Y156358D01*
X198250Y156442D01*
X198000Y156567D01*
X197750Y156817D01*
X197583Y157108D01*
X197500Y157400D01*
Y157692D01*
X197583Y157983D01*
X197708Y158233D01*
X197875Y158442D01*
G01X197500Y161000D02*
X200000D01*
X198208Y159458D01*
Y161542D01*
G01X198000Y162683D02*
X197708Y162933D01*
X197542Y163267D01*
X197500Y163642D01*
X197542Y163975D01*
X197750Y164308D01*
X198000Y164517D01*
X198250Y164558D01*
X198542Y164475D01*
X198750Y164183D01*
X198833Y163892D01*
Y163517D01*
G01Y163892D02*
X198958Y164142D01*
X199167Y164350D01*
X199417Y164433D01*
X199667Y164350D01*
X199875Y164142D01*
X200000Y163767D01*
X199958Y163392D01*
X199792Y163017D01*
G01X193500Y155017D02*
X196000D01*
Y156058D01*
X195875Y156392D01*
X195708Y156600D01*
X195375Y156683D01*
X195042Y156600D01*
X194833Y156350D01*
X194708Y156058D01*
Y155017D01*
G01Y156058D02*
X193500Y156683D01*
G01Y158950D02*
X196000D01*
X195500Y158450D01*
G01X193500D02*
Y159450D01*
G01X195583Y161258D02*
X195833Y161508D01*
X195958Y161800D01*
X196000Y162133D01*
X195917Y162550D01*
X195708Y162842D01*
X195458Y162925D01*
X195208Y162883D01*
X195000Y162717D01*
X194583Y161883D01*
X194292Y161508D01*
X193875Y161258D01*
X193500Y161175D01*
Y162925D01*
G01X196000Y165150D02*
X195917Y164817D01*
X195708Y164567D01*
X195458Y164400D01*
X195125Y164275D01*
X194750Y164233D01*
X194375Y164275D01*
X194042Y164400D01*
X193792Y164567D01*
X193583Y164817D01*
X193500Y165150D01*
X193583Y165483D01*
X193792Y165733D01*
X194042Y165900D01*
X194375Y166025D01*
X194750Y166067D01*
X195125Y166025D01*
X195458Y165900D01*
X195708Y165733D01*
X195917Y165483D01*
X196000Y165150D01*
G01X198000Y167567D02*
X200500D01*
Y168608D01*
X200375Y168942D01*
X200208Y169150D01*
X199875Y169233D01*
X199542Y169150D01*
X199333Y168900D01*
X199208Y168608D01*
Y167567D01*
G01Y168608D02*
X198000Y169233D01*
G01X198292Y170792D02*
X198083Y171083D01*
X198000Y171417D01*
X198083Y171750D01*
X198333Y172042D01*
X198708Y172250D01*
X199083Y172333D01*
X199542D01*
X199917Y172250D01*
X200250Y172042D01*
X200417Y171792D01*
X200500Y171500D01*
X200417Y171167D01*
X200250Y170917D01*
X200000Y170750D01*
X199667Y170667D01*
X199375Y170750D01*
X199083Y170958D01*
X198917Y171208D01*
X198875Y171500D01*
X198958Y171833D01*
X199167Y172083D01*
X199542Y172333D01*
G01X198375Y173683D02*
X198167Y173933D01*
X198042Y174225D01*
X198000Y174600D01*
X198083Y174975D01*
X198250Y175267D01*
X198542Y175475D01*
X198875Y175517D01*
X199208Y175433D01*
X199417Y175225D01*
X199583Y174933D01*
X199625Y174642D01*
X199583Y174350D01*
X199417Y173975D01*
X200500Y174100D01*
Y175225D01*
G01X205433Y190000D02*
Y192500D01*
X204392D01*
X204058Y192375D01*
X203850Y192208D01*
X203767Y191875D01*
X203850Y191542D01*
X204100Y191333D01*
X204392Y191208D01*
X205433D01*
G01X204392D02*
X203767Y190000D01*
G01X201500D02*
X201208Y190042D01*
X200875Y190167D01*
X200667Y190375D01*
X200583Y190667D01*
X200667Y190958D01*
X200917Y191208D01*
X201292Y191333D01*
X201708D01*
X201958Y191417D01*
X202167Y191625D01*
X202250Y191917D01*
X202125Y192208D01*
X201833Y192417D01*
X201500Y192500D01*
X201167Y192417D01*
X200875Y192208D01*
X200750Y191917D01*
X200833Y191625D01*
X201042Y191417D01*
X201292Y191333D01*
X201708D01*
X202083Y191208D01*
X202333Y190958D01*
X202417Y190667D01*
X202333Y190375D01*
X202125Y190167D01*
X201792Y190042D01*
X201500Y190000D01*
G01X199317Y190500D02*
X199067Y190208D01*
X198733Y190042D01*
X198358Y190000D01*
X198025Y190042D01*
X197692Y190250D01*
X197483Y190500D01*
X197442Y190750D01*
X197525Y191042D01*
X197817Y191250D01*
X198108Y191333D01*
X198483D01*
G01X198108D02*
X197858Y191458D01*
X197650Y191667D01*
X197567Y191917D01*
X197650Y192167D01*
X197858Y192375D01*
X198233Y192500D01*
X198608Y192458D01*
X198983Y192292D01*
G01X215533Y198000D02*
Y200500D01*
X214533D01*
X214200Y200375D01*
X213950Y200083D01*
X213867Y199750D01*
X213950Y199417D01*
X214158Y199167D01*
X214533Y199042D01*
X215533D01*
G01X212433Y198000D02*
Y200500D01*
X211392D01*
X211058Y200375D01*
X210850Y200208D01*
X210767Y199875D01*
X210850Y199542D01*
X211100Y199333D01*
X211392Y199208D01*
X212433D01*
G01X211392D02*
X210767Y198000D01*
G01X208500D02*
Y200500D01*
X209000Y200000D01*
G01Y198000D02*
X208000D01*
G01X206317Y198375D02*
X206067Y198167D01*
X205775Y198042D01*
X205400Y198000D01*
X205025Y198083D01*
X204733Y198250D01*
X204525Y198542D01*
X204483Y198875D01*
X204567Y199208D01*
X204775Y199417D01*
X205067Y199583D01*
X205358Y199625D01*
X205650Y199583D01*
X206025Y199417D01*
X205900Y200500D01*
X204775D01*
G01X203092Y200083D02*
X202842Y200333D01*
X202550Y200458D01*
X202217Y200500D01*
X201800Y200417D01*
X201508Y200208D01*
X201425Y199958D01*
X201467Y199708D01*
X201633Y199500D01*
X202467Y199083D01*
X202842Y198792D01*
X203092Y198375D01*
X203175Y198000D01*
X201425D01*
G01X189000Y209017D02*
X191500D01*
Y210058D01*
X191375Y210392D01*
X191208Y210600D01*
X190875Y210683D01*
X190542Y210600D01*
X190333Y210350D01*
X190208Y210058D01*
Y209017D01*
G01Y210058D02*
X189000Y210683D01*
G01Y212950D02*
X191500D01*
X191000Y212450D01*
G01X189000D02*
Y213450D01*
G01X191500Y216050D02*
X191417Y215717D01*
X191208Y215467D01*
X190958Y215300D01*
X190625Y215175D01*
X190250Y215133D01*
X189875Y215175D01*
X189542Y215300D01*
X189292Y215467D01*
X189083Y215717D01*
X189000Y216050D01*
X189083Y216383D01*
X189292Y216633D01*
X189542Y216800D01*
X189875Y216925D01*
X190250Y216967D01*
X190625Y216925D01*
X190958Y216800D01*
X191208Y216633D01*
X191417Y216383D01*
X191500Y216050D01*
G01X191083Y218358D02*
X191333Y218608D01*
X191458Y218900D01*
X191500Y219233D01*
X191417Y219650D01*
X191208Y219942D01*
X190958Y220025D01*
X190708Y219983D01*
X190500Y219817D01*
X190083Y218983D01*
X189792Y218608D01*
X189375Y218358D01*
X189000Y218275D01*
Y220025D01*
G01X209033Y205000D02*
Y207500D01*
X208033D01*
X207700Y207375D01*
X207450Y207083D01*
X207367Y206750D01*
X207450Y206417D01*
X207658Y206167D01*
X208033Y206042D01*
X209033D01*
G01X205933Y205000D02*
Y207500D01*
X204892D01*
X204558Y207375D01*
X204350Y207208D01*
X204267Y206875D01*
X204350Y206542D01*
X204600Y206333D01*
X204892Y206208D01*
X205933D01*
G01X204892D02*
X204267Y205000D01*
G01X202000D02*
Y207500D01*
X202500Y207000D01*
G01Y205000D02*
X201500D01*
G01X199817Y205375D02*
X199567Y205167D01*
X199275Y205042D01*
X198900Y205000D01*
X198525Y205083D01*
X198233Y205250D01*
X198025Y205542D01*
X197983Y205875D01*
X198067Y206208D01*
X198275Y206417D01*
X198567Y206583D01*
X198858Y206625D01*
X199150Y206583D01*
X199525Y206417D01*
X199400Y207500D01*
X198275D01*
G01X196717Y205375D02*
X196467Y205167D01*
X196175Y205042D01*
X195800Y205000D01*
X195425Y205083D01*
X195133Y205250D01*
X194925Y205542D01*
X194883Y205875D01*
X194967Y206208D01*
X195175Y206417D01*
X195467Y206583D01*
X195758Y206625D01*
X196050Y206583D01*
X196425Y206417D01*
X196300Y207500D01*
X195175D01*
G01X202392Y243317D02*
X202517Y243067D01*
X202600Y242775D01*
Y242442D01*
X202475Y242067D01*
X202267Y241775D01*
X202017Y241567D01*
X201600Y241400D01*
X201225Y241358D01*
X200850Y241442D01*
X200600Y241567D01*
X200350Y241817D01*
X200183Y242108D01*
X200100Y242400D01*
Y242692D01*
X200183Y242983D01*
X200308Y243233D01*
X200475Y243442D01*
G01X201142Y244708D02*
X201433Y245000D01*
X201600Y245250D01*
X201683Y245583D01*
X201600Y245875D01*
X201433Y246083D01*
X201183Y246250D01*
X200892Y246292D01*
X200642Y246250D01*
X200392Y246083D01*
X200183Y245833D01*
X200100Y245542D01*
X200183Y245208D01*
X200433Y244917D01*
X200808Y244750D01*
X201225Y244708D01*
X201767Y244792D01*
X202058Y244917D01*
X202350Y245125D01*
X202558Y245417D01*
X202600Y245708D01*
X202517Y246000D01*
X202308Y246208D01*
G01X200100Y248600D02*
X202600D01*
X202100Y248100D01*
G01X200100D02*
Y249100D01*
G01X197892Y243317D02*
X198017Y243067D01*
X198100Y242775D01*
Y242442D01*
X197975Y242067D01*
X197767Y241775D01*
X197517Y241567D01*
X197100Y241400D01*
X196725Y241358D01*
X196350Y241442D01*
X196100Y241567D01*
X195850Y241817D01*
X195683Y242108D01*
X195600Y242400D01*
Y242692D01*
X195683Y242983D01*
X195808Y243233D01*
X195975Y243442D01*
G01X196642Y244708D02*
X196933Y245000D01*
X197100Y245250D01*
X197183Y245583D01*
X197100Y245875D01*
X196933Y246083D01*
X196683Y246250D01*
X196392Y246292D01*
X196142Y246250D01*
X195892Y246083D01*
X195683Y245833D01*
X195600Y245542D01*
X195683Y245208D01*
X195933Y244917D01*
X196308Y244750D01*
X196725Y244708D01*
X197267Y244792D01*
X197558Y244917D01*
X197850Y245125D01*
X198058Y245417D01*
X198100Y245708D01*
X198017Y246000D01*
X197808Y246208D01*
G01X195600Y248600D02*
X195642Y248892D01*
X195767Y249225D01*
X195975Y249433D01*
X196267Y249517D01*
X196558Y249433D01*
X196808Y249183D01*
X196933Y248808D01*
Y248392D01*
X197017Y248142D01*
X197225Y247933D01*
X197517Y247850D01*
X197808Y247975D01*
X198017Y248267D01*
X198100Y248600D01*
X198017Y248933D01*
X197808Y249225D01*
X197517Y249350D01*
X197225Y249267D01*
X197017Y249058D01*
X196933Y248808D01*
Y248392D01*
X196808Y248017D01*
X196558Y247767D01*
X196267Y247683D01*
X195975Y247767D01*
X195767Y247975D01*
X195642Y248308D01*
X195600Y248600D01*
G01X202792Y255317D02*
X202917Y255067D01*
X203000Y254775D01*
Y254442D01*
X202875Y254067D01*
X202667Y253775D01*
X202417Y253567D01*
X202000Y253400D01*
X201625Y253358D01*
X201250Y253442D01*
X201000Y253567D01*
X200750Y253817D01*
X200583Y254108D01*
X200500Y254400D01*
Y254692D01*
X200583Y254983D01*
X200708Y255233D01*
X200875Y255442D01*
G01X201542Y256708D02*
X201833Y257000D01*
X202000Y257250D01*
X202083Y257583D01*
X202000Y257875D01*
X201833Y258083D01*
X201583Y258250D01*
X201292Y258292D01*
X201042Y258250D01*
X200792Y258083D01*
X200583Y257833D01*
X200500Y257542D01*
X200583Y257208D01*
X200833Y256917D01*
X201208Y256750D01*
X201625Y256708D01*
X202167Y256792D01*
X202458Y256917D01*
X202750Y257125D01*
X202958Y257417D01*
X203000Y257708D01*
X202917Y258000D01*
X202708Y258208D01*
G01X202583Y259808D02*
X202833Y260058D01*
X202958Y260350D01*
X203000Y260683D01*
X202917Y261100D01*
X202708Y261392D01*
X202458Y261475D01*
X202208Y261433D01*
X202000Y261267D01*
X201583Y260433D01*
X201292Y260058D01*
X200875Y259808D01*
X200500Y259725D01*
Y261475D01*
G01X198792Y255317D02*
X198917Y255067D01*
X199000Y254775D01*
Y254442D01*
X198875Y254067D01*
X198667Y253775D01*
X198417Y253567D01*
X198000Y253400D01*
X197625Y253358D01*
X197250Y253442D01*
X197000Y253567D01*
X196750Y253817D01*
X196583Y254108D01*
X196500Y254400D01*
Y254692D01*
X196583Y254983D01*
X196708Y255233D01*
X196875Y255442D01*
G01X197542Y256708D02*
X197833Y257000D01*
X198000Y257250D01*
X198083Y257583D01*
X198000Y257875D01*
X197833Y258083D01*
X197583Y258250D01*
X197292Y258292D01*
X197042Y258250D01*
X196792Y258083D01*
X196583Y257833D01*
X196500Y257542D01*
X196583Y257208D01*
X196833Y256917D01*
X197208Y256750D01*
X197625Y256708D01*
X198167Y256792D01*
X198458Y256917D01*
X198750Y257125D01*
X198958Y257417D01*
X199000Y257708D01*
X198917Y258000D01*
X198708Y258208D01*
G01X196500Y260517D02*
X197042Y260600D01*
X197500Y260725D01*
X197917Y260892D01*
X198375Y261100D01*
X199000Y261433D01*
Y259767D01*
G01X270050Y266500D02*
X266550Y271500D01*
G01X270050D02*
X266550Y266500D01*
G01X264283Y270667D02*
X263783Y271167D01*
X263200Y271417D01*
X262533Y271500D01*
X261700Y271333D01*
X261117Y270917D01*
X260950Y270417D01*
X261033Y269917D01*
X261367Y269500D01*
X263033Y268667D01*
X263783Y268083D01*
X264283Y267250D01*
X264450Y266500D01*
X260950D01*
G01X257100Y266333D02*
X257267Y266417D01*
Y266583D01*
X257100Y266667D01*
X256933Y266583D01*
Y266417D01*
X257100Y266333D01*
G01Y268583D02*
X257267Y268667D01*
Y268833D01*
X257100Y268917D01*
X256933Y268833D01*
Y268667D01*
X257100Y268583D01*
G01X251500Y266500D02*
Y271500D01*
X252500Y270500D01*
G01Y266500D02*
X250500D01*
G01X244900D02*
Y271500D01*
X247983Y267917D01*
X243817D01*
G01X240300Y266333D02*
X240467Y266417D01*
Y266583D01*
X240300Y266667D01*
X240133Y266583D01*
Y266417D01*
X240300Y266333D01*
G01X236533Y267500D02*
X236033Y266917D01*
X235367Y266583D01*
X234617Y266500D01*
X233950Y266583D01*
X233283Y267000D01*
X232867Y267500D01*
X232783Y268000D01*
X232950Y268583D01*
X233533Y269000D01*
X234117Y269167D01*
X234867D01*
G01X234117D02*
X233617Y269417D01*
X233200Y269833D01*
X233033Y270333D01*
X233200Y270833D01*
X233617Y271250D01*
X234367Y271500D01*
X235117Y271417D01*
X235867Y271083D01*
G01X229100Y266500D02*
Y271500D01*
X230100Y270500D01*
G01Y266500D02*
X228100D01*
G01X223500D02*
X222917Y266583D01*
X222250Y266833D01*
X221833Y267250D01*
X221667Y267833D01*
X221833Y268417D01*
X222333Y268917D01*
X223083Y269167D01*
X223917D01*
X224417Y269333D01*
X224833Y269750D01*
X225000Y270333D01*
X224750Y270917D01*
X224167Y271333D01*
X223500Y271500D01*
X222833Y271333D01*
X222250Y270917D01*
X222000Y270333D01*
X222167Y269750D01*
X222583Y269333D01*
X223083Y269167D01*
X223917D01*
X224667Y268917D01*
X225167Y268417D01*
X225333Y267833D01*
X225167Y267250D01*
X224750Y266833D01*
X224083Y266583D01*
X223500Y266500D01*
G01X217900D02*
Y271500D01*
X218900Y270500D01*
G01Y266500D02*
X216900D01*
G01X212300D02*
X211717Y266583D01*
X211050Y266833D01*
X210633Y267250D01*
X210467Y267833D01*
X210633Y268417D01*
X211133Y268917D01*
X211883Y269167D01*
X212717D01*
X213217Y269333D01*
X213633Y269750D01*
X213800Y270333D01*
X213550Y270917D01*
X212967Y271333D01*
X212300Y271500D01*
X211633Y271333D01*
X211050Y270917D01*
X210800Y270333D01*
X210967Y269750D01*
X211383Y269333D01*
X211883Y269167D01*
X212717D01*
X213467Y268917D01*
X213967Y268417D01*
X214133Y267833D01*
X213967Y267250D01*
X213550Y266833D01*
X212883Y266583D01*
X212300Y266500D01*
G01X208867D02*
Y271500D01*
X206700Y267333D01*
X204533Y271500D01*
Y266500D01*
G01X202850D02*
Y271500D01*
G01X199350D02*
Y266500D01*
G01Y269000D02*
X202850D01*
G01X197083Y271500D02*
X193917D01*
X197083Y266500D01*
X193917D01*
G01X227150Y44000D02*
Y41500D01*
G01X228108Y44000D02*
X226192D01*
G01X224883Y41500D02*
Y44000D01*
X223883D01*
X223550Y43875D01*
X223300Y43583D01*
X223217Y43250D01*
X223300Y42917D01*
X223508Y42667D01*
X223883Y42542D01*
X224883D01*
G01X221867Y41875D02*
X221617Y41667D01*
X221325Y41542D01*
X220950Y41500D01*
X220575Y41583D01*
X220283Y41750D01*
X220075Y42042D01*
X220033Y42375D01*
X220117Y42708D01*
X220325Y42917D01*
X220617Y43083D01*
X220908Y43125D01*
X221200Y43083D01*
X221575Y42917D01*
X221450Y44000D01*
X220325D01*
G01X218558Y41792D02*
X218267Y41583D01*
X217933Y41500D01*
X217600Y41583D01*
X217308Y41833D01*
X217100Y42208D01*
X217017Y42583D01*
Y43042D01*
X217100Y43417D01*
X217308Y43750D01*
X217558Y43917D01*
X217850Y44000D01*
X218183Y43917D01*
X218433Y43750D01*
X218600Y43500D01*
X218683Y43167D01*
X218600Y42875D01*
X218392Y42583D01*
X218142Y42417D01*
X217850Y42375D01*
X217517Y42458D01*
X217267Y42667D01*
X217017Y43042D01*
G01X223017Y54500D02*
Y52708D01*
X222850Y52333D01*
X222517Y52083D01*
X222100Y52000D01*
X221683Y52083D01*
X221350Y52333D01*
X221183Y52708D01*
Y54500D01*
G01X219917Y52500D02*
X219667Y52208D01*
X219333Y52042D01*
X218958Y52000D01*
X218625Y52042D01*
X218292Y52250D01*
X218083Y52500D01*
X218042Y52750D01*
X218125Y53042D01*
X218417Y53250D01*
X218708Y53333D01*
X219083D01*
G01X218708D02*
X218458Y53458D01*
X218250Y53667D01*
X218167Y53917D01*
X218250Y54167D01*
X218458Y54375D01*
X218833Y54500D01*
X219208Y54458D01*
X219583Y54292D01*
G01X215900Y52000D02*
Y54500D01*
X216400Y54000D01*
G01Y52000D02*
X215400D01*
G01X224983Y59000D02*
Y61500D01*
X223942D01*
X223608Y61375D01*
X223400Y61208D01*
X223317Y60875D01*
X223400Y60542D01*
X223650Y60333D01*
X223942Y60208D01*
X224983D01*
G01X223942D02*
X223317Y59000D01*
G01X220550D02*
Y61500D01*
X222092Y59708D01*
X220008D01*
G01X218867Y59500D02*
X218617Y59208D01*
X218283Y59042D01*
X217908Y59000D01*
X217575Y59042D01*
X217242Y59250D01*
X217033Y59500D01*
X216992Y59750D01*
X217075Y60042D01*
X217367Y60250D01*
X217658Y60333D01*
X218033D01*
G01X217658D02*
X217408Y60458D01*
X217200Y60667D01*
X217117Y60917D01*
X217200Y61167D01*
X217408Y61375D01*
X217783Y61500D01*
X218158Y61458D01*
X218533Y61292D01*
G01X214350Y59000D02*
Y61500D01*
X215892Y59708D01*
X213808D01*
G01X210000Y54517D02*
X212500D01*
Y55558D01*
X212375Y55892D01*
X212208Y56100D01*
X211875Y56183D01*
X211542Y56100D01*
X211333Y55850D01*
X211208Y55558D01*
Y54517D01*
G01Y55558D02*
X210000Y56183D01*
G01X210500Y57533D02*
X210208Y57783D01*
X210042Y58117D01*
X210000Y58492D01*
X210042Y58825D01*
X210250Y59158D01*
X210500Y59367D01*
X210750Y59408D01*
X211042Y59325D01*
X211250Y59033D01*
X211333Y58742D01*
Y58367D01*
G01Y58742D02*
X211458Y58992D01*
X211667Y59200D01*
X211917Y59283D01*
X212167Y59200D01*
X212375Y58992D01*
X212500Y58617D01*
X212458Y58242D01*
X212292Y57867D01*
G01X210292Y60842D02*
X210083Y61133D01*
X210000Y61467D01*
X210083Y61800D01*
X210333Y62092D01*
X210708Y62300D01*
X211083Y62383D01*
X211542D01*
X211917Y62300D01*
X212250Y62092D01*
X212417Y61842D01*
X212500Y61550D01*
X212417Y61217D01*
X212250Y60967D01*
X212000Y60800D01*
X211667Y60717D01*
X211375Y60800D01*
X211083Y61008D01*
X210917Y61258D01*
X210875Y61550D01*
X210958Y61883D01*
X211167Y62133D01*
X211542Y62383D01*
G01X210500Y63733D02*
X210208Y63983D01*
X210042Y64317D01*
X210000Y64692D01*
X210042Y65025D01*
X210250Y65358D01*
X210500Y65567D01*
X210750Y65608D01*
X211042Y65525D01*
X211250Y65233D01*
X211333Y64942D01*
Y64567D01*
G01Y64942D02*
X211458Y65192D01*
X211667Y65400D01*
X211917Y65483D01*
X212167Y65400D01*
X212375Y65192D01*
X212500Y64817D01*
X212458Y64442D01*
X212292Y64067D01*
G01X212792Y81767D02*
X212917Y81517D01*
X213000Y81225D01*
Y80892D01*
X212875Y80517D01*
X212667Y80225D01*
X212417Y80017D01*
X212000Y79850D01*
X211625Y79808D01*
X211250Y79892D01*
X211000Y80017D01*
X210750Y80267D01*
X210583Y80558D01*
X210500Y80850D01*
Y81142D01*
X210583Y81433D01*
X210708Y81683D01*
X210875Y81892D01*
G01X211000Y83033D02*
X210708Y83283D01*
X210542Y83617D01*
X210500Y83992D01*
X210542Y84325D01*
X210750Y84658D01*
X211000Y84867D01*
X211250Y84908D01*
X211542Y84825D01*
X211750Y84533D01*
X211833Y84242D01*
Y83867D01*
G01Y84242D02*
X211958Y84492D01*
X212167Y84700D01*
X212417Y84783D01*
X212667Y84700D01*
X212875Y84492D01*
X213000Y84117D01*
X212958Y83742D01*
X212792Y83367D01*
G01X213000Y87050D02*
X212917Y86717D01*
X212708Y86467D01*
X212458Y86300D01*
X212125Y86175D01*
X211750Y86133D01*
X211375Y86175D01*
X211042Y86300D01*
X210792Y86467D01*
X210583Y86717D01*
X210500Y87050D01*
X210583Y87383D01*
X210792Y87633D01*
X211042Y87800D01*
X211375Y87925D01*
X211750Y87967D01*
X212125Y87925D01*
X212458Y87800D01*
X212708Y87633D01*
X212917Y87383D01*
X213000Y87050D01*
G01X210500Y90650D02*
X213000D01*
X211208Y89108D01*
Y91192D01*
G01X202900Y87600D02*
X205500Y85000D01*
Y90200D01*
X202900Y87600D01*
G01X205500Y77300D02*
Y85000D01*
G01X212792Y95267D02*
X212917Y95017D01*
X213000Y94725D01*
Y94392D01*
X212875Y94017D01*
X212667Y93725D01*
X212417Y93517D01*
X212000Y93350D01*
X211625Y93308D01*
X211250Y93392D01*
X211000Y93517D01*
X210750Y93767D01*
X210583Y94058D01*
X210500Y94350D01*
Y94642D01*
X210583Y94933D01*
X210708Y95183D01*
X210875Y95392D01*
G01X211000Y96533D02*
X210708Y96783D01*
X210542Y97117D01*
X210500Y97492D01*
X210542Y97825D01*
X210750Y98158D01*
X211000Y98367D01*
X211250Y98408D01*
X211542Y98325D01*
X211750Y98033D01*
X211833Y97742D01*
Y97367D01*
G01Y97742D02*
X211958Y97992D01*
X212167Y98200D01*
X212417Y98283D01*
X212667Y98200D01*
X212875Y97992D01*
X213000Y97617D01*
X212958Y97242D01*
X212792Y96867D01*
G01X213000Y100550D02*
X212917Y100217D01*
X212708Y99967D01*
X212458Y99800D01*
X212125Y99675D01*
X211750Y99633D01*
X211375Y99675D01*
X211042Y99800D01*
X210792Y99967D01*
X210583Y100217D01*
X210500Y100550D01*
X210583Y100883D01*
X210792Y101133D01*
X211042Y101300D01*
X211375Y101425D01*
X211750Y101467D01*
X212125Y101425D01*
X212458Y101300D01*
X212708Y101133D01*
X212917Y100883D01*
X213000Y100550D01*
G01X212583Y102858D02*
X212833Y103108D01*
X212958Y103400D01*
X213000Y103733D01*
X212917Y104150D01*
X212708Y104442D01*
X212458Y104525D01*
X212208Y104483D01*
X212000Y104317D01*
X211583Y103483D01*
X211292Y103108D01*
X210875Y102858D01*
X210500Y102775D01*
Y104525D01*
G01X206500Y98017D02*
X209000D01*
Y99058D01*
X208875Y99392D01*
X208708Y99600D01*
X208375Y99683D01*
X208042Y99600D01*
X207833Y99350D01*
X207708Y99058D01*
Y98017D01*
G01Y99058D02*
X206500Y99683D01*
G01Y102450D02*
X209000D01*
X207208Y100908D01*
Y102992D01*
G01X207000Y104133D02*
X206708Y104383D01*
X206542Y104717D01*
X206500Y105092D01*
X206542Y105425D01*
X206750Y105758D01*
X207000Y105967D01*
X207250Y106008D01*
X207542Y105925D01*
X207750Y105633D01*
X207833Y105342D01*
Y104967D01*
G01Y105342D02*
X207958Y105592D01*
X208167Y105800D01*
X208417Y105883D01*
X208667Y105800D01*
X208875Y105592D01*
X209000Y105217D01*
X208958Y104842D01*
X208792Y104467D01*
G01X206792Y107442D02*
X206583Y107733D01*
X206500Y108067D01*
X206583Y108400D01*
X206833Y108692D01*
X207208Y108900D01*
X207583Y108983D01*
X208042D01*
X208417Y108900D01*
X208750Y108692D01*
X208917Y108442D01*
X209000Y108150D01*
X208917Y107817D01*
X208750Y107567D01*
X208500Y107400D01*
X208167Y107317D01*
X207875Y107400D01*
X207583Y107608D01*
X207417Y107858D01*
X207375Y108150D01*
X207458Y108483D01*
X207667Y108733D01*
X208042Y108983D01*
G01X212792Y108267D02*
X212917Y108017D01*
X213000Y107725D01*
Y107392D01*
X212875Y107017D01*
X212667Y106725D01*
X212417Y106517D01*
X212000Y106350D01*
X211625Y106308D01*
X211250Y106392D01*
X211000Y106517D01*
X210750Y106767D01*
X210583Y107058D01*
X210500Y107350D01*
Y107642D01*
X210583Y107933D01*
X210708Y108183D01*
X210875Y108392D01*
G01X211000Y109533D02*
X210708Y109783D01*
X210542Y110117D01*
X210500Y110492D01*
X210542Y110825D01*
X210750Y111158D01*
X211000Y111367D01*
X211250Y111408D01*
X211542Y111325D01*
X211750Y111033D01*
X211833Y110742D01*
Y110367D01*
G01Y110742D02*
X211958Y110992D01*
X212167Y111200D01*
X212417Y111283D01*
X212667Y111200D01*
X212875Y110992D01*
X213000Y110617D01*
X212958Y110242D01*
X212792Y109867D01*
G01X213000Y113550D02*
X212917Y113217D01*
X212708Y112967D01*
X212458Y112800D01*
X212125Y112675D01*
X211750Y112633D01*
X211375Y112675D01*
X211042Y112800D01*
X210792Y112967D01*
X210583Y113217D01*
X210500Y113550D01*
X210583Y113883D01*
X210792Y114133D01*
X211042Y114300D01*
X211375Y114425D01*
X211750Y114467D01*
X212125Y114425D01*
X212458Y114300D01*
X212708Y114133D01*
X212917Y113883D01*
X213000Y113550D01*
G01X211000Y115733D02*
X210708Y115983D01*
X210542Y116317D01*
X210500Y116692D01*
X210542Y117025D01*
X210750Y117358D01*
X211000Y117567D01*
X211250Y117608D01*
X211542Y117525D01*
X211750Y117233D01*
X211833Y116942D01*
Y116567D01*
G01Y116942D02*
X211958Y117192D01*
X212167Y117400D01*
X212417Y117483D01*
X212667Y117400D01*
X212875Y117192D01*
X213000Y116817D01*
X212958Y116442D01*
X212792Y116067D01*
G01Y121767D02*
X212917Y121517D01*
X213000Y121225D01*
Y120892D01*
X212875Y120517D01*
X212667Y120225D01*
X212417Y120017D01*
X212000Y119850D01*
X211625Y119808D01*
X211250Y119892D01*
X211000Y120017D01*
X210750Y120267D01*
X210583Y120558D01*
X210500Y120850D01*
Y121142D01*
X210583Y121433D01*
X210708Y121683D01*
X210875Y121892D01*
G01X212583Y123158D02*
X212833Y123408D01*
X212958Y123700D01*
X213000Y124033D01*
X212917Y124450D01*
X212708Y124742D01*
X212458Y124825D01*
X212208Y124783D01*
X212000Y124617D01*
X211583Y123783D01*
X211292Y123408D01*
X210875Y123158D01*
X210500Y123075D01*
Y124825D01*
G01X211000Y126133D02*
X210708Y126383D01*
X210542Y126717D01*
X210500Y127092D01*
X210542Y127425D01*
X210750Y127758D01*
X211000Y127967D01*
X211250Y128008D01*
X211542Y127925D01*
X211750Y127633D01*
X211833Y127342D01*
Y126967D01*
G01Y127342D02*
X211958Y127592D01*
X212167Y127800D01*
X212417Y127883D01*
X212667Y127800D01*
X212875Y127592D01*
X213000Y127217D01*
X212958Y126842D01*
X212792Y126467D01*
G01X210500Y130150D02*
X213000D01*
X212500Y129650D01*
G01X210500D02*
Y130650D01*
G01X206500Y111517D02*
X209000D01*
Y112558D01*
X208875Y112892D01*
X208708Y113100D01*
X208375Y113183D01*
X208042Y113100D01*
X207833Y112850D01*
X207708Y112558D01*
Y111517D01*
G01Y112558D02*
X206500Y113183D01*
G01Y115950D02*
X209000D01*
X207208Y114408D01*
Y116492D01*
G01X206875Y117633D02*
X206667Y117883D01*
X206542Y118175D01*
X206500Y118550D01*
X206583Y118925D01*
X206750Y119217D01*
X207042Y119425D01*
X207375Y119467D01*
X207708Y119383D01*
X207917Y119175D01*
X208083Y118883D01*
X208125Y118592D01*
X208083Y118300D01*
X207917Y117925D01*
X209000Y118050D01*
Y119175D01*
G01X206500Y122150D02*
X209000D01*
X207208Y120608D01*
Y122692D01*
G01X208292Y158317D02*
X208417Y158067D01*
X208500Y157775D01*
Y157442D01*
X208375Y157067D01*
X208167Y156775D01*
X207917Y156567D01*
X207500Y156400D01*
X207125Y156358D01*
X206750Y156442D01*
X206500Y156567D01*
X206250Y156817D01*
X206083Y157108D01*
X206000Y157400D01*
Y157692D01*
X206083Y157983D01*
X206208Y158233D01*
X206375Y158442D01*
G01X206500Y159583D02*
X206208Y159833D01*
X206042Y160167D01*
X206000Y160542D01*
X206042Y160875D01*
X206250Y161208D01*
X206500Y161417D01*
X206750Y161458D01*
X207042Y161375D01*
X207250Y161083D01*
X207333Y160792D01*
Y160417D01*
G01Y160792D02*
X207458Y161042D01*
X207667Y161250D01*
X207917Y161333D01*
X208167Y161250D01*
X208375Y161042D01*
X208500Y160667D01*
X208458Y160292D01*
X208292Y159917D01*
G01X207042Y162808D02*
X207333Y163100D01*
X207500Y163350D01*
X207583Y163683D01*
X207500Y163975D01*
X207333Y164183D01*
X207083Y164350D01*
X206792Y164392D01*
X206542Y164350D01*
X206292Y164183D01*
X206083Y163933D01*
X206000Y163642D01*
X206083Y163308D01*
X206333Y163017D01*
X206708Y162850D01*
X207125Y162808D01*
X207667Y162892D01*
X207958Y163017D01*
X208250Y163225D01*
X208458Y163517D01*
X208500Y163808D01*
X208417Y164100D01*
X208208Y164308D01*
G01X209792Y169817D02*
X209917Y169567D01*
X210000Y169275D01*
Y168942D01*
X209875Y168567D01*
X209667Y168275D01*
X209417Y168067D01*
X209000Y167900D01*
X208625Y167858D01*
X208250Y167942D01*
X208000Y168067D01*
X207750Y168317D01*
X207583Y168608D01*
X207500Y168900D01*
Y169192D01*
X207583Y169483D01*
X207708Y169733D01*
X207875Y169942D01*
G01X209583Y171208D02*
X209833Y171458D01*
X209958Y171750D01*
X210000Y172083D01*
X209917Y172500D01*
X209708Y172792D01*
X209458Y172875D01*
X209208Y172833D01*
X209000Y172667D01*
X208583Y171833D01*
X208292Y171458D01*
X207875Y171208D01*
X207500Y171125D01*
Y172875D01*
G01X208000Y174183D02*
X207708Y174433D01*
X207542Y174767D01*
X207500Y175142D01*
X207542Y175475D01*
X207750Y175808D01*
X208000Y176017D01*
X208250Y176058D01*
X208542Y175975D01*
X208750Y175683D01*
X208833Y175392D01*
Y175017D01*
G01Y175392D02*
X208958Y175642D01*
X209167Y175850D01*
X209417Y175933D01*
X209667Y175850D01*
X209875Y175642D01*
X210000Y175267D01*
X209958Y174892D01*
X209792Y174517D01*
G01X208000Y226517D02*
X210500D01*
Y227517D01*
X210375Y227850D01*
X210083Y228100D01*
X209750Y228183D01*
X209417Y228100D01*
X209167Y227892D01*
X209042Y227517D01*
Y226517D01*
G01X208000Y229617D02*
X210500D01*
Y230658D01*
X210375Y230992D01*
X210208Y231200D01*
X209875Y231283D01*
X209542Y231200D01*
X209333Y230950D01*
X209208Y230658D01*
Y229617D01*
G01Y230658D02*
X208000Y231283D01*
G01Y234050D02*
X210500D01*
X208708Y232508D01*
Y234592D01*
G01X208500Y235733D02*
X208208Y235983D01*
X208042Y236317D01*
X208000Y236692D01*
X208042Y237025D01*
X208250Y237358D01*
X208500Y237567D01*
X208750Y237608D01*
X209042Y237525D01*
X209250Y237233D01*
X209333Y236942D01*
Y236567D01*
G01Y236942D02*
X209458Y237192D01*
X209667Y237400D01*
X209917Y237483D01*
X210167Y237400D01*
X210375Y237192D01*
X210500Y236817D01*
X210458Y236442D01*
X210292Y236067D01*
G01X212000Y226517D02*
X214500D01*
Y227517D01*
X214375Y227850D01*
X214083Y228100D01*
X213750Y228183D01*
X213417Y228100D01*
X213167Y227892D01*
X213042Y227517D01*
Y226517D01*
G01X212000Y229617D02*
X214500D01*
Y230658D01*
X214375Y230992D01*
X214208Y231200D01*
X213875Y231283D01*
X213542Y231200D01*
X213333Y230950D01*
X213208Y230658D01*
Y229617D01*
G01Y230658D02*
X212000Y231283D01*
G01Y233550D02*
X212042Y233842D01*
X212167Y234175D01*
X212375Y234383D01*
X212667Y234467D01*
X212958Y234383D01*
X213208Y234133D01*
X213333Y233758D01*
Y233342D01*
X213417Y233092D01*
X213625Y232883D01*
X213917Y232800D01*
X214208Y232925D01*
X214417Y233217D01*
X214500Y233550D01*
X214417Y233883D01*
X214208Y234175D01*
X213917Y234300D01*
X213625Y234217D01*
X213417Y234008D01*
X213333Y233758D01*
Y233342D01*
X213208Y232967D01*
X212958Y232717D01*
X212667Y232633D01*
X212375Y232717D01*
X212167Y232925D01*
X212042Y233258D01*
X212000Y233550D01*
G01X212292Y235942D02*
X212083Y236233D01*
X212000Y236567D01*
X212083Y236900D01*
X212333Y237192D01*
X212708Y237400D01*
X213083Y237483D01*
X213542D01*
X213917Y237400D01*
X214250Y237192D01*
X214417Y236942D01*
X214500Y236650D01*
X214417Y236317D01*
X214250Y236067D01*
X214000Y235900D01*
X213667Y235817D01*
X213375Y235900D01*
X213083Y236108D01*
X212917Y236358D01*
X212875Y236650D01*
X212958Y236983D01*
X213167Y237233D01*
X213542Y237483D01*
G01X241483Y41500D02*
Y44000D01*
X240442D01*
X240108Y43875D01*
X239900Y43708D01*
X239817Y43375D01*
X239900Y43042D01*
X240150Y42833D01*
X240442Y42708D01*
X241483D01*
G01X240442D02*
X239817Y41500D01*
G01X238467Y42000D02*
X238217Y41708D01*
X237883Y41542D01*
X237508Y41500D01*
X237175Y41542D01*
X236842Y41750D01*
X236633Y42000D01*
X236592Y42250D01*
X236675Y42542D01*
X236967Y42750D01*
X237258Y42833D01*
X237633D01*
G01X237258D02*
X237008Y42958D01*
X236800Y43167D01*
X236717Y43417D01*
X236800Y43667D01*
X237008Y43875D01*
X237383Y44000D01*
X237758Y43958D01*
X238133Y43792D01*
G01X235158Y41792D02*
X234867Y41583D01*
X234533Y41500D01*
X234200Y41583D01*
X233908Y41833D01*
X233700Y42208D01*
X233617Y42583D01*
Y43042D01*
X233700Y43417D01*
X233908Y43750D01*
X234158Y43917D01*
X234450Y44000D01*
X234783Y43917D01*
X235033Y43750D01*
X235200Y43500D01*
X235283Y43167D01*
X235200Y42875D01*
X234992Y42583D01*
X234742Y42417D01*
X234450Y42375D01*
X234117Y42458D01*
X233867Y42667D01*
X233617Y43042D01*
G01X232142Y42542D02*
X231850Y42833D01*
X231600Y43000D01*
X231267Y43083D01*
X230975Y43000D01*
X230767Y42833D01*
X230600Y42583D01*
X230558Y42292D01*
X230600Y42042D01*
X230767Y41792D01*
X231017Y41583D01*
X231308Y41500D01*
X231642Y41583D01*
X231933Y41833D01*
X232100Y42208D01*
X232142Y42625D01*
X232058Y43167D01*
X231933Y43458D01*
X231725Y43750D01*
X231433Y43958D01*
X231142Y44000D01*
X230850Y43917D01*
X230642Y43708D01*
G01X225250Y53800D02*
Y51200D01*
G01X233150Y53800D02*
X225250D01*
G01Y51200D02*
X233150D01*
G01X248500Y243500D02*
X218000D01*
Y206000D01*
X235500D01*
Y199500D01*
X265000D01*
Y237000D01*
X259000D01*
Y243500D01*
X248500D01*
G01X231983Y208000D02*
Y210500D01*
X230942D01*
X230608Y210375D01*
X230400Y210208D01*
X230317Y209875D01*
X230400Y209542D01*
X230650Y209333D01*
X230942Y209208D01*
X231983D01*
G01X230942D02*
X230317Y208000D01*
G01X227550D02*
Y210500D01*
X229092Y208708D01*
X227008D01*
G01X224950Y210500D02*
X225283Y210417D01*
X225533Y210208D01*
X225700Y209958D01*
X225825Y209625D01*
X225867Y209250D01*
X225825Y208875D01*
X225700Y208542D01*
X225533Y208292D01*
X225283Y208083D01*
X224950Y208000D01*
X224617Y208083D01*
X224367Y208292D01*
X224200Y208542D01*
X224075Y208875D01*
X224033Y209250D01*
X224075Y209625D01*
X224200Y209958D01*
X224367Y210208D01*
X224617Y210417D01*
X224950Y210500D01*
G01X222767Y208375D02*
X222517Y208167D01*
X222225Y208042D01*
X221850Y208000D01*
X221475Y208083D01*
X221183Y208250D01*
X220975Y208542D01*
X220933Y208875D01*
X221017Y209208D01*
X221225Y209417D01*
X221517Y209583D01*
X221808Y209625D01*
X222100Y209583D01*
X222475Y209417D01*
X222350Y210500D01*
X221225D01*
G01X229500Y213467D02*
X232000D01*
Y214467D01*
X231875Y214800D01*
X231583Y215050D01*
X231250Y215133D01*
X230917Y215050D01*
X230667Y214842D01*
X230542Y214467D01*
Y213467D01*
G01X229500Y216567D02*
X232000D01*
Y217608D01*
X231875Y217942D01*
X231708Y218150D01*
X231375Y218233D01*
X231042Y218150D01*
X230833Y217900D01*
X230708Y217608D01*
Y216567D01*
G01Y217608D02*
X229500Y218233D01*
G01Y220500D02*
X232000D01*
X231500Y220000D01*
G01X229500D02*
Y221000D01*
G01X231583Y222808D02*
X231833Y223058D01*
X231958Y223350D01*
X232000Y223683D01*
X231917Y224100D01*
X231708Y224392D01*
X231458Y224475D01*
X231208Y224433D01*
X231000Y224267D01*
X230583Y223433D01*
X230292Y223058D01*
X229875Y222808D01*
X229500Y222725D01*
Y224475D01*
G01X229792Y225992D02*
X229583Y226283D01*
X229500Y226617D01*
X229583Y226950D01*
X229833Y227242D01*
X230208Y227450D01*
X230583Y227533D01*
X231042D01*
X231417Y227450D01*
X231750Y227242D01*
X231917Y226992D01*
X232000Y226700D01*
X231917Y226367D01*
X231750Y226117D01*
X231500Y225950D01*
X231167Y225867D01*
X230875Y225950D01*
X230583Y226158D01*
X230417Y226408D01*
X230375Y226700D01*
X230458Y227033D01*
X230667Y227283D01*
X231042Y227533D01*
G01X227000Y215983D02*
X225208D01*
X224833Y216150D01*
X224583Y216483D01*
X224500Y216900D01*
X224583Y217317D01*
X224833Y217650D01*
X225208Y217817D01*
X227000D01*
G01X224500Y220000D02*
X227000D01*
X226500Y219500D01*
G01X224500D02*
Y220500D01*
G01X224875Y222183D02*
X224667Y222433D01*
X224542Y222725D01*
X224500Y223100D01*
X224583Y223475D01*
X224750Y223767D01*
X225042Y223975D01*
X225375Y224017D01*
X225708Y223933D01*
X225917Y223725D01*
X226083Y223433D01*
X226125Y223142D01*
X226083Y222850D01*
X225917Y222475D01*
X227000Y222600D01*
Y223725D01*
G01X231292Y231817D02*
X231417Y231567D01*
X231500Y231275D01*
Y230942D01*
X231375Y230567D01*
X231167Y230275D01*
X230917Y230067D01*
X230500Y229900D01*
X230125Y229858D01*
X229750Y229942D01*
X229500Y230067D01*
X229250Y230317D01*
X229083Y230608D01*
X229000Y230900D01*
Y231192D01*
X229083Y231483D01*
X229208Y231733D01*
X229375Y231942D01*
G01X229000Y234000D02*
X231500D01*
X231000Y233500D01*
G01X229000D02*
Y234500D01*
G01X229375Y236183D02*
X229167Y236433D01*
X229042Y236725D01*
X229000Y237100D01*
X229083Y237475D01*
X229250Y237767D01*
X229542Y237975D01*
X229875Y238017D01*
X230208Y237933D01*
X230417Y237725D01*
X230583Y237433D01*
X230625Y237142D01*
X230583Y236850D01*
X230417Y236475D01*
X231500Y236600D01*
Y237725D01*
G01X243983Y230500D02*
Y233000D01*
X242942D01*
X242608Y232875D01*
X242400Y232708D01*
X242317Y232375D01*
X242400Y232042D01*
X242650Y231833D01*
X242942Y231708D01*
X243983D01*
G01X242942D02*
X242317Y230500D01*
G01X240967Y231000D02*
X240717Y230708D01*
X240383Y230542D01*
X240008Y230500D01*
X239675Y230542D01*
X239342Y230750D01*
X239133Y231000D01*
X239092Y231250D01*
X239175Y231542D01*
X239467Y231750D01*
X239758Y231833D01*
X240133D01*
G01X239758D02*
X239508Y231958D01*
X239300Y232167D01*
X239217Y232417D01*
X239300Y232667D01*
X239508Y232875D01*
X239883Y233000D01*
X240258Y232958D01*
X240633Y232792D01*
G01X237742Y232583D02*
X237492Y232833D01*
X237200Y232958D01*
X236867Y233000D01*
X236450Y232917D01*
X236158Y232708D01*
X236075Y232458D01*
X236117Y232208D01*
X236283Y232000D01*
X237117Y231583D01*
X237492Y231292D01*
X237742Y230875D01*
X237825Y230500D01*
X236075D01*
G01X234767Y231000D02*
X234517Y230708D01*
X234183Y230542D01*
X233808Y230500D01*
X233475Y230542D01*
X233142Y230750D01*
X232933Y231000D01*
X232892Y231250D01*
X232975Y231542D01*
X233267Y231750D01*
X233558Y231833D01*
X233933D01*
G01X233558D02*
X233308Y231958D01*
X233100Y232167D01*
X233017Y232417D01*
X233100Y232667D01*
X233308Y232875D01*
X233683Y233000D01*
X234058Y232958D01*
X234433Y232792D01*
G01X254483Y41500D02*
Y44000D01*
X253442D01*
X253108Y43875D01*
X252900Y43708D01*
X252817Y43375D01*
X252900Y43042D01*
X253150Y42833D01*
X253442Y42708D01*
X254483D01*
G01X253442D02*
X252817Y41500D01*
G01X251467Y42000D02*
X251217Y41708D01*
X250883Y41542D01*
X250508Y41500D01*
X250175Y41542D01*
X249842Y41750D01*
X249633Y42000D01*
X249592Y42250D01*
X249675Y42542D01*
X249967Y42750D01*
X250258Y42833D01*
X250633D01*
G01X250258D02*
X250008Y42958D01*
X249800Y43167D01*
X249717Y43417D01*
X249800Y43667D01*
X250008Y43875D01*
X250383Y44000D01*
X250758Y43958D01*
X251133Y43792D01*
G01X247450Y41500D02*
X247158Y41542D01*
X246825Y41667D01*
X246617Y41875D01*
X246533Y42167D01*
X246617Y42458D01*
X246867Y42708D01*
X247242Y42833D01*
X247658D01*
X247908Y42917D01*
X248117Y43125D01*
X248200Y43417D01*
X248075Y43708D01*
X247783Y43917D01*
X247450Y44000D01*
X247117Y43917D01*
X246825Y43708D01*
X246700Y43417D01*
X246783Y43125D01*
X246992Y42917D01*
X247242Y42833D01*
X247658D01*
X248033Y42708D01*
X248283Y42458D01*
X248367Y42167D01*
X248283Y41875D01*
X248075Y41667D01*
X247742Y41542D01*
X247450Y41500D01*
G01X245142Y43583D02*
X244892Y43833D01*
X244600Y43958D01*
X244267Y44000D01*
X243850Y43917D01*
X243558Y43708D01*
X243475Y43458D01*
X243517Y43208D01*
X243683Y43000D01*
X244517Y42583D01*
X244892Y42292D01*
X245142Y41875D01*
X245225Y41500D01*
X243475D01*
G01X248733Y60792D02*
X248983Y60917D01*
X249275Y61000D01*
X249608D01*
X249983Y60875D01*
X250275Y60667D01*
X250483Y60417D01*
X250650Y60000D01*
X250692Y59625D01*
X250608Y59250D01*
X250483Y59000D01*
X250233Y58750D01*
X249942Y58583D01*
X249650Y58500D01*
X249358D01*
X249067Y58583D01*
X248817Y58708D01*
X248608Y58875D01*
G01X247467Y59000D02*
X247217Y58708D01*
X246883Y58542D01*
X246508Y58500D01*
X246175Y58542D01*
X245842Y58750D01*
X245633Y59000D01*
X245592Y59250D01*
X245675Y59542D01*
X245967Y59750D01*
X246258Y59833D01*
X246633D01*
G01X246258D02*
X246008Y59958D01*
X245800Y60167D01*
X245717Y60417D01*
X245800Y60667D01*
X246008Y60875D01*
X246383Y61000D01*
X246758Y60958D01*
X247133Y60792D01*
G01X243450Y58500D02*
Y61000D01*
X243950Y60500D01*
G01Y58500D02*
X242950D01*
G01X240433D02*
X240350Y59042D01*
X240225Y59500D01*
X240058Y59917D01*
X239850Y60375D01*
X239517Y61000D01*
X241183D01*
G01X233150Y51200D02*
Y53800D01*
G01X239683Y192292D02*
X239933Y192417D01*
X240225Y192500D01*
X240558D01*
X240933Y192375D01*
X241225Y192167D01*
X241433Y191917D01*
X241600Y191500D01*
X241642Y191125D01*
X241558Y190750D01*
X241433Y190500D01*
X241183Y190250D01*
X240892Y190083D01*
X240600Y190000D01*
X240308D01*
X240017Y190083D01*
X239767Y190208D01*
X239558Y190375D01*
G01X238458Y190000D02*
Y192500D01*
X236542Y190000D01*
Y192500D01*
G01X235317Y190375D02*
X235067Y190167D01*
X234775Y190042D01*
X234400Y190000D01*
X234025Y190083D01*
X233733Y190250D01*
X233525Y190542D01*
X233483Y190875D01*
X233567Y191208D01*
X233775Y191417D01*
X234067Y191583D01*
X234358Y191625D01*
X234650Y191583D01*
X235025Y191417D01*
X234900Y192500D01*
X233775D01*
G01X244433Y209500D02*
Y212000D01*
X243392D01*
X243058Y211875D01*
X242850Y211708D01*
X242767Y211375D01*
X242850Y211042D01*
X243100Y210833D01*
X243392Y210708D01*
X244433D01*
G01X243392D02*
X242767Y209500D01*
G01X240500D02*
X240208Y209542D01*
X239875Y209667D01*
X239667Y209875D01*
X239583Y210167D01*
X239667Y210458D01*
X239917Y210708D01*
X240292Y210833D01*
X240708D01*
X240958Y210917D01*
X241167Y211125D01*
X241250Y211417D01*
X241125Y211708D01*
X240833Y211917D01*
X240500Y212000D01*
X240167Y211917D01*
X239875Y211708D01*
X239750Y211417D01*
X239833Y211125D01*
X240042Y210917D01*
X240292Y210833D01*
X240708D01*
X241083Y210708D01*
X241333Y210458D01*
X241417Y210167D01*
X241333Y209875D01*
X241125Y209667D01*
X240792Y209542D01*
X240500Y209500D01*
G01X238192Y211583D02*
X237942Y211833D01*
X237650Y211958D01*
X237317Y212000D01*
X236900Y211917D01*
X236608Y211708D01*
X236525Y211458D01*
X236567Y211208D01*
X236733Y211000D01*
X237567Y210583D01*
X237942Y210292D01*
X238192Y209875D01*
X238275Y209500D01*
X236525D01*
G01X244433Y213500D02*
Y216000D01*
X243392D01*
X243058Y215875D01*
X242850Y215708D01*
X242767Y215375D01*
X242850Y215042D01*
X243100Y214833D01*
X243392Y214708D01*
X244433D01*
G01X243392D02*
X242767Y213500D01*
G01X241208Y213792D02*
X240917Y213583D01*
X240583Y213500D01*
X240250Y213583D01*
X239958Y213833D01*
X239750Y214208D01*
X239667Y214583D01*
Y215042D01*
X239750Y215417D01*
X239958Y215750D01*
X240208Y215917D01*
X240500Y216000D01*
X240833Y215917D01*
X241083Y215750D01*
X241250Y215500D01*
X241333Y215167D01*
X241250Y214875D01*
X241042Y214583D01*
X240792Y214417D01*
X240500Y214375D01*
X240167Y214458D01*
X239917Y214667D01*
X239667Y215042D01*
G01X236900Y213500D02*
Y216000D01*
X238442Y214208D01*
X236358D01*
G01X246000Y205017D02*
X248500D01*
Y206058D01*
X248375Y206392D01*
X248208Y206600D01*
X247875Y206683D01*
X247542Y206600D01*
X247333Y206350D01*
X247208Y206058D01*
Y205017D01*
G01Y206058D02*
X246000Y206683D01*
G01X246500Y208033D02*
X246208Y208283D01*
X246042Y208617D01*
X246000Y208992D01*
X246042Y209325D01*
X246250Y209658D01*
X246500Y209867D01*
X246750Y209908D01*
X247042Y209825D01*
X247250Y209533D01*
X247333Y209242D01*
Y208867D01*
G01Y209242D02*
X247458Y209492D01*
X247667Y209700D01*
X247917Y209783D01*
X248167Y209700D01*
X248375Y209492D01*
X248500Y209117D01*
X248458Y208742D01*
X248292Y208367D01*
G01X246000Y211967D02*
X246542Y212050D01*
X247000Y212175D01*
X247417Y212342D01*
X247875Y212550D01*
X248500Y212883D01*
Y211217D01*
G01X247042Y214358D02*
X247333Y214650D01*
X247500Y214900D01*
X247583Y215233D01*
X247500Y215525D01*
X247333Y215733D01*
X247083Y215900D01*
X246792Y215942D01*
X246542Y215900D01*
X246292Y215733D01*
X246083Y215483D01*
X246000Y215192D01*
X246083Y214858D01*
X246333Y214567D01*
X246708Y214400D01*
X247125Y214358D01*
X247667Y214442D01*
X247958Y214567D01*
X248250Y214775D01*
X248458Y215067D01*
X248500Y215358D01*
X248417Y215650D01*
X248208Y215858D01*
G01X244433Y205500D02*
Y208000D01*
X243392D01*
X243058Y207875D01*
X242850Y207708D01*
X242767Y207375D01*
X242850Y207042D01*
X243100Y206833D01*
X243392Y206708D01*
X244433D01*
G01X243392D02*
X242767Y205500D01*
G01X240500D02*
X240208Y205542D01*
X239875Y205667D01*
X239667Y205875D01*
X239583Y206167D01*
X239667Y206458D01*
X239917Y206708D01*
X240292Y206833D01*
X240708D01*
X240958Y206917D01*
X241167Y207125D01*
X241250Y207417D01*
X241125Y207708D01*
X240833Y207917D01*
X240500Y208000D01*
X240167Y207917D01*
X239875Y207708D01*
X239750Y207417D01*
X239833Y207125D01*
X240042Y206917D01*
X240292Y206833D01*
X240708D01*
X241083Y206708D01*
X241333Y206458D01*
X241417Y206167D01*
X241333Y205875D01*
X241125Y205667D01*
X240792Y205542D01*
X240500Y205500D01*
G01X237400D02*
Y208000D01*
X237900Y207500D01*
G01Y205500D02*
X236900D01*
G01X243000Y218017D02*
X245500D01*
Y219058D01*
X245375Y219392D01*
X245208Y219600D01*
X244875Y219683D01*
X244542Y219600D01*
X244333Y219350D01*
X244208Y219058D01*
Y218017D01*
G01Y219058D02*
X243000Y219683D01*
G01X243500Y221033D02*
X243208Y221283D01*
X243042Y221617D01*
X243000Y221992D01*
X243042Y222325D01*
X243250Y222658D01*
X243500Y222867D01*
X243750Y222908D01*
X244042Y222825D01*
X244250Y222533D01*
X244333Y222242D01*
Y221867D01*
G01Y222242D02*
X244458Y222492D01*
X244667Y222700D01*
X244917Y222783D01*
X245167Y222700D01*
X245375Y222492D01*
X245500Y222117D01*
X245458Y221742D01*
X245292Y221367D01*
G01X245083Y224258D02*
X245333Y224508D01*
X245458Y224800D01*
X245500Y225133D01*
X245417Y225550D01*
X245208Y225842D01*
X244958Y225925D01*
X244708Y225883D01*
X244500Y225717D01*
X244083Y224883D01*
X243792Y224508D01*
X243375Y224258D01*
X243000Y224175D01*
Y225925D01*
G01Y228650D02*
X245500D01*
X243708Y227108D01*
Y229192D01*
G01X238700Y218267D02*
X241200D01*
Y219308D01*
X241075Y219642D01*
X240908Y219850D01*
X240575Y219933D01*
X240242Y219850D01*
X240033Y219600D01*
X239908Y219308D01*
Y218267D01*
G01Y219308D02*
X238700Y219933D01*
G01X238992Y221492D02*
X238783Y221783D01*
X238700Y222117D01*
X238783Y222450D01*
X239033Y222742D01*
X239408Y222950D01*
X239783Y223033D01*
X240242D01*
X240617Y222950D01*
X240950Y222742D01*
X241117Y222492D01*
X241200Y222200D01*
X241117Y221867D01*
X240950Y221617D01*
X240700Y221450D01*
X240367Y221367D01*
X240075Y221450D01*
X239783Y221658D01*
X239617Y221908D01*
X239575Y222200D01*
X239658Y222533D01*
X239867Y222783D01*
X240242Y223033D01*
G01X239200Y224383D02*
X238908Y224633D01*
X238742Y224967D01*
X238700Y225342D01*
X238742Y225675D01*
X238950Y226008D01*
X239200Y226217D01*
X239450Y226258D01*
X239742Y226175D01*
X239950Y225883D01*
X240033Y225592D01*
Y225217D01*
G01Y225592D02*
X240158Y225842D01*
X240367Y226050D01*
X240617Y226133D01*
X240867Y226050D01*
X241075Y225842D01*
X241200Y225467D01*
X241158Y225092D01*
X240992Y224717D01*
G01X256983Y230500D02*
Y233000D01*
X255942D01*
X255608Y232875D01*
X255400Y232708D01*
X255317Y232375D01*
X255400Y232042D01*
X255650Y231833D01*
X255942Y231708D01*
X256983D01*
G01X255942D02*
X255317Y230500D01*
G01X253967Y231000D02*
X253717Y230708D01*
X253383Y230542D01*
X253008Y230500D01*
X252675Y230542D01*
X252342Y230750D01*
X252133Y231000D01*
X252092Y231250D01*
X252175Y231542D01*
X252467Y231750D01*
X252758Y231833D01*
X253133D01*
G01X252758D02*
X252508Y231958D01*
X252300Y232167D01*
X252217Y232417D01*
X252300Y232667D01*
X252508Y232875D01*
X252883Y233000D01*
X253258Y232958D01*
X253633Y232792D01*
G01X250742Y232583D02*
X250492Y232833D01*
X250200Y232958D01*
X249867Y233000D01*
X249450Y232917D01*
X249158Y232708D01*
X249075Y232458D01*
X249117Y232208D01*
X249283Y232000D01*
X250117Y231583D01*
X250492Y231292D01*
X250742Y230875D01*
X250825Y230500D01*
X249075D01*
G01X247642Y232583D02*
X247392Y232833D01*
X247100Y232958D01*
X246767Y233000D01*
X246350Y232917D01*
X246058Y232708D01*
X245975Y232458D01*
X246017Y232208D01*
X246183Y232000D01*
X247017Y231583D01*
X247392Y231292D01*
X247642Y230875D01*
X247725Y230500D01*
X245975D01*
G01X248483Y235000D02*
Y237500D01*
X247442D01*
X247108Y237375D01*
X246900Y237208D01*
X246817Y236875D01*
X246900Y236542D01*
X247150Y236333D01*
X247442Y236208D01*
X248483D01*
G01X247442D02*
X246817Y235000D01*
G01X245467Y235500D02*
X245217Y235208D01*
X244883Y235042D01*
X244508Y235000D01*
X244175Y235042D01*
X243842Y235250D01*
X243633Y235500D01*
X243592Y235750D01*
X243675Y236042D01*
X243967Y236250D01*
X244258Y236333D01*
X244633D01*
G01X244258D02*
X244008Y236458D01*
X243800Y236667D01*
X243717Y236917D01*
X243800Y237167D01*
X244008Y237375D01*
X244383Y237500D01*
X244758Y237458D01*
X245133Y237292D01*
G01X241450Y235000D02*
Y237500D01*
X241950Y237000D01*
G01Y235000D02*
X240950D01*
G01X238350D02*
X238058Y235042D01*
X237725Y235167D01*
X237517Y235375D01*
X237433Y235667D01*
X237517Y235958D01*
X237767Y236208D01*
X238142Y236333D01*
X238558D01*
X238808Y236417D01*
X239017Y236625D01*
X239100Y236917D01*
X238975Y237208D01*
X238683Y237417D01*
X238350Y237500D01*
X238017Y237417D01*
X237725Y237208D01*
X237600Y236917D01*
X237683Y236625D01*
X237892Y236417D01*
X238142Y236333D01*
X238558D01*
X238933Y236208D01*
X239183Y235958D01*
X239267Y235667D01*
X239183Y235375D01*
X238975Y235167D01*
X238642Y235042D01*
X238350Y235000D01*
G01X247983Y239000D02*
Y241500D01*
X246942D01*
X246608Y241375D01*
X246400Y241208D01*
X246317Y240875D01*
X246400Y240542D01*
X246650Y240333D01*
X246942Y240208D01*
X247983D01*
G01X246942D02*
X246317Y239000D01*
G01X244967Y239500D02*
X244717Y239208D01*
X244383Y239042D01*
X244008Y239000D01*
X243675Y239042D01*
X243342Y239250D01*
X243133Y239500D01*
X243092Y239750D01*
X243175Y240042D01*
X243467Y240250D01*
X243758Y240333D01*
X244133D01*
G01X243758D02*
X243508Y240458D01*
X243300Y240667D01*
X243217Y240917D01*
X243300Y241167D01*
X243508Y241375D01*
X243883Y241500D01*
X244258Y241458D01*
X244633Y241292D01*
G01X240950Y239000D02*
Y241500D01*
X241450Y241000D01*
G01Y239000D02*
X240450D01*
G01X237933D02*
X237850Y239542D01*
X237725Y240000D01*
X237558Y240417D01*
X237350Y240875D01*
X237017Y241500D01*
X238683D01*
G01X252292Y47767D02*
X252417Y47517D01*
X252500Y47225D01*
Y46892D01*
X252375Y46517D01*
X252167Y46225D01*
X251917Y46017D01*
X251500Y45850D01*
X251125Y45808D01*
X250750Y45892D01*
X250500Y46017D01*
X250250Y46267D01*
X250083Y46558D01*
X250000Y46850D01*
Y47142D01*
X250083Y47433D01*
X250208Y47683D01*
X250375Y47892D01*
G01X250500Y49033D02*
X250208Y49283D01*
X250042Y49617D01*
X250000Y49992D01*
X250042Y50325D01*
X250250Y50658D01*
X250500Y50867D01*
X250750Y50908D01*
X251042Y50825D01*
X251250Y50533D01*
X251333Y50242D01*
Y49867D01*
G01Y50242D02*
X251458Y50492D01*
X251667Y50700D01*
X251917Y50783D01*
X252167Y50700D01*
X252375Y50492D01*
X252500Y50117D01*
X252458Y49742D01*
X252292Y49367D01*
G01X252500Y53050D02*
X252417Y52717D01*
X252208Y52467D01*
X251958Y52300D01*
X251625Y52175D01*
X251250Y52133D01*
X250875Y52175D01*
X250542Y52300D01*
X250292Y52467D01*
X250083Y52717D01*
X250000Y53050D01*
X250083Y53383D01*
X250292Y53633D01*
X250542Y53800D01*
X250875Y53925D01*
X251250Y53967D01*
X251625Y53925D01*
X251958Y53800D01*
X252208Y53633D01*
X252417Y53383D01*
X252500Y53050D01*
G01X251042Y55358D02*
X251333Y55650D01*
X251500Y55900D01*
X251583Y56233D01*
X251500Y56525D01*
X251333Y56733D01*
X251083Y56900D01*
X250792Y56942D01*
X250542Y56900D01*
X250292Y56733D01*
X250083Y56483D01*
X250000Y56192D01*
X250083Y55858D01*
X250333Y55567D01*
X250708Y55400D01*
X251125Y55358D01*
X251667Y55442D01*
X251958Y55567D01*
X252250Y55775D01*
X252458Y56067D01*
X252500Y56358D01*
X252417Y56650D01*
X252208Y56858D01*
G01X256292Y47767D02*
X256417Y47517D01*
X256500Y47225D01*
Y46892D01*
X256375Y46517D01*
X256167Y46225D01*
X255917Y46017D01*
X255500Y45850D01*
X255125Y45808D01*
X254750Y45892D01*
X254500Y46017D01*
X254250Y46267D01*
X254083Y46558D01*
X254000Y46850D01*
Y47142D01*
X254083Y47433D01*
X254208Y47683D01*
X254375Y47892D01*
G01X254500Y49033D02*
X254208Y49283D01*
X254042Y49617D01*
X254000Y49992D01*
X254042Y50325D01*
X254250Y50658D01*
X254500Y50867D01*
X254750Y50908D01*
X255042Y50825D01*
X255250Y50533D01*
X255333Y50242D01*
Y49867D01*
G01Y50242D02*
X255458Y50492D01*
X255667Y50700D01*
X255917Y50783D01*
X256167Y50700D01*
X256375Y50492D01*
X256500Y50117D01*
X256458Y49742D01*
X256292Y49367D01*
G01X256500Y53050D02*
X256417Y52717D01*
X256208Y52467D01*
X255958Y52300D01*
X255625Y52175D01*
X255250Y52133D01*
X254875Y52175D01*
X254542Y52300D01*
X254292Y52467D01*
X254083Y52717D01*
X254000Y53050D01*
X254083Y53383D01*
X254292Y53633D01*
X254542Y53800D01*
X254875Y53925D01*
X255250Y53967D01*
X255625Y53925D01*
X255958Y53800D01*
X256208Y53633D01*
X256417Y53383D01*
X256500Y53050D01*
G01X254375Y55233D02*
X254167Y55483D01*
X254042Y55775D01*
X254000Y56150D01*
X254083Y56525D01*
X254250Y56817D01*
X254542Y57025D01*
X254875Y57067D01*
X255208Y56983D01*
X255417Y56775D01*
X255583Y56483D01*
X255625Y56192D01*
X255583Y55900D01*
X255417Y55525D01*
X256500Y55650D01*
Y56775D01*
G01X268500Y57500D02*
Y62000D01*
X257000D01*
Y71000D01*
G01X257500Y92500D02*
Y96000D01*
X265500D01*
Y98000D01*
G01X263183Y101292D02*
X263433Y101417D01*
X263725Y101500D01*
X264058D01*
X264433Y101375D01*
X264725Y101167D01*
X264933Y100917D01*
X265100Y100500D01*
X265142Y100125D01*
X265058Y99750D01*
X264933Y99500D01*
X264683Y99250D01*
X264392Y99083D01*
X264100Y99000D01*
X263808D01*
X263517Y99083D01*
X263267Y99208D01*
X263058Y99375D01*
G01X260500Y99000D02*
Y101500D01*
X262042Y99708D01*
X259958D01*
G01X257900Y99000D02*
X257608Y99042D01*
X257275Y99167D01*
X257067Y99375D01*
X256983Y99667D01*
X257067Y99958D01*
X257317Y100208D01*
X257692Y100333D01*
X258108D01*
X258358Y100417D01*
X258567Y100625D01*
X258650Y100917D01*
X258525Y101208D01*
X258233Y101417D01*
X257900Y101500D01*
X257567Y101417D01*
X257275Y101208D01*
X257150Y100917D01*
X257233Y100625D01*
X257442Y100417D01*
X257692Y100333D01*
X258108D01*
X258483Y100208D01*
X258733Y99958D01*
X258817Y99667D01*
X258733Y99375D01*
X258525Y99167D01*
X258192Y99042D01*
X257900Y99000D01*
G01X263183Y105292D02*
X263433Y105417D01*
X263725Y105500D01*
X264058D01*
X264433Y105375D01*
X264725Y105167D01*
X264933Y104917D01*
X265100Y104500D01*
X265142Y104125D01*
X265058Y103750D01*
X264933Y103500D01*
X264683Y103250D01*
X264392Y103083D01*
X264100Y103000D01*
X263808D01*
X263517Y103083D01*
X263267Y103208D01*
X263058Y103375D01*
G01X260500Y103000D02*
Y105500D01*
X262042Y103708D01*
X259958D01*
G01X258817Y103375D02*
X258567Y103167D01*
X258275Y103042D01*
X257900Y103000D01*
X257525Y103083D01*
X257233Y103250D01*
X257025Y103542D01*
X256983Y103875D01*
X257067Y104208D01*
X257275Y104417D01*
X257567Y104583D01*
X257858Y104625D01*
X258150Y104583D01*
X258525Y104417D01*
X258400Y105500D01*
X257275D01*
G01X264183Y127792D02*
X264433Y127917D01*
X264725Y128000D01*
X265058D01*
X265433Y127875D01*
X265725Y127667D01*
X265933Y127417D01*
X266100Y127000D01*
X266142Y126625D01*
X266058Y126250D01*
X265933Y126000D01*
X265683Y125750D01*
X265392Y125583D01*
X265100Y125500D01*
X264808D01*
X264517Y125583D01*
X264267Y125708D01*
X264058Y125875D01*
G01X262000Y125500D02*
X261708Y125542D01*
X261375Y125667D01*
X261167Y125875D01*
X261083Y126167D01*
X261167Y126458D01*
X261417Y126708D01*
X261792Y126833D01*
X262208D01*
X262458Y126917D01*
X262667Y127125D01*
X262750Y127417D01*
X262625Y127708D01*
X262333Y127917D01*
X262000Y128000D01*
X261667Y127917D01*
X261375Y127708D01*
X261250Y127417D01*
X261333Y127125D01*
X261542Y126917D01*
X261792Y126833D01*
X262208D01*
X262583Y126708D01*
X262833Y126458D01*
X262917Y126167D01*
X262833Y125875D01*
X262625Y125667D01*
X262292Y125542D01*
X262000Y125500D01*
G01X259692Y127583D02*
X259442Y127833D01*
X259150Y127958D01*
X258817Y128000D01*
X258400Y127917D01*
X258108Y127708D01*
X258025Y127458D01*
X258067Y127208D01*
X258233Y127000D01*
X259067Y126583D01*
X259442Y126292D01*
X259692Y125875D01*
X259775Y125500D01*
X258025D01*
G01X265017Y133000D02*
Y131208D01*
X264850Y130833D01*
X264517Y130583D01*
X264100Y130500D01*
X263683Y130583D01*
X263350Y130833D01*
X263183Y131208D01*
Y133000D01*
G01X260500Y130500D02*
Y133000D01*
X262042Y131208D01*
X259958D01*
G01X258817Y130875D02*
X258567Y130667D01*
X258275Y130542D01*
X257900Y130500D01*
X257525Y130583D01*
X257233Y130750D01*
X257025Y131042D01*
X256983Y131375D01*
X257067Y131708D01*
X257275Y131917D01*
X257567Y132083D01*
X257858Y132125D01*
X258150Y132083D01*
X258525Y131917D01*
X258400Y133000D01*
X257275D01*
G01X257000Y134967D02*
X259500D01*
Y135967D01*
X259375Y136300D01*
X259083Y136550D01*
X258750Y136633D01*
X258417Y136550D01*
X258167Y136342D01*
X258042Y135967D01*
Y134967D01*
G01X257000Y138067D02*
X259500D01*
Y139108D01*
X259375Y139442D01*
X259208Y139650D01*
X258875Y139733D01*
X258542Y139650D01*
X258333Y139400D01*
X258208Y139108D01*
Y138067D01*
G01Y139108D02*
X257000Y139733D01*
G01Y142000D02*
X259500D01*
X259000Y141500D01*
G01X257000D02*
Y142500D01*
G01X259083Y144308D02*
X259333Y144558D01*
X259458Y144850D01*
X259500Y145183D01*
X259417Y145600D01*
X259208Y145892D01*
X258958Y145975D01*
X258708Y145933D01*
X258500Y145767D01*
X258083Y144933D01*
X257792Y144558D01*
X257375Y144308D01*
X257000Y144225D01*
Y145975D01*
G01Y148200D02*
X257042Y148492D01*
X257167Y148825D01*
X257375Y149033D01*
X257667Y149117D01*
X257958Y149033D01*
X258208Y148783D01*
X258333Y148408D01*
Y147992D01*
X258417Y147742D01*
X258625Y147533D01*
X258917Y147450D01*
X259208Y147575D01*
X259417Y147867D01*
X259500Y148200D01*
X259417Y148533D01*
X259208Y148825D01*
X258917Y148950D01*
X258625Y148867D01*
X258417Y148658D01*
X258333Y148408D01*
Y147992D01*
X258208Y147617D01*
X257958Y147367D01*
X257667Y147283D01*
X257375Y147367D01*
X257167Y147575D01*
X257042Y147908D01*
X257000Y148200D01*
G01X258500Y150967D02*
X261000D01*
Y151967D01*
X260875Y152300D01*
X260583Y152550D01*
X260250Y152633D01*
X259917Y152550D01*
X259667Y152342D01*
X259542Y151967D01*
Y150967D01*
G01X258500Y154067D02*
X261000D01*
Y155108D01*
X260875Y155442D01*
X260708Y155650D01*
X260375Y155733D01*
X260042Y155650D01*
X259833Y155400D01*
X259708Y155108D01*
Y154067D01*
G01Y155108D02*
X258500Y155733D01*
G01Y158000D02*
X261000D01*
X260500Y157500D01*
G01X258500D02*
Y158500D01*
G01X260583Y160308D02*
X260833Y160558D01*
X260958Y160850D01*
X261000Y161183D01*
X260917Y161600D01*
X260708Y161892D01*
X260458Y161975D01*
X260208Y161933D01*
X260000Y161767D01*
X259583Y160933D01*
X259292Y160558D01*
X258875Y160308D01*
X258500Y160225D01*
Y161975D01*
G01Y164117D02*
X259042Y164200D01*
X259500Y164325D01*
X259917Y164492D01*
X260375Y164700D01*
X261000Y165033D01*
Y163367D01*
G01Y170400D02*
X261042Y170067D01*
X261208Y169775D01*
X261458Y169525D01*
X261750Y169358D01*
X262083Y169275D01*
X262417D01*
X262750Y169358D01*
X263042Y169525D01*
X263292Y169775D01*
X263458Y170067D01*
X263500Y170400D01*
X263458Y170733D01*
X263292Y171025D01*
X263042Y171275D01*
X262750Y171442D01*
X262417Y171525D01*
X262083D01*
X261750Y171442D01*
X261458Y171275D01*
X261208Y171025D01*
X261042Y170733D01*
X261000Y170400D01*
G01X261667Y170733D02*
X261000Y171233D01*
G01Y173500D02*
X263500D01*
X263000Y173000D01*
G01X261000D02*
Y174000D01*
G01Y177100D02*
X263500D01*
X261708Y175558D01*
Y177642D01*
G01X261000Y186017D02*
X263500D01*
Y187058D01*
X263375Y187392D01*
X263208Y187600D01*
X262875Y187683D01*
X262542Y187600D01*
X262333Y187350D01*
X262208Y187058D01*
Y186017D01*
G01Y187058D02*
X261000Y187683D01*
G01X263083Y189158D02*
X263333Y189408D01*
X263458Y189700D01*
X263500Y190033D01*
X263417Y190450D01*
X263208Y190742D01*
X262958Y190825D01*
X262708Y190783D01*
X262500Y190617D01*
X262083Y189783D01*
X261792Y189408D01*
X261375Y189158D01*
X261000Y189075D01*
Y190825D01*
G01X261292Y192342D02*
X261083Y192633D01*
X261000Y192967D01*
X261083Y193300D01*
X261333Y193592D01*
X261708Y193800D01*
X262083Y193883D01*
X262542D01*
X262917Y193800D01*
X263250Y193592D01*
X263417Y193342D01*
X263500Y193050D01*
X263417Y192717D01*
X263250Y192467D01*
X263000Y192300D01*
X262667Y192217D01*
X262375Y192300D01*
X262083Y192508D01*
X261917Y192758D01*
X261875Y193050D01*
X261958Y193383D01*
X262167Y193633D01*
X262542Y193883D01*
G01X261000Y196650D02*
X263500D01*
X261708Y195108D01*
Y197192D01*
G01X256292Y202767D02*
X256417Y202517D01*
X256500Y202225D01*
Y201892D01*
X256375Y201517D01*
X256167Y201225D01*
X255917Y201017D01*
X255500Y200850D01*
X255125Y200808D01*
X254750Y200892D01*
X254500Y201017D01*
X254250Y201267D01*
X254083Y201558D01*
X254000Y201850D01*
Y202142D01*
X254083Y202433D01*
X254208Y202683D01*
X254375Y202892D01*
G01X256083Y204158D02*
X256333Y204408D01*
X256458Y204700D01*
X256500Y205033D01*
X256417Y205450D01*
X256208Y205742D01*
X255958Y205825D01*
X255708Y205783D01*
X255500Y205617D01*
X255083Y204783D01*
X254792Y204408D01*
X254375Y204158D01*
X254000Y204075D01*
Y205825D01*
G01X256500Y208050D02*
X256417Y207717D01*
X256208Y207467D01*
X255958Y207300D01*
X255625Y207175D01*
X255250Y207133D01*
X254875Y207175D01*
X254542Y207300D01*
X254292Y207467D01*
X254083Y207717D01*
X254000Y208050D01*
X254083Y208383D01*
X254292Y208633D01*
X254542Y208800D01*
X254875Y208925D01*
X255250Y208967D01*
X255625Y208925D01*
X255958Y208800D01*
X256208Y208633D01*
X256417Y208383D01*
X256500Y208050D01*
G01Y211150D02*
X256417Y210817D01*
X256208Y210567D01*
X255958Y210400D01*
X255625Y210275D01*
X255250Y210233D01*
X254875Y210275D01*
X254542Y210400D01*
X254292Y210567D01*
X254083Y210817D01*
X254000Y211150D01*
X254083Y211483D01*
X254292Y211733D01*
X254542Y211900D01*
X254875Y212025D01*
X255250Y212067D01*
X255625Y212025D01*
X255958Y211900D01*
X256208Y211733D01*
X256417Y211483D01*
X256500Y211150D01*
G01X258000Y210517D02*
X260500D01*
Y211558D01*
X260375Y211892D01*
X260208Y212100D01*
X259875Y212183D01*
X259542Y212100D01*
X259333Y211850D01*
X259208Y211558D01*
Y210517D01*
G01Y211558D02*
X258000Y212183D01*
G01X258500Y213533D02*
X258208Y213783D01*
X258042Y214117D01*
X258000Y214492D01*
X258042Y214825D01*
X258250Y215158D01*
X258500Y215367D01*
X258750Y215408D01*
X259042Y215325D01*
X259250Y215033D01*
X259333Y214742D01*
Y214367D01*
G01Y214742D02*
X259458Y214992D01*
X259667Y215200D01*
X259917Y215283D01*
X260167Y215200D01*
X260375Y214992D01*
X260500Y214617D01*
X260458Y214242D01*
X260292Y213867D01*
G01X258500Y216633D02*
X258208Y216883D01*
X258042Y217217D01*
X258000Y217592D01*
X258042Y217925D01*
X258250Y218258D01*
X258500Y218467D01*
X258750Y218508D01*
X259042Y218425D01*
X259250Y218133D01*
X259333Y217842D01*
Y217467D01*
G01Y217842D02*
X259458Y218092D01*
X259667Y218300D01*
X259917Y218383D01*
X260167Y218300D01*
X260375Y218092D01*
X260500Y217717D01*
X260458Y217342D01*
X260292Y216967D01*
G01X258000Y221150D02*
X260500D01*
X258708Y219608D01*
Y221692D01*
G01X250000Y205017D02*
X252500D01*
Y206058D01*
X252375Y206392D01*
X252208Y206600D01*
X251875Y206683D01*
X251542Y206600D01*
X251333Y206350D01*
X251208Y206058D01*
Y205017D01*
G01Y206058D02*
X250000Y206683D01*
G01X250500Y208033D02*
X250208Y208283D01*
X250042Y208617D01*
X250000Y208992D01*
X250042Y209325D01*
X250250Y209658D01*
X250500Y209867D01*
X250750Y209908D01*
X251042Y209825D01*
X251250Y209533D01*
X251333Y209242D01*
Y208867D01*
G01Y209242D02*
X251458Y209492D01*
X251667Y209700D01*
X251917Y209783D01*
X252167Y209700D01*
X252375Y209492D01*
X252500Y209117D01*
X252458Y208742D01*
X252292Y208367D01*
G01X250500Y211133D02*
X250208Y211383D01*
X250042Y211717D01*
X250000Y212092D01*
X250042Y212425D01*
X250250Y212758D01*
X250500Y212967D01*
X250750Y213008D01*
X251042Y212925D01*
X251250Y212633D01*
X251333Y212342D01*
Y211967D01*
G01Y212342D02*
X251458Y212592D01*
X251667Y212800D01*
X251917Y212883D01*
X252167Y212800D01*
X252375Y212592D01*
X252500Y212217D01*
X252458Y211842D01*
X252292Y211467D01*
G01X252083Y214358D02*
X252333Y214608D01*
X252458Y214900D01*
X252500Y215233D01*
X252417Y215650D01*
X252208Y215942D01*
X251958Y216025D01*
X251708Y215983D01*
X251500Y215817D01*
X251083Y214983D01*
X250792Y214608D01*
X250375Y214358D01*
X250000Y214275D01*
Y216025D01*
G01X254000Y215017D02*
X256500D01*
Y216058D01*
X256375Y216392D01*
X256208Y216600D01*
X255875Y216683D01*
X255542Y216600D01*
X255333Y216350D01*
X255208Y216058D01*
Y215017D01*
G01Y216058D02*
X254000Y216683D01*
G01X254500Y218033D02*
X254208Y218283D01*
X254042Y218617D01*
X254000Y218992D01*
X254042Y219325D01*
X254250Y219658D01*
X254500Y219867D01*
X254750Y219908D01*
X255042Y219825D01*
X255250Y219533D01*
X255333Y219242D01*
Y218867D01*
G01Y219242D02*
X255458Y219492D01*
X255667Y219700D01*
X255917Y219783D01*
X256167Y219700D01*
X256375Y219492D01*
X256500Y219117D01*
X256458Y218742D01*
X256292Y218367D01*
G01X254500Y221133D02*
X254208Y221383D01*
X254042Y221717D01*
X254000Y222092D01*
X254042Y222425D01*
X254250Y222758D01*
X254500Y222967D01*
X254750Y223008D01*
X255042Y222925D01*
X255250Y222633D01*
X255333Y222342D01*
Y221967D01*
G01Y222342D02*
X255458Y222592D01*
X255667Y222800D01*
X255917Y222883D01*
X256167Y222800D01*
X256375Y222592D01*
X256500Y222217D01*
X256458Y221842D01*
X256292Y221467D01*
G01X256500Y225150D02*
X256417Y224817D01*
X256208Y224567D01*
X255958Y224400D01*
X255625Y224275D01*
X255250Y224233D01*
X254875Y224275D01*
X254542Y224400D01*
X254292Y224567D01*
X254083Y224817D01*
X254000Y225150D01*
X254083Y225483D01*
X254292Y225733D01*
X254542Y225900D01*
X254875Y226025D01*
X255250Y226067D01*
X255625Y226025D01*
X255958Y225900D01*
X256208Y225733D01*
X256417Y225483D01*
X256500Y225150D01*
G01X256800Y235500D02*
Y242500D01*
G01X251200D02*
Y235500D01*
G01Y239000D02*
X256800D01*
G01X270292Y37767D02*
X270417Y37517D01*
X270500Y37225D01*
Y36892D01*
X270375Y36517D01*
X270167Y36225D01*
X269917Y36017D01*
X269500Y35850D01*
X269125Y35808D01*
X268750Y35892D01*
X268500Y36017D01*
X268250Y36267D01*
X268083Y36558D01*
X268000Y36850D01*
Y37142D01*
X268083Y37433D01*
X268208Y37683D01*
X268375Y37892D01*
G01X270083Y39158D02*
X270333Y39408D01*
X270458Y39700D01*
X270500Y40033D01*
X270417Y40450D01*
X270208Y40742D01*
X269958Y40825D01*
X269708Y40783D01*
X269500Y40617D01*
X269083Y39783D01*
X268792Y39408D01*
X268375Y39158D01*
X268000Y39075D01*
Y40825D01*
G01Y43050D02*
X268042Y43342D01*
X268167Y43675D01*
X268375Y43883D01*
X268667Y43967D01*
X268958Y43883D01*
X269208Y43633D01*
X269333Y43258D01*
Y42842D01*
X269417Y42592D01*
X269625Y42383D01*
X269917Y42300D01*
X270208Y42425D01*
X270417Y42717D01*
X270500Y43050D01*
X270417Y43383D01*
X270208Y43675D01*
X269917Y43800D01*
X269625Y43717D01*
X269417Y43508D01*
X269333Y43258D01*
Y42842D01*
X269208Y42467D01*
X268958Y42217D01*
X268667Y42133D01*
X268375Y42217D01*
X268167Y42425D01*
X268042Y42758D01*
X268000Y43050D01*
G01Y46150D02*
X270500D01*
X270000Y45650D01*
G01X268000D02*
Y46650D01*
G01X274792Y37767D02*
X274917Y37517D01*
X275000Y37225D01*
Y36892D01*
X274875Y36517D01*
X274667Y36225D01*
X274417Y36017D01*
X274000Y35850D01*
X273625Y35808D01*
X273250Y35892D01*
X273000Y36017D01*
X272750Y36267D01*
X272583Y36558D01*
X272500Y36850D01*
Y37142D01*
X272583Y37433D01*
X272708Y37683D01*
X272875Y37892D01*
G01X274583Y39158D02*
X274833Y39408D01*
X274958Y39700D01*
X275000Y40033D01*
X274917Y40450D01*
X274708Y40742D01*
X274458Y40825D01*
X274208Y40783D01*
X274000Y40617D01*
X273583Y39783D01*
X273292Y39408D01*
X272875Y39158D01*
X272500Y39075D01*
Y40825D01*
G01Y43050D02*
X272542Y43342D01*
X272667Y43675D01*
X272875Y43883D01*
X273167Y43967D01*
X273458Y43883D01*
X273708Y43633D01*
X273833Y43258D01*
Y42842D01*
X273917Y42592D01*
X274125Y42383D01*
X274417Y42300D01*
X274708Y42425D01*
X274917Y42717D01*
X275000Y43050D01*
X274917Y43383D01*
X274708Y43675D01*
X274417Y43800D01*
X274125Y43717D01*
X273917Y43508D01*
X273833Y43258D01*
Y42842D01*
X273708Y42467D01*
X273458Y42217D01*
X273167Y42133D01*
X272875Y42217D01*
X272667Y42425D01*
X272542Y42758D01*
X272500Y43050D01*
G01X275000Y46150D02*
X274917Y45817D01*
X274708Y45567D01*
X274458Y45400D01*
X274125Y45275D01*
X273750Y45233D01*
X273375Y45275D01*
X273042Y45400D01*
X272792Y45567D01*
X272583Y45817D01*
X272500Y46150D01*
X272583Y46483D01*
X272792Y46733D01*
X273042Y46900D01*
X273375Y47025D01*
X273750Y47067D01*
X274125Y47025D01*
X274458Y46900D01*
X274708Y46733D01*
X274917Y46483D01*
X275000Y46150D01*
G01X278000Y36017D02*
X280500D01*
Y37058D01*
X280375Y37392D01*
X280208Y37600D01*
X279875Y37683D01*
X279542Y37600D01*
X279333Y37350D01*
X279208Y37058D01*
Y36017D01*
G01Y37058D02*
X278000Y37683D01*
G01Y40450D02*
X280500D01*
X278708Y38908D01*
Y40992D01*
G01X278000Y42967D02*
X278542Y43050D01*
X279000Y43175D01*
X279417Y43342D01*
X279875Y43550D01*
X280500Y43883D01*
Y42217D01*
G01X278292Y45442D02*
X278083Y45733D01*
X278000Y46067D01*
X278083Y46400D01*
X278333Y46692D01*
X278708Y46900D01*
X279083Y46983D01*
X279542D01*
X279917Y46900D01*
X280250Y46692D01*
X280417Y46442D01*
X280500Y46150D01*
X280417Y45817D01*
X280250Y45567D01*
X280000Y45400D01*
X279667Y45317D01*
X279375Y45400D01*
X279083Y45608D01*
X278917Y45858D01*
X278875Y46150D01*
X278958Y46483D01*
X279167Y46733D01*
X279542Y46983D01*
G01X285500Y106500D02*
Y110000D01*
X268500D01*
Y104500D01*
G01X279233Y117792D02*
X279483Y117917D01*
X279775Y118000D01*
X280108D01*
X280483Y117875D01*
X280775Y117667D01*
X280983Y117417D01*
X281150Y117000D01*
X281192Y116625D01*
X281108Y116250D01*
X280983Y116000D01*
X280733Y115750D01*
X280442Y115583D01*
X280150Y115500D01*
X279858D01*
X279567Y115583D01*
X279317Y115708D01*
X279108Y115875D01*
G01X277842Y117583D02*
X277592Y117833D01*
X277300Y117958D01*
X276967Y118000D01*
X276550Y117917D01*
X276258Y117708D01*
X276175Y117458D01*
X276217Y117208D01*
X276383Y117000D01*
X277217Y116583D01*
X277592Y116292D01*
X277842Y115875D01*
X277925Y115500D01*
X276175D01*
G01X273950D02*
X273658Y115542D01*
X273325Y115667D01*
X273117Y115875D01*
X273033Y116167D01*
X273117Y116458D01*
X273367Y116708D01*
X273742Y116833D01*
X274158D01*
X274408Y116917D01*
X274617Y117125D01*
X274700Y117417D01*
X274575Y117708D01*
X274283Y117917D01*
X273950Y118000D01*
X273617Y117917D01*
X273325Y117708D01*
X273200Y117417D01*
X273283Y117125D01*
X273492Y116917D01*
X273742Y116833D01*
X274158D01*
X274533Y116708D01*
X274783Y116458D01*
X274867Y116167D01*
X274783Y115875D01*
X274575Y115667D01*
X274242Y115542D01*
X273950Y115500D01*
G01X271642Y117583D02*
X271392Y117833D01*
X271100Y117958D01*
X270767Y118000D01*
X270350Y117917D01*
X270058Y117708D01*
X269975Y117458D01*
X270017Y117208D01*
X270183Y117000D01*
X271017Y116583D01*
X271392Y116292D01*
X271642Y115875D01*
X271725Y115500D01*
X269975D01*
G01X279233Y113792D02*
X279483Y113917D01*
X279775Y114000D01*
X280108D01*
X280483Y113875D01*
X280775Y113667D01*
X280983Y113417D01*
X281150Y113000D01*
X281192Y112625D01*
X281108Y112250D01*
X280983Y112000D01*
X280733Y111750D01*
X280442Y111583D01*
X280150Y111500D01*
X279858D01*
X279567Y111583D01*
X279317Y111708D01*
X279108Y111875D01*
G01X277842Y113583D02*
X277592Y113833D01*
X277300Y113958D01*
X276967Y114000D01*
X276550Y113917D01*
X276258Y113708D01*
X276175Y113458D01*
X276217Y113208D01*
X276383Y113000D01*
X277217Y112583D01*
X277592Y112292D01*
X277842Y111875D01*
X277925Y111500D01*
X276175D01*
G01X273950D02*
X273658Y111542D01*
X273325Y111667D01*
X273117Y111875D01*
X273033Y112167D01*
X273117Y112458D01*
X273367Y112708D01*
X273742Y112833D01*
X274158D01*
X274408Y112917D01*
X274617Y113125D01*
X274700Y113417D01*
X274575Y113708D01*
X274283Y113917D01*
X273950Y114000D01*
X273617Y113917D01*
X273325Y113708D01*
X273200Y113417D01*
X273283Y113125D01*
X273492Y112917D01*
X273742Y112833D01*
X274158D01*
X274533Y112708D01*
X274783Y112458D01*
X274867Y112167D01*
X274783Y111875D01*
X274575Y111667D01*
X274242Y111542D01*
X273950Y111500D01*
G01X271767Y112000D02*
X271517Y111708D01*
X271183Y111542D01*
X270808Y111500D01*
X270475Y111542D01*
X270142Y111750D01*
X269933Y112000D01*
X269892Y112250D01*
X269975Y112542D01*
X270267Y112750D01*
X270558Y112833D01*
X270933D01*
G01X270558D02*
X270308Y112958D01*
X270100Y113167D01*
X270017Y113417D01*
X270100Y113667D01*
X270308Y113875D01*
X270683Y114000D01*
X271058Y113958D01*
X271433Y113792D01*
G01X270900Y131150D02*
X273500D01*
G01X270900Y139050D02*
Y131150D01*
G01X273500D02*
Y139050D01*
G01X278000Y141000D02*
X280000D01*
Y143000D01*
X286500D01*
Y141000D01*
G01X287000Y160500D02*
Y158500D01*
X283000D01*
Y162000D01*
X272000D01*
Y158500D01*
X266500D01*
Y149500D01*
G01X267000Y144000D02*
Y141000D01*
X268500D01*
G01X268050Y150300D02*
Y147700D01*
G01X275950Y150300D02*
X268050D01*
G01X275950Y147700D02*
Y150300D01*
G01X268050Y147700D02*
X275950D01*
G01X273500Y139050D02*
X270900D01*
G01X278750Y174250D02*
Y170750D01*
X265250D01*
Y174250D01*
X278750D01*
G01X265000Y186017D02*
X267500D01*
Y187058D01*
X267375Y187392D01*
X267208Y187600D01*
X266875Y187683D01*
X266542Y187600D01*
X266333Y187350D01*
X266208Y187058D01*
Y186017D01*
G01Y187058D02*
X265000Y187683D01*
G01X265500Y189033D02*
X265208Y189283D01*
X265042Y189617D01*
X265000Y189992D01*
X265042Y190325D01*
X265250Y190658D01*
X265500Y190867D01*
X265750Y190908D01*
X266042Y190825D01*
X266250Y190533D01*
X266333Y190242D01*
Y189867D01*
G01Y190242D02*
X266458Y190492D01*
X266667Y190700D01*
X266917Y190783D01*
X267167Y190700D01*
X267375Y190492D01*
X267500Y190117D01*
X267458Y189742D01*
X267292Y189367D01*
G01X267500Y193050D02*
X267417Y192717D01*
X267208Y192467D01*
X266958Y192300D01*
X266625Y192175D01*
X266250Y192133D01*
X265875Y192175D01*
X265542Y192300D01*
X265292Y192467D01*
X265083Y192717D01*
X265000Y193050D01*
X265083Y193383D01*
X265292Y193633D01*
X265542Y193800D01*
X265875Y193925D01*
X266250Y193967D01*
X266625Y193925D01*
X266958Y193800D01*
X267208Y193633D01*
X267417Y193383D01*
X267500Y193050D01*
G01Y196150D02*
X267417Y195817D01*
X267208Y195567D01*
X266958Y195400D01*
X266625Y195275D01*
X266250Y195233D01*
X265875Y195275D01*
X265542Y195400D01*
X265292Y195567D01*
X265083Y195817D01*
X265000Y196150D01*
X265083Y196483D01*
X265292Y196733D01*
X265542Y196900D01*
X265875Y197025D01*
X266250Y197067D01*
X266625Y197025D01*
X266958Y196900D01*
X267208Y196733D01*
X267417Y196483D01*
X267500Y196150D01*
G01X269000Y186017D02*
X271500D01*
Y187058D01*
X271375Y187392D01*
X271208Y187600D01*
X270875Y187683D01*
X270542Y187600D01*
X270333Y187350D01*
X270208Y187058D01*
Y186017D01*
G01Y187058D02*
X269000Y187683D01*
G01X271083Y189158D02*
X271333Y189408D01*
X271458Y189700D01*
X271500Y190033D01*
X271417Y190450D01*
X271208Y190742D01*
X270958Y190825D01*
X270708Y190783D01*
X270500Y190617D01*
X270083Y189783D01*
X269792Y189408D01*
X269375Y189158D01*
X269000Y189075D01*
Y190825D01*
G01X269292Y192342D02*
X269083Y192633D01*
X269000Y192967D01*
X269083Y193300D01*
X269333Y193592D01*
X269708Y193800D01*
X270083Y193883D01*
X270542D01*
X270917Y193800D01*
X271250Y193592D01*
X271417Y193342D01*
X271500Y193050D01*
X271417Y192717D01*
X271250Y192467D01*
X271000Y192300D01*
X270667Y192217D01*
X270375Y192300D01*
X270083Y192508D01*
X269917Y192758D01*
X269875Y193050D01*
X269958Y193383D01*
X270167Y193633D01*
X270542Y193883D01*
G01X269375Y195233D02*
X269167Y195483D01*
X269042Y195775D01*
X269000Y196150D01*
X269083Y196525D01*
X269250Y196817D01*
X269542Y197025D01*
X269875Y197067D01*
X270208Y196983D01*
X270417Y196775D01*
X270583Y196483D01*
X270625Y196192D01*
X270583Y195900D01*
X270417Y195525D01*
X271500Y195650D01*
Y196775D01*
G01X272000Y201017D02*
X274500D01*
Y202058D01*
X274375Y202392D01*
X274208Y202600D01*
X273875Y202683D01*
X273542Y202600D01*
X273333Y202350D01*
X273208Y202058D01*
Y201017D01*
G01Y202058D02*
X272000Y202683D01*
G01X274083Y204158D02*
X274333Y204408D01*
X274458Y204700D01*
X274500Y205033D01*
X274417Y205450D01*
X274208Y205742D01*
X273958Y205825D01*
X273708Y205783D01*
X273500Y205617D01*
X273083Y204783D01*
X272792Y204408D01*
X272375Y204158D01*
X272000Y204075D01*
Y205825D01*
G01X273042Y207258D02*
X273333Y207550D01*
X273500Y207800D01*
X273583Y208133D01*
X273500Y208425D01*
X273333Y208633D01*
X273083Y208800D01*
X272792Y208842D01*
X272542Y208800D01*
X272292Y208633D01*
X272083Y208383D01*
X272000Y208092D01*
X272083Y207758D01*
X272333Y207467D01*
X272708Y207300D01*
X273125Y207258D01*
X273667Y207342D01*
X273958Y207467D01*
X274250Y207675D01*
X274458Y207967D01*
X274500Y208258D01*
X274417Y208550D01*
X274208Y208758D01*
G01X274083Y210358D02*
X274333Y210608D01*
X274458Y210900D01*
X274500Y211233D01*
X274417Y211650D01*
X274208Y211942D01*
X273958Y212025D01*
X273708Y211983D01*
X273500Y211817D01*
X273083Y210983D01*
X272792Y210608D01*
X272375Y210358D01*
X272000Y210275D01*
Y212025D01*
G01X268000Y201017D02*
X270500D01*
Y202058D01*
X270375Y202392D01*
X270208Y202600D01*
X269875Y202683D01*
X269542Y202600D01*
X269333Y202350D01*
X269208Y202058D01*
Y201017D01*
G01Y202058D02*
X268000Y202683D01*
G01X270083Y204158D02*
X270333Y204408D01*
X270458Y204700D01*
X270500Y205033D01*
X270417Y205450D01*
X270208Y205742D01*
X269958Y205825D01*
X269708Y205783D01*
X269500Y205617D01*
X269083Y204783D01*
X268792Y204408D01*
X268375Y204158D01*
X268000Y204075D01*
Y205825D01*
G01Y207967D02*
X268542Y208050D01*
X269000Y208175D01*
X269417Y208342D01*
X269875Y208550D01*
X270500Y208883D01*
Y207217D01*
G01X268375Y210233D02*
X268167Y210483D01*
X268042Y210775D01*
X268000Y211150D01*
X268083Y211525D01*
X268250Y211817D01*
X268542Y212025D01*
X268875Y212067D01*
X269208Y211983D01*
X269417Y211775D01*
X269583Y211483D01*
X269625Y211192D01*
X269583Y210900D01*
X269417Y210525D01*
X270500Y210650D01*
Y211775D01*
G01X277292Y228817D02*
X277417Y228567D01*
X277500Y228275D01*
Y227942D01*
X277375Y227567D01*
X277167Y227275D01*
X276917Y227067D01*
X276500Y226900D01*
X276125Y226858D01*
X275750Y226942D01*
X275500Y227067D01*
X275250Y227317D01*
X275083Y227608D01*
X275000Y227900D01*
Y228192D01*
X275083Y228483D01*
X275208Y228733D01*
X275375Y228942D01*
G01X275000Y230917D02*
X275542Y231000D01*
X276000Y231125D01*
X276417Y231292D01*
X276875Y231500D01*
X277500Y231833D01*
Y230167D01*
G01X275292Y233392D02*
X275083Y233683D01*
X275000Y234017D01*
X275083Y234350D01*
X275333Y234642D01*
X275708Y234850D01*
X276083Y234933D01*
X276542D01*
X276917Y234850D01*
X277250Y234642D01*
X277417Y234392D01*
X277500Y234100D01*
X277417Y233767D01*
X277250Y233517D01*
X277000Y233350D01*
X276667Y233267D01*
X276375Y233350D01*
X276083Y233558D01*
X275917Y233808D01*
X275875Y234100D01*
X275958Y234433D01*
X276167Y234683D01*
X276542Y234933D01*
G01X273292Y228817D02*
X273417Y228567D01*
X273500Y228275D01*
Y227942D01*
X273375Y227567D01*
X273167Y227275D01*
X272917Y227067D01*
X272500Y226900D01*
X272125Y226858D01*
X271750Y226942D01*
X271500Y227067D01*
X271250Y227317D01*
X271083Y227608D01*
X271000Y227900D01*
Y228192D01*
X271083Y228483D01*
X271208Y228733D01*
X271375Y228942D01*
G01X271000Y231000D02*
X271042Y231292D01*
X271167Y231625D01*
X271375Y231833D01*
X271667Y231917D01*
X271958Y231833D01*
X272208Y231583D01*
X272333Y231208D01*
Y230792D01*
X272417Y230542D01*
X272625Y230333D01*
X272917Y230250D01*
X273208Y230375D01*
X273417Y230667D01*
X273500Y231000D01*
X273417Y231333D01*
X273208Y231625D01*
X272917Y231750D01*
X272625Y231667D01*
X272417Y231458D01*
X272333Y231208D01*
Y230792D01*
X272208Y230417D01*
X271958Y230167D01*
X271667Y230083D01*
X271375Y230167D01*
X271167Y230375D01*
X271042Y230708D01*
X271000Y231000D01*
G01X273500Y234100D02*
X273417Y233767D01*
X273208Y233517D01*
X272958Y233350D01*
X272625Y233225D01*
X272250Y233183D01*
X271875Y233225D01*
X271542Y233350D01*
X271292Y233517D01*
X271083Y233767D01*
X271000Y234100D01*
X271083Y234433D01*
X271292Y234683D01*
X271542Y234850D01*
X271875Y234975D01*
X272250Y235017D01*
X272625Y234975D01*
X272958Y234850D01*
X273208Y234683D01*
X273417Y234433D01*
X273500Y234100D01*
G01X267000Y227017D02*
X269500D01*
Y228058D01*
X269375Y228392D01*
X269208Y228600D01*
X268875Y228683D01*
X268542Y228600D01*
X268333Y228350D01*
X268208Y228058D01*
Y227017D01*
G01Y228058D02*
X267000Y228683D01*
G01Y231450D02*
X269500D01*
X267708Y229908D01*
Y231992D01*
G01X267292Y233342D02*
X267083Y233633D01*
X267000Y233967D01*
X267083Y234300D01*
X267333Y234592D01*
X267708Y234800D01*
X268083Y234883D01*
X268542D01*
X268917Y234800D01*
X269250Y234592D01*
X269417Y234342D01*
X269500Y234050D01*
X269417Y233717D01*
X269250Y233467D01*
X269000Y233300D01*
X268667Y233217D01*
X268375Y233300D01*
X268083Y233508D01*
X267917Y233758D01*
X267875Y234050D01*
X267958Y234383D01*
X268167Y234633D01*
X268542Y234883D01*
G01X267375Y236233D02*
X267167Y236483D01*
X267042Y236775D01*
X267000Y237150D01*
X267083Y237525D01*
X267250Y237817D01*
X267542Y238025D01*
X267875Y238067D01*
X268208Y237983D01*
X268417Y237775D01*
X268583Y237483D01*
X268625Y237192D01*
X268583Y236900D01*
X268417Y236525D01*
X269500Y236650D01*
Y237775D01*
G01X275483Y250500D02*
Y253000D01*
X274442D01*
X274108Y252875D01*
X273900Y252708D01*
X273817Y252375D01*
X273900Y252042D01*
X274150Y251833D01*
X274442Y251708D01*
X275483D01*
G01X274442D02*
X273817Y250500D01*
G01X271550D02*
Y253000D01*
X272050Y252500D01*
G01Y250500D02*
X271050D01*
G01X268533D02*
X268450Y251042D01*
X268325Y251500D01*
X268158Y251917D01*
X267950Y252375D01*
X267617Y253000D01*
X269283D01*
G01X266142Y252583D02*
X265892Y252833D01*
X265600Y252958D01*
X265267Y253000D01*
X264850Y252917D01*
X264558Y252708D01*
X264475Y252458D01*
X264517Y252208D01*
X264683Y252000D01*
X265517Y251583D01*
X265892Y251292D01*
X266142Y250875D01*
X266225Y250500D01*
X264475D01*
G01X294292Y48767D02*
X294417Y48517D01*
X294500Y48225D01*
Y47892D01*
X294375Y47517D01*
X294167Y47225D01*
X293917Y47017D01*
X293500Y46850D01*
X293125Y46808D01*
X292750Y46892D01*
X292500Y47017D01*
X292250Y47267D01*
X292083Y47558D01*
X292000Y47850D01*
Y48142D01*
X292083Y48433D01*
X292208Y48683D01*
X292375Y48892D01*
G01X294083Y50158D02*
X294333Y50408D01*
X294458Y50700D01*
X294500Y51033D01*
X294417Y51450D01*
X294208Y51742D01*
X293958Y51825D01*
X293708Y51783D01*
X293500Y51617D01*
X293083Y50783D01*
X292792Y50408D01*
X292375Y50158D01*
X292000Y50075D01*
Y51825D01*
G01Y53967D02*
X292542Y54050D01*
X293000Y54175D01*
X293417Y54342D01*
X293875Y54550D01*
X294500Y54883D01*
Y53217D01*
G01X292000Y57150D02*
X292042Y57442D01*
X292167Y57775D01*
X292375Y57983D01*
X292667Y58067D01*
X292958Y57983D01*
X293208Y57733D01*
X293333Y57358D01*
Y56942D01*
X293417Y56692D01*
X293625Y56483D01*
X293917Y56400D01*
X294208Y56525D01*
X294417Y56817D01*
X294500Y57150D01*
X294417Y57483D01*
X294208Y57775D01*
X293917Y57900D01*
X293625Y57817D01*
X293417Y57608D01*
X293333Y57358D01*
Y56942D01*
X293208Y56567D01*
X292958Y56317D01*
X292667Y56233D01*
X292375Y56317D01*
X292167Y56525D01*
X292042Y56858D01*
X292000Y57150D01*
G01X284292Y46767D02*
X284417Y46517D01*
X284500Y46225D01*
Y45892D01*
X284375Y45517D01*
X284167Y45225D01*
X283917Y45017D01*
X283500Y44850D01*
X283125Y44808D01*
X282750Y44892D01*
X282500Y45017D01*
X282250Y45267D01*
X282083Y45558D01*
X282000Y45850D01*
Y46142D01*
X282083Y46433D01*
X282208Y46683D01*
X282375Y46892D01*
G01X284083Y48158D02*
X284333Y48408D01*
X284458Y48700D01*
X284500Y49033D01*
X284417Y49450D01*
X284208Y49742D01*
X283958Y49825D01*
X283708Y49783D01*
X283500Y49617D01*
X283083Y48783D01*
X282792Y48408D01*
X282375Y48158D01*
X282000Y48075D01*
Y49825D01*
G01Y51967D02*
X282542Y52050D01*
X283000Y52175D01*
X283417Y52342D01*
X283875Y52550D01*
X284500Y52883D01*
Y51217D01*
G01X282292Y54442D02*
X282083Y54733D01*
X282000Y55067D01*
X282083Y55400D01*
X282333Y55692D01*
X282708Y55900D01*
X283083Y55983D01*
X283542D01*
X283917Y55900D01*
X284250Y55692D01*
X284417Y55442D01*
X284500Y55150D01*
X284417Y54817D01*
X284250Y54567D01*
X284000Y54400D01*
X283667Y54317D01*
X283375Y54400D01*
X283083Y54608D01*
X282917Y54858D01*
X282875Y55150D01*
X282958Y55483D01*
X283167Y55733D01*
X283542Y55983D01*
G01X285500Y106500D02*
Y105500D01*
X305500D01*
G01X298650Y103500D02*
Y101000D01*
G01X299608Y103500D02*
X297692D01*
G01X296383Y101000D02*
Y103500D01*
X295383D01*
X295050Y103375D01*
X294800Y103083D01*
X294717Y102750D01*
X294800Y102417D01*
X295008Y102167D01*
X295383Y102042D01*
X296383D01*
G01X291950Y101000D02*
Y103500D01*
X293492Y101708D01*
X291408D01*
G01X290267Y101375D02*
X290017Y101167D01*
X289725Y101042D01*
X289350Y101000D01*
X288975Y101083D01*
X288683Y101250D01*
X288475Y101542D01*
X288433Y101875D01*
X288517Y102208D01*
X288725Y102417D01*
X289017Y102583D01*
X289308Y102625D01*
X289600Y102583D01*
X289975Y102417D01*
X289850Y103500D01*
X288725D01*
G01X283292Y120767D02*
X283417Y120517D01*
X283500Y120225D01*
Y119892D01*
X283375Y119517D01*
X283167Y119225D01*
X282917Y119017D01*
X282500Y118850D01*
X282125Y118808D01*
X281750Y118892D01*
X281500Y119017D01*
X281250Y119267D01*
X281083Y119558D01*
X281000Y119850D01*
Y120142D01*
X281083Y120433D01*
X281208Y120683D01*
X281375Y120892D01*
G01X281000Y122950D02*
X283500D01*
X283000Y122450D01*
G01X281000D02*
Y123450D01*
G01X281292Y125342D02*
X281083Y125633D01*
X281000Y125967D01*
X281083Y126300D01*
X281333Y126592D01*
X281708Y126800D01*
X282083Y126883D01*
X282542D01*
X282917Y126800D01*
X283250Y126592D01*
X283417Y126342D01*
X283500Y126050D01*
X283417Y125717D01*
X283250Y125467D01*
X283000Y125300D01*
X282667Y125217D01*
X282375Y125300D01*
X282083Y125508D01*
X281917Y125758D01*
X281875Y126050D01*
X281958Y126383D01*
X282167Y126633D01*
X282542Y126883D01*
G01X281000Y129150D02*
X283500D01*
X283000Y128650D01*
G01X281000D02*
Y129650D01*
G01X285000Y116017D02*
X287500D01*
Y117058D01*
X287375Y117392D01*
X287208Y117600D01*
X286875Y117683D01*
X286542Y117600D01*
X286333Y117350D01*
X286208Y117058D01*
Y116017D01*
G01Y117058D02*
X285000Y117683D01*
G01X285500Y119033D02*
X285208Y119283D01*
X285042Y119617D01*
X285000Y119992D01*
X285042Y120325D01*
X285250Y120658D01*
X285500Y120867D01*
X285750Y120908D01*
X286042Y120825D01*
X286250Y120533D01*
X286333Y120242D01*
Y119867D01*
G01Y120242D02*
X286458Y120492D01*
X286667Y120700D01*
X286917Y120783D01*
X287167Y120700D01*
X287375Y120492D01*
X287500Y120117D01*
X287458Y119742D01*
X287292Y119367D01*
G01X285500Y122133D02*
X285208Y122383D01*
X285042Y122717D01*
X285000Y123092D01*
X285042Y123425D01*
X285250Y123758D01*
X285500Y123967D01*
X285750Y124008D01*
X286042Y123925D01*
X286250Y123633D01*
X286333Y123342D01*
Y122967D01*
G01Y123342D02*
X286458Y123592D01*
X286667Y123800D01*
X286917Y123883D01*
X287167Y123800D01*
X287375Y123592D01*
X287500Y123217D01*
X287458Y122842D01*
X287292Y122467D01*
G01X285375Y125233D02*
X285167Y125483D01*
X285042Y125775D01*
X285000Y126150D01*
X285083Y126525D01*
X285250Y126817D01*
X285542Y127025D01*
X285875Y127067D01*
X286208Y126983D01*
X286417Y126775D01*
X286583Y126483D01*
X286625Y126192D01*
X286583Y125900D01*
X286417Y125525D01*
X287500Y125650D01*
Y126775D01*
G01X296983Y137000D02*
Y139500D01*
X295942D01*
X295608Y139375D01*
X295400Y139208D01*
X295317Y138875D01*
X295400Y138542D01*
X295650Y138333D01*
X295942Y138208D01*
X296983D01*
G01X295942D02*
X295317Y137000D01*
G01X293967Y137500D02*
X293717Y137208D01*
X293383Y137042D01*
X293008Y137000D01*
X292675Y137042D01*
X292342Y137250D01*
X292133Y137500D01*
X292092Y137750D01*
X292175Y138042D01*
X292467Y138250D01*
X292758Y138333D01*
X293133D01*
G01X292758D02*
X292508Y138458D01*
X292300Y138667D01*
X292217Y138917D01*
X292300Y139167D01*
X292508Y139375D01*
X292883Y139500D01*
X293258Y139458D01*
X293633Y139292D01*
G01X290742Y139083D02*
X290492Y139333D01*
X290200Y139458D01*
X289867Y139500D01*
X289450Y139417D01*
X289158Y139208D01*
X289075Y138958D01*
X289117Y138708D01*
X289283Y138500D01*
X290117Y138083D01*
X290492Y137792D01*
X290742Y137375D01*
X290825Y137000D01*
X289075D01*
G01X287558Y137292D02*
X287267Y137083D01*
X286933Y137000D01*
X286600Y137083D01*
X286308Y137333D01*
X286100Y137708D01*
X286017Y138083D01*
Y138542D01*
X286100Y138917D01*
X286308Y139250D01*
X286558Y139417D01*
X286850Y139500D01*
X287183Y139417D01*
X287433Y139250D01*
X287600Y139000D01*
X287683Y138667D01*
X287600Y138375D01*
X287392Y138083D01*
X287142Y137917D01*
X286850Y137875D01*
X286517Y137958D01*
X286267Y138167D01*
X286017Y138542D01*
G01X285000Y170517D02*
X287500D01*
Y171558D01*
X287375Y171892D01*
X287208Y172100D01*
X286875Y172183D01*
X286542Y172100D01*
X286333Y171850D01*
X286208Y171558D01*
Y170517D01*
G01Y171558D02*
X285000Y172183D01*
G01Y174950D02*
X287500D01*
X285708Y173408D01*
Y175492D01*
G01X287500Y177550D02*
X287417Y177217D01*
X287208Y176967D01*
X286958Y176800D01*
X286625Y176675D01*
X286250Y176633D01*
X285875Y176675D01*
X285542Y176800D01*
X285292Y176967D01*
X285083Y177217D01*
X285000Y177550D01*
X285083Y177883D01*
X285292Y178133D01*
X285542Y178300D01*
X285875Y178425D01*
X286250Y178467D01*
X286625Y178425D01*
X286958Y178300D01*
X287208Y178133D01*
X287417Y177883D01*
X287500Y177550D01*
G01X285000Y181150D02*
X287500D01*
X285708Y179608D01*
Y181692D01*
G01X299683Y219792D02*
X299933Y219917D01*
X300225Y220000D01*
X300558D01*
X300933Y219875D01*
X301225Y219667D01*
X301433Y219417D01*
X301600Y219000D01*
X301642Y218625D01*
X301558Y218250D01*
X301433Y218000D01*
X301183Y217750D01*
X300892Y217583D01*
X300600Y217500D01*
X300308D01*
X300017Y217583D01*
X299767Y217708D01*
X299558Y217875D01*
G01X297583Y217500D02*
X297500Y218042D01*
X297375Y218500D01*
X297208Y218917D01*
X297000Y219375D01*
X296667Y220000D01*
X298333D01*
G01X294400Y217500D02*
Y220000D01*
X294900Y219500D01*
G01Y217500D02*
X293900D01*
G01X292983Y223000D02*
Y225500D01*
X291942D01*
X291608Y225375D01*
X291400Y225208D01*
X291317Y224875D01*
X291400Y224542D01*
X291650Y224333D01*
X291942Y224208D01*
X292983D01*
G01X291942D02*
X291317Y223000D01*
G01X289050D02*
Y225500D01*
X289550Y225000D01*
G01Y223000D02*
X288550D01*
G01X286867Y223500D02*
X286617Y223208D01*
X286283Y223042D01*
X285908Y223000D01*
X285575Y223042D01*
X285242Y223250D01*
X285033Y223500D01*
X284992Y223750D01*
X285075Y224042D01*
X285367Y224250D01*
X285658Y224333D01*
X286033D01*
G01X285658D02*
X285408Y224458D01*
X285200Y224667D01*
X285117Y224917D01*
X285200Y225167D01*
X285408Y225375D01*
X285783Y225500D01*
X286158Y225458D01*
X286533Y225292D01*
G01X283642Y224042D02*
X283350Y224333D01*
X283100Y224500D01*
X282767Y224583D01*
X282475Y224500D01*
X282267Y224333D01*
X282100Y224083D01*
X282058Y223792D01*
X282100Y223542D01*
X282267Y223292D01*
X282517Y223083D01*
X282808Y223000D01*
X283142Y223083D01*
X283433Y223333D01*
X283600Y223708D01*
X283642Y224125D01*
X283558Y224667D01*
X283433Y224958D01*
X283225Y225250D01*
X282933Y225458D01*
X282642Y225500D01*
X282350Y225417D01*
X282142Y225208D01*
G01X292983Y227000D02*
Y229500D01*
X291942D01*
X291608Y229375D01*
X291400Y229208D01*
X291317Y228875D01*
X291400Y228542D01*
X291650Y228333D01*
X291942Y228208D01*
X292983D01*
G01X291942D02*
X291317Y227000D01*
G01X289050D02*
Y229500D01*
X289550Y229000D01*
G01Y227000D02*
X288550D01*
G01X286867Y227500D02*
X286617Y227208D01*
X286283Y227042D01*
X285908Y227000D01*
X285575Y227042D01*
X285242Y227250D01*
X285033Y227500D01*
X284992Y227750D01*
X285075Y228042D01*
X285367Y228250D01*
X285658Y228333D01*
X286033D01*
G01X285658D02*
X285408Y228458D01*
X285200Y228667D01*
X285117Y228917D01*
X285200Y229167D01*
X285408Y229375D01*
X285783Y229500D01*
X286158Y229458D01*
X286533Y229292D01*
G01X283767Y227375D02*
X283517Y227167D01*
X283225Y227042D01*
X282850Y227000D01*
X282475Y227083D01*
X282183Y227250D01*
X281975Y227542D01*
X281933Y227875D01*
X282017Y228208D01*
X282225Y228417D01*
X282517Y228583D01*
X282808Y228625D01*
X283100Y228583D01*
X283475Y228417D01*
X283350Y229500D01*
X282225D01*
G01X295483Y242500D02*
Y245000D01*
X294442D01*
X294108Y244875D01*
X293900Y244708D01*
X293817Y244375D01*
X293900Y244042D01*
X294150Y243833D01*
X294442Y243708D01*
X295483D01*
G01X294442D02*
X293817Y242500D01*
G01X291550D02*
Y245000D01*
X292050Y244500D01*
G01Y242500D02*
X291050D01*
G01X289367Y242875D02*
X289117Y242667D01*
X288825Y242542D01*
X288450Y242500D01*
X288075Y242583D01*
X287783Y242750D01*
X287575Y243042D01*
X287533Y243375D01*
X287617Y243708D01*
X287825Y243917D01*
X288117Y244083D01*
X288408Y244125D01*
X288700Y244083D01*
X289075Y243917D01*
X288950Y245000D01*
X287825D01*
G01X286058Y242792D02*
X285767Y242583D01*
X285433Y242500D01*
X285100Y242583D01*
X284808Y242833D01*
X284600Y243208D01*
X284517Y243583D01*
Y244042D01*
X284600Y244417D01*
X284808Y244750D01*
X285058Y244917D01*
X285350Y245000D01*
X285683Y244917D01*
X285933Y244750D01*
X286100Y244500D01*
X286183Y244167D01*
X286100Y243875D01*
X285892Y243583D01*
X285642Y243417D01*
X285350Y243375D01*
X285017Y243458D01*
X284767Y243667D01*
X284517Y244042D01*
G01X292483Y237000D02*
Y239500D01*
X291442D01*
X291108Y239375D01*
X290900Y239208D01*
X290817Y238875D01*
X290900Y238542D01*
X291150Y238333D01*
X291442Y238208D01*
X292483D01*
G01X291442D02*
X290817Y237000D01*
G01X288050D02*
Y239500D01*
X289592Y237708D01*
X287508D01*
G01X285450Y237000D02*
X285158Y237042D01*
X284825Y237167D01*
X284617Y237375D01*
X284533Y237667D01*
X284617Y237958D01*
X284867Y238208D01*
X285242Y238333D01*
X285658D01*
X285908Y238417D01*
X286117Y238625D01*
X286200Y238917D01*
X286075Y239208D01*
X285783Y239417D01*
X285450Y239500D01*
X285117Y239417D01*
X284825Y239208D01*
X284700Y238917D01*
X284783Y238625D01*
X284992Y238417D01*
X285242Y238333D01*
X285658D01*
X286033Y238208D01*
X286283Y237958D01*
X286367Y237667D01*
X286283Y237375D01*
X286075Y237167D01*
X285742Y237042D01*
X285450Y237000D01*
G01X283142Y238042D02*
X282850Y238333D01*
X282600Y238500D01*
X282267Y238583D01*
X281975Y238500D01*
X281767Y238333D01*
X281600Y238083D01*
X281558Y237792D01*
X281600Y237542D01*
X281767Y237292D01*
X282017Y237083D01*
X282308Y237000D01*
X282642Y237083D01*
X282933Y237333D01*
X283100Y237708D01*
X283142Y238125D01*
X283058Y238667D01*
X282933Y238958D01*
X282725Y239250D01*
X282433Y239458D01*
X282142Y239500D01*
X281850Y239417D01*
X281642Y239208D01*
G01X293500Y247517D02*
X296000D01*
Y248558D01*
X295875Y248892D01*
X295708Y249100D01*
X295375Y249183D01*
X295042Y249100D01*
X294833Y248850D01*
X294708Y248558D01*
Y247517D01*
G01Y248558D02*
X293500Y249183D01*
G01Y251450D02*
X296000D01*
X295500Y250950D01*
G01X293500D02*
Y251950D01*
G01X293792Y253842D02*
X293583Y254133D01*
X293500Y254467D01*
X293583Y254800D01*
X293833Y255092D01*
X294208Y255300D01*
X294583Y255383D01*
X295042D01*
X295417Y255300D01*
X295750Y255092D01*
X295917Y254842D01*
X296000Y254550D01*
X295917Y254217D01*
X295750Y253967D01*
X295500Y253800D01*
X295167Y253717D01*
X294875Y253800D01*
X294583Y254008D01*
X294417Y254258D01*
X294375Y254550D01*
X294458Y254883D01*
X294667Y255133D01*
X295042Y255383D01*
G01X296000Y257650D02*
X295917Y257317D01*
X295708Y257067D01*
X295458Y256900D01*
X295125Y256775D01*
X294750Y256733D01*
X294375Y256775D01*
X294042Y256900D01*
X293792Y257067D01*
X293583Y257317D01*
X293500Y257650D01*
X293583Y257983D01*
X293792Y258233D01*
X294042Y258400D01*
X294375Y258525D01*
X294750Y258567D01*
X295125Y258525D01*
X295458Y258400D01*
X295708Y258233D01*
X295917Y257983D01*
X296000Y257650D01*
G01X298292Y48767D02*
X298417Y48517D01*
X298500Y48225D01*
Y47892D01*
X298375Y47517D01*
X298167Y47225D01*
X297917Y47017D01*
X297500Y46850D01*
X297125Y46808D01*
X296750Y46892D01*
X296500Y47017D01*
X296250Y47267D01*
X296083Y47558D01*
X296000Y47850D01*
Y48142D01*
X296083Y48433D01*
X296208Y48683D01*
X296375Y48892D01*
G01X298083Y50158D02*
X298333Y50408D01*
X298458Y50700D01*
X298500Y51033D01*
X298417Y51450D01*
X298208Y51742D01*
X297958Y51825D01*
X297708Y51783D01*
X297500Y51617D01*
X297083Y50783D01*
X296792Y50408D01*
X296375Y50158D01*
X296000Y50075D01*
Y51825D01*
G01Y53967D02*
X296542Y54050D01*
X297000Y54175D01*
X297417Y54342D01*
X297875Y54550D01*
X298500Y54883D01*
Y53217D01*
G01X296000Y57067D02*
X296542Y57150D01*
X297000Y57275D01*
X297417Y57442D01*
X297875Y57650D01*
X298500Y57983D01*
Y56317D01*
G01X302292Y48767D02*
X302417Y48517D01*
X302500Y48225D01*
Y47892D01*
X302375Y47517D01*
X302167Y47225D01*
X301917Y47017D01*
X301500Y46850D01*
X301125Y46808D01*
X300750Y46892D01*
X300500Y47017D01*
X300250Y47267D01*
X300083Y47558D01*
X300000Y47850D01*
Y48142D01*
X300083Y48433D01*
X300208Y48683D01*
X300375Y48892D01*
G01X302083Y50158D02*
X302333Y50408D01*
X302458Y50700D01*
X302500Y51033D01*
X302417Y51450D01*
X302208Y51742D01*
X301958Y51825D01*
X301708Y51783D01*
X301500Y51617D01*
X301083Y50783D01*
X300792Y50408D01*
X300375Y50158D01*
X300000Y50075D01*
Y51825D01*
G01Y53967D02*
X300542Y54050D01*
X301000Y54175D01*
X301417Y54342D01*
X301875Y54550D01*
X302500Y54883D01*
Y53217D01*
G01X301042Y56358D02*
X301333Y56650D01*
X301500Y56900D01*
X301583Y57233D01*
X301500Y57525D01*
X301333Y57733D01*
X301083Y57900D01*
X300792Y57942D01*
X300542Y57900D01*
X300292Y57733D01*
X300083Y57483D01*
X300000Y57192D01*
X300083Y56858D01*
X300333Y56567D01*
X300708Y56400D01*
X301125Y56358D01*
X301667Y56442D01*
X301958Y56567D01*
X302250Y56775D01*
X302458Y57067D01*
X302500Y57358D01*
X302417Y57650D01*
X302208Y57858D01*
G01X313292Y46767D02*
X313417Y46517D01*
X313500Y46225D01*
Y45892D01*
X313375Y45517D01*
X313167Y45225D01*
X312917Y45017D01*
X312500Y44850D01*
X312125Y44808D01*
X311750Y44892D01*
X311500Y45017D01*
X311250Y45267D01*
X311083Y45558D01*
X311000Y45850D01*
Y46142D01*
X311083Y46433D01*
X311208Y46683D01*
X311375Y46892D01*
G01X313083Y48158D02*
X313333Y48408D01*
X313458Y48700D01*
X313500Y49033D01*
X313417Y49450D01*
X313208Y49742D01*
X312958Y49825D01*
X312708Y49783D01*
X312500Y49617D01*
X312083Y48783D01*
X311792Y48408D01*
X311375Y48158D01*
X311000Y48075D01*
Y49825D01*
G01Y51967D02*
X311542Y52050D01*
X312000Y52175D01*
X312417Y52342D01*
X312875Y52550D01*
X313500Y52883D01*
Y51217D01*
G01X311375Y54233D02*
X311167Y54483D01*
X311042Y54775D01*
X311000Y55150D01*
X311083Y55525D01*
X311250Y55817D01*
X311542Y56025D01*
X311875Y56067D01*
X312208Y55983D01*
X312417Y55775D01*
X312583Y55483D01*
X312625Y55192D01*
X312583Y54900D01*
X312417Y54525D01*
X313500Y54650D01*
Y55775D01*
G01X304433Y91000D02*
Y98000D01*
G01X299367D02*
X304433Y93683D01*
G01X298567Y91000D02*
X302167Y95667D01*
G01X310983Y111000D02*
Y113500D01*
X309942D01*
X309608Y113375D01*
X309400Y113208D01*
X309317Y112875D01*
X309400Y112542D01*
X309650Y112333D01*
X309942Y112208D01*
X310983D01*
G01X309942D02*
X309317Y111000D01*
G01X306550D02*
Y113500D01*
X308092Y111708D01*
X306008D01*
G01X304867Y111375D02*
X304617Y111167D01*
X304325Y111042D01*
X303950Y111000D01*
X303575Y111083D01*
X303283Y111250D01*
X303075Y111542D01*
X303033Y111875D01*
X303117Y112208D01*
X303325Y112417D01*
X303617Y112583D01*
X303908Y112625D01*
X304200Y112583D01*
X304575Y112417D01*
X304450Y113500D01*
X303325D01*
G01X301642Y112042D02*
X301350Y112333D01*
X301100Y112500D01*
X300767Y112583D01*
X300475Y112500D01*
X300267Y112333D01*
X300100Y112083D01*
X300058Y111792D01*
X300100Y111542D01*
X300267Y111292D01*
X300517Y111083D01*
X300808Y111000D01*
X301142Y111083D01*
X301433Y111333D01*
X301600Y111708D01*
X301642Y112125D01*
X301558Y112667D01*
X301433Y112958D01*
X301225Y113250D01*
X300933Y113458D01*
X300642Y113500D01*
X300350Y113417D01*
X300142Y113208D01*
G01X312483Y115000D02*
Y117500D01*
X311442D01*
X311108Y117375D01*
X310900Y117208D01*
X310817Y116875D01*
X310900Y116542D01*
X311150Y116333D01*
X311442Y116208D01*
X312483D01*
G01X311442D02*
X310817Y115000D01*
G01X308050D02*
Y117500D01*
X309592Y115708D01*
X307508D01*
G01X306367Y115375D02*
X306117Y115167D01*
X305825Y115042D01*
X305450Y115000D01*
X305075Y115083D01*
X304783Y115250D01*
X304575Y115542D01*
X304533Y115875D01*
X304617Y116208D01*
X304825Y116417D01*
X305117Y116583D01*
X305408Y116625D01*
X305700Y116583D01*
X306075Y116417D01*
X305950Y117500D01*
X304825D01*
G01X302433Y115000D02*
X302350Y115542D01*
X302225Y116000D01*
X302058Y116417D01*
X301850Y116875D01*
X301517Y117500D01*
X303183D01*
G01X313483Y107000D02*
Y109500D01*
X312442D01*
X312108Y109375D01*
X311900Y109208D01*
X311817Y108875D01*
X311900Y108542D01*
X312150Y108333D01*
X312442Y108208D01*
X313483D01*
G01X312442D02*
X311817Y107000D01*
G01X310467Y107500D02*
X310217Y107208D01*
X309883Y107042D01*
X309508Y107000D01*
X309175Y107042D01*
X308842Y107250D01*
X308633Y107500D01*
X308592Y107750D01*
X308675Y108042D01*
X308967Y108250D01*
X309258Y108333D01*
X309633D01*
G01X309258D02*
X309008Y108458D01*
X308800Y108667D01*
X308717Y108917D01*
X308800Y109167D01*
X309008Y109375D01*
X309383Y109500D01*
X309758Y109458D01*
X310133Y109292D01*
G01X307242Y108042D02*
X306950Y108333D01*
X306700Y108500D01*
X306367Y108583D01*
X306075Y108500D01*
X305867Y108333D01*
X305700Y108083D01*
X305658Y107792D01*
X305700Y107542D01*
X305867Y107292D01*
X306117Y107083D01*
X306408Y107000D01*
X306742Y107083D01*
X307033Y107333D01*
X307200Y107708D01*
X307242Y108125D01*
X307158Y108667D01*
X307033Y108958D01*
X306825Y109250D01*
X306533Y109458D01*
X306242Y109500D01*
X305950Y109417D01*
X305742Y109208D01*
G01X304142Y109083D02*
X303892Y109333D01*
X303600Y109458D01*
X303267Y109500D01*
X302850Y109417D01*
X302558Y109208D01*
X302475Y108958D01*
X302517Y108708D01*
X302683Y108500D01*
X303517Y108083D01*
X303892Y107792D01*
X304142Y107375D01*
X304225Y107000D01*
X302475D01*
G01X313983Y119000D02*
Y121500D01*
X312942D01*
X312608Y121375D01*
X312400Y121208D01*
X312317Y120875D01*
X312400Y120542D01*
X312650Y120333D01*
X312942Y120208D01*
X313983D01*
G01X312942D02*
X312317Y119000D01*
G01X310050D02*
Y121500D01*
X310550Y121000D01*
G01Y119000D02*
X309550D01*
G01X307742Y121083D02*
X307492Y121333D01*
X307200Y121458D01*
X306867Y121500D01*
X306450Y121417D01*
X306158Y121208D01*
X306075Y120958D01*
X306117Y120708D01*
X306283Y120500D01*
X307117Y120083D01*
X307492Y119792D01*
X307742Y119375D01*
X307825Y119000D01*
X306075D01*
G01X304642Y121083D02*
X304392Y121333D01*
X304100Y121458D01*
X303767Y121500D01*
X303350Y121417D01*
X303058Y121208D01*
X302975Y120958D01*
X303017Y120708D01*
X303183Y120500D01*
X304017Y120083D01*
X304392Y119792D01*
X304642Y119375D01*
X304725Y119000D01*
X302975D01*
G01X312983Y131000D02*
Y133500D01*
X311942D01*
X311608Y133375D01*
X311400Y133208D01*
X311317Y132875D01*
X311400Y132542D01*
X311650Y132333D01*
X311942Y132208D01*
X312983D01*
G01X311942D02*
X311317Y131000D01*
G01X309967Y131500D02*
X309717Y131208D01*
X309383Y131042D01*
X309008Y131000D01*
X308675Y131042D01*
X308342Y131250D01*
X308133Y131500D01*
X308092Y131750D01*
X308175Y132042D01*
X308467Y132250D01*
X308758Y132333D01*
X309133D01*
G01X308758D02*
X308508Y132458D01*
X308300Y132667D01*
X308217Y132917D01*
X308300Y133167D01*
X308508Y133375D01*
X308883Y133500D01*
X309258Y133458D01*
X309633Y133292D01*
G01X306742Y132042D02*
X306450Y132333D01*
X306200Y132500D01*
X305867Y132583D01*
X305575Y132500D01*
X305367Y132333D01*
X305200Y132083D01*
X305158Y131792D01*
X305200Y131542D01*
X305367Y131292D01*
X305617Y131083D01*
X305908Y131000D01*
X306242Y131083D01*
X306533Y131333D01*
X306700Y131708D01*
X306742Y132125D01*
X306658Y132667D01*
X306533Y132958D01*
X306325Y133250D01*
X306033Y133458D01*
X305742Y133500D01*
X305450Y133417D01*
X305242Y133208D01*
G01X302933Y131000D02*
X302850Y131542D01*
X302725Y132000D01*
X302558Y132417D01*
X302350Y132875D01*
X302017Y133500D01*
X303683D01*
G01X316483Y123000D02*
Y125500D01*
X315442D01*
X315108Y125375D01*
X314900Y125208D01*
X314817Y124875D01*
X314900Y124542D01*
X315150Y124333D01*
X315442Y124208D01*
X316483D01*
G01X315442D02*
X314817Y123000D01*
G01X312550D02*
Y125500D01*
X313050Y125000D01*
G01Y123000D02*
X312050D01*
G01X310242Y125083D02*
X309992Y125333D01*
X309700Y125458D01*
X309367Y125500D01*
X308950Y125417D01*
X308658Y125208D01*
X308575Y124958D01*
X308617Y124708D01*
X308783Y124500D01*
X309617Y124083D01*
X309992Y123792D01*
X310242Y123375D01*
X310325Y123000D01*
X308575D01*
G01X306350D02*
Y125500D01*
X306850Y125000D01*
G01Y123000D02*
X305850D01*
G01X311983Y127000D02*
Y129500D01*
X310942D01*
X310608Y129375D01*
X310400Y129208D01*
X310317Y128875D01*
X310400Y128542D01*
X310650Y128333D01*
X310942Y128208D01*
X311983D01*
G01X310942D02*
X310317Y127000D01*
G01X308050D02*
Y129500D01*
X308550Y129000D01*
G01Y127000D02*
X307550D01*
G01X304950D02*
Y129500D01*
X305450Y129000D01*
G01Y127000D02*
X304450D01*
G01X302558Y127292D02*
X302267Y127083D01*
X301933Y127000D01*
X301600Y127083D01*
X301308Y127333D01*
X301100Y127708D01*
X301017Y128083D01*
Y128542D01*
X301100Y128917D01*
X301308Y129250D01*
X301558Y129417D01*
X301850Y129500D01*
X302183Y129417D01*
X302433Y129250D01*
X302600Y129000D01*
X302683Y128667D01*
X302600Y128375D01*
X302392Y128083D01*
X302142Y127917D01*
X301850Y127875D01*
X301517Y127958D01*
X301267Y128167D01*
X301017Y128542D01*
G01X313483Y135500D02*
Y138000D01*
X312442D01*
X312108Y137875D01*
X311900Y137708D01*
X311817Y137375D01*
X311900Y137042D01*
X312150Y136833D01*
X312442Y136708D01*
X313483D01*
G01X312442D02*
X311817Y135500D01*
G01X309550D02*
Y138000D01*
X310050Y137500D01*
G01Y135500D02*
X309050D01*
G01X306450Y138000D02*
X306783Y137917D01*
X307033Y137708D01*
X307200Y137458D01*
X307325Y137125D01*
X307367Y136750D01*
X307325Y136375D01*
X307200Y136042D01*
X307033Y135792D01*
X306783Y135583D01*
X306450Y135500D01*
X306117Y135583D01*
X305867Y135792D01*
X305700Y136042D01*
X305575Y136375D01*
X305533Y136750D01*
X305575Y137125D01*
X305700Y137458D01*
X305867Y137708D01*
X306117Y137917D01*
X306450Y138000D01*
G01X303350Y135500D02*
X303058Y135542D01*
X302725Y135667D01*
X302517Y135875D01*
X302433Y136167D01*
X302517Y136458D01*
X302767Y136708D01*
X303142Y136833D01*
X303558D01*
X303808Y136917D01*
X304017Y137125D01*
X304100Y137417D01*
X303975Y137708D01*
X303683Y137917D01*
X303350Y138000D01*
X303017Y137917D01*
X302725Y137708D01*
X302600Y137417D01*
X302683Y137125D01*
X302892Y136917D01*
X303142Y136833D01*
X303558D01*
X303933Y136708D01*
X304183Y136458D01*
X304267Y136167D01*
X304183Y135875D01*
X303975Y135667D01*
X303642Y135542D01*
X303350Y135500D01*
G01X300000Y144000D02*
X302000D01*
X304500Y141500D01*
X313000D01*
G01X311800Y153500D02*
Y160500D01*
G01X306200D02*
Y153500D01*
G01Y157000D02*
X311800D01*
G01X303000Y160000D02*
X297000D01*
Y164500D01*
G01X312483Y165500D02*
Y168000D01*
X311442D01*
X311108Y167875D01*
X310900Y167708D01*
X310817Y167375D01*
X310900Y167042D01*
X311150Y166833D01*
X311442Y166708D01*
X312483D01*
G01X311442D02*
X310817Y165500D01*
G01X309467Y166000D02*
X309217Y165708D01*
X308883Y165542D01*
X308508Y165500D01*
X308175Y165542D01*
X307842Y165750D01*
X307633Y166000D01*
X307592Y166250D01*
X307675Y166542D01*
X307967Y166750D01*
X308258Y166833D01*
X308633D01*
G01X308258D02*
X308008Y166958D01*
X307800Y167167D01*
X307717Y167417D01*
X307800Y167667D01*
X308008Y167875D01*
X308383Y168000D01*
X308758Y167958D01*
X309133Y167792D01*
G01X305450Y168000D02*
X305783Y167917D01*
X306033Y167708D01*
X306200Y167458D01*
X306325Y167125D01*
X306367Y166750D01*
X306325Y166375D01*
X306200Y166042D01*
X306033Y165792D01*
X305783Y165583D01*
X305450Y165500D01*
X305117Y165583D01*
X304867Y165792D01*
X304700Y166042D01*
X304575Y166375D01*
X304533Y166750D01*
X304575Y167125D01*
X304700Y167458D01*
X304867Y167708D01*
X305117Y167917D01*
X305450Y168000D01*
G01X302350Y165500D02*
X302058Y165542D01*
X301725Y165667D01*
X301517Y165875D01*
X301433Y166167D01*
X301517Y166458D01*
X301767Y166708D01*
X302142Y166833D01*
X302558D01*
X302808Y166917D01*
X303017Y167125D01*
X303100Y167417D01*
X302975Y167708D01*
X302683Y167917D01*
X302350Y168000D01*
X302017Y167917D01*
X301725Y167708D01*
X301600Y167417D01*
X301683Y167125D01*
X301892Y166917D01*
X302142Y166833D01*
X302558D01*
X302933Y166708D01*
X303183Y166458D01*
X303267Y166167D01*
X303183Y165875D01*
X302975Y165667D01*
X302642Y165542D01*
X302350Y165500D01*
G01X309483Y177000D02*
Y179500D01*
X308442D01*
X308108Y179375D01*
X307900Y179208D01*
X307817Y178875D01*
X307900Y178542D01*
X308150Y178333D01*
X308442Y178208D01*
X309483D01*
G01X308442D02*
X307817Y177000D01*
G01X306467Y177500D02*
X306217Y177208D01*
X305883Y177042D01*
X305508Y177000D01*
X305175Y177042D01*
X304842Y177250D01*
X304633Y177500D01*
X304592Y177750D01*
X304675Y178042D01*
X304967Y178250D01*
X305258Y178333D01*
X305633D01*
G01X305258D02*
X305008Y178458D01*
X304800Y178667D01*
X304717Y178917D01*
X304800Y179167D01*
X305008Y179375D01*
X305383Y179500D01*
X305758Y179458D01*
X306133Y179292D01*
G01X302450Y177000D02*
Y179500D01*
X302950Y179000D01*
G01Y177000D02*
X301950D01*
G01X298850D02*
Y179500D01*
X300392Y177708D01*
X298308D01*
G01X308933Y182000D02*
Y184500D01*
X307892D01*
X307558Y184375D01*
X307350Y184208D01*
X307267Y183875D01*
X307350Y183542D01*
X307600Y183333D01*
X307892Y183208D01*
X308933D01*
G01X307892D02*
X307267Y182000D01*
G01X305083D02*
X305000Y182542D01*
X304875Y183000D01*
X304708Y183417D01*
X304500Y183875D01*
X304167Y184500D01*
X305833D01*
G01X301900D02*
X302233Y184417D01*
X302483Y184208D01*
X302650Y183958D01*
X302775Y183625D01*
X302817Y183250D01*
X302775Y182875D01*
X302650Y182542D01*
X302483Y182292D01*
X302233Y182083D01*
X301900Y182000D01*
X301567Y182083D01*
X301317Y182292D01*
X301150Y182542D01*
X301025Y182875D01*
X300983Y183250D01*
X301025Y183625D01*
X301150Y183958D01*
X301317Y184208D01*
X301567Y184417D01*
X301900Y184500D01*
G01X314433Y169500D02*
Y172000D01*
X313392D01*
X313058Y171875D01*
X312850Y171708D01*
X312767Y171375D01*
X312850Y171042D01*
X313100Y170833D01*
X313392Y170708D01*
X314433D01*
G01X313392D02*
X312767Y169500D01*
G01X311292Y170542D02*
X311000Y170833D01*
X310750Y171000D01*
X310417Y171083D01*
X310125Y171000D01*
X309917Y170833D01*
X309750Y170583D01*
X309708Y170292D01*
X309750Y170042D01*
X309917Y169792D01*
X310167Y169583D01*
X310458Y169500D01*
X310792Y169583D01*
X311083Y169833D01*
X311250Y170208D01*
X311292Y170625D01*
X311208Y171167D01*
X311083Y171458D01*
X310875Y171750D01*
X310583Y171958D01*
X310292Y172000D01*
X310000Y171917D01*
X309792Y171708D01*
G01X307400Y169500D02*
X307108Y169542D01*
X306775Y169667D01*
X306567Y169875D01*
X306483Y170167D01*
X306567Y170458D01*
X306817Y170708D01*
X307192Y170833D01*
X307608D01*
X307858Y170917D01*
X308067Y171125D01*
X308150Y171417D01*
X308025Y171708D01*
X307733Y171917D01*
X307400Y172000D01*
X307067Y171917D01*
X306775Y171708D01*
X306650Y171417D01*
X306733Y171125D01*
X306942Y170917D01*
X307192Y170833D01*
X307608D01*
X307983Y170708D01*
X308233Y170458D01*
X308317Y170167D01*
X308233Y169875D01*
X308025Y169667D01*
X307692Y169542D01*
X307400Y169500D01*
G01X301000Y194017D02*
X303500D01*
Y195058D01*
X303375Y195392D01*
X303208Y195600D01*
X302875Y195683D01*
X302542Y195600D01*
X302333Y195350D01*
X302208Y195058D01*
Y194017D01*
G01Y195058D02*
X301000Y195683D01*
G01X303083Y197158D02*
X303333Y197408D01*
X303458Y197700D01*
X303500Y198033D01*
X303417Y198450D01*
X303208Y198742D01*
X302958Y198825D01*
X302708Y198783D01*
X302500Y198617D01*
X302083Y197783D01*
X301792Y197408D01*
X301375Y197158D01*
X301000Y197075D01*
Y198825D01*
G01X302042Y200258D02*
X302333Y200550D01*
X302500Y200800D01*
X302583Y201133D01*
X302500Y201425D01*
X302333Y201633D01*
X302083Y201800D01*
X301792Y201842D01*
X301542Y201800D01*
X301292Y201633D01*
X301083Y201383D01*
X301000Y201092D01*
X301083Y200758D01*
X301333Y200467D01*
X301708Y200300D01*
X302125Y200258D01*
X302667Y200342D01*
X302958Y200467D01*
X303250Y200675D01*
X303458Y200967D01*
X303500Y201258D01*
X303417Y201550D01*
X303208Y201758D01*
G01X301500Y203233D02*
X301208Y203483D01*
X301042Y203817D01*
X301000Y204192D01*
X301042Y204525D01*
X301250Y204858D01*
X301500Y205067D01*
X301750Y205108D01*
X302042Y205025D01*
X302250Y204733D01*
X302333Y204442D01*
Y204067D01*
G01Y204442D02*
X302458Y204692D01*
X302667Y204900D01*
X302917Y204983D01*
X303167Y204900D01*
X303375Y204692D01*
X303500Y204317D01*
X303458Y203942D01*
X303292Y203567D01*
G01X308983Y186000D02*
Y188500D01*
X307942D01*
X307608Y188375D01*
X307400Y188208D01*
X307317Y187875D01*
X307400Y187542D01*
X307650Y187333D01*
X307942Y187208D01*
X308983D01*
G01X307942D02*
X307317Y186000D01*
G01X305842Y188083D02*
X305592Y188333D01*
X305300Y188458D01*
X304967Y188500D01*
X304550Y188417D01*
X304258Y188208D01*
X304175Y187958D01*
X304217Y187708D01*
X304383Y187500D01*
X305217Y187083D01*
X305592Y186792D01*
X305842Y186375D01*
X305925Y186000D01*
X304175D01*
G01X302658Y186292D02*
X302367Y186083D01*
X302033Y186000D01*
X301700Y186083D01*
X301408Y186333D01*
X301200Y186708D01*
X301117Y187083D01*
Y187542D01*
X301200Y187917D01*
X301408Y188250D01*
X301658Y188417D01*
X301950Y188500D01*
X302283Y188417D01*
X302533Y188250D01*
X302700Y188000D01*
X302783Y187667D01*
X302700Y187375D01*
X302492Y187083D01*
X302242Y186917D01*
X301950Y186875D01*
X301617Y186958D01*
X301367Y187167D01*
X301117Y187542D01*
G01X299642Y188083D02*
X299392Y188333D01*
X299100Y188458D01*
X298767Y188500D01*
X298350Y188417D01*
X298058Y188208D01*
X297975Y187958D01*
X298017Y187708D01*
X298183Y187500D01*
X299017Y187083D01*
X299392Y186792D01*
X299642Y186375D01*
X299725Y186000D01*
X297975D01*
G01X301000Y207900D02*
X301042Y207567D01*
X301208Y207275D01*
X301458Y207025D01*
X301750Y206858D01*
X302083Y206775D01*
X302417D01*
X302750Y206858D01*
X303042Y207025D01*
X303292Y207275D01*
X303458Y207567D01*
X303500Y207900D01*
X303458Y208233D01*
X303292Y208525D01*
X303042Y208775D01*
X302750Y208942D01*
X302417Y209025D01*
X302083D01*
X301750Y208942D01*
X301458Y208775D01*
X301208Y208525D01*
X301042Y208233D01*
X301000Y207900D01*
G01X301667Y208233D02*
X301000Y208733D01*
G01Y211000D02*
X303500D01*
X303000Y210500D01*
G01X301000D02*
Y211500D01*
G01Y214100D02*
X303500D01*
X303000Y213600D01*
G01X301000D02*
Y214600D01*
G01X317983Y209000D02*
Y211500D01*
X316942D01*
X316608Y211375D01*
X316400Y211208D01*
X316317Y210875D01*
X316400Y210542D01*
X316650Y210333D01*
X316942Y210208D01*
X317983D01*
G01X316942D02*
X316317Y209000D01*
G01X314967Y209500D02*
X314717Y209208D01*
X314383Y209042D01*
X314008Y209000D01*
X313675Y209042D01*
X313342Y209250D01*
X313133Y209500D01*
X313092Y209750D01*
X313175Y210042D01*
X313467Y210250D01*
X313758Y210333D01*
X314133D01*
G01X313758D02*
X313508Y210458D01*
X313300Y210667D01*
X313217Y210917D01*
X313300Y211167D01*
X313508Y211375D01*
X313883Y211500D01*
X314258Y211458D01*
X314633Y211292D01*
G01X310950Y209000D02*
Y211500D01*
X311450Y211000D01*
G01Y209000D02*
X310450D01*
G01X307850Y211500D02*
X308183Y211417D01*
X308433Y211208D01*
X308600Y210958D01*
X308725Y210625D01*
X308767Y210250D01*
X308725Y209875D01*
X308600Y209542D01*
X308433Y209292D01*
X308183Y209083D01*
X307850Y209000D01*
X307517Y209083D01*
X307267Y209292D01*
X307100Y209542D01*
X306975Y209875D01*
X306933Y210250D01*
X306975Y210625D01*
X307100Y210958D01*
X307267Y211208D01*
X307517Y211417D01*
X307850Y211500D01*
G01X317983Y205000D02*
Y207500D01*
X316942D01*
X316608Y207375D01*
X316400Y207208D01*
X316317Y206875D01*
X316400Y206542D01*
X316650Y206333D01*
X316942Y206208D01*
X317983D01*
G01X316942D02*
X316317Y205000D01*
G01X314967Y205500D02*
X314717Y205208D01*
X314383Y205042D01*
X314008Y205000D01*
X313675Y205042D01*
X313342Y205250D01*
X313133Y205500D01*
X313092Y205750D01*
X313175Y206042D01*
X313467Y206250D01*
X313758Y206333D01*
X314133D01*
G01X313758D02*
X313508Y206458D01*
X313300Y206667D01*
X313217Y206917D01*
X313300Y207167D01*
X313508Y207375D01*
X313883Y207500D01*
X314258Y207458D01*
X314633Y207292D01*
G01X310950Y205000D02*
Y207500D01*
X311450Y207000D01*
G01Y205000D02*
X310450D01*
G01X308767Y205500D02*
X308517Y205208D01*
X308183Y205042D01*
X307808Y205000D01*
X307475Y205042D01*
X307142Y205250D01*
X306933Y205500D01*
X306892Y205750D01*
X306975Y206042D01*
X307267Y206250D01*
X307558Y206333D01*
X307933D01*
G01X307558D02*
X307308Y206458D01*
X307100Y206667D01*
X307017Y206917D01*
X307100Y207167D01*
X307308Y207375D01*
X307683Y207500D01*
X308058Y207458D01*
X308433Y207292D01*
G01X317933Y213000D02*
Y215500D01*
X316892D01*
X316558Y215375D01*
X316350Y215208D01*
X316267Y214875D01*
X316350Y214542D01*
X316600Y214333D01*
X316892Y214208D01*
X317933D01*
G01X316892D02*
X316267Y213000D01*
G01X314917Y213500D02*
X314667Y213208D01*
X314333Y213042D01*
X313958Y213000D01*
X313625Y213042D01*
X313292Y213250D01*
X313083Y213500D01*
X313042Y213750D01*
X313125Y214042D01*
X313417Y214250D01*
X313708Y214333D01*
X314083D01*
G01X313708D02*
X313458Y214458D01*
X313250Y214667D01*
X313167Y214917D01*
X313250Y215167D01*
X313458Y215375D01*
X313833Y215500D01*
X314208Y215458D01*
X314583Y215292D01*
G01X310900Y213000D02*
X310608Y213042D01*
X310275Y213167D01*
X310067Y213375D01*
X309983Y213667D01*
X310067Y213958D01*
X310317Y214208D01*
X310692Y214333D01*
X311108D01*
X311358Y214417D01*
X311567Y214625D01*
X311650Y214917D01*
X311525Y215208D01*
X311233Y215417D01*
X310900Y215500D01*
X310567Y215417D01*
X310275Y215208D01*
X310150Y214917D01*
X310233Y214625D01*
X310442Y214417D01*
X310692Y214333D01*
X311108D01*
X311483Y214208D01*
X311733Y213958D01*
X311817Y213667D01*
X311733Y213375D01*
X311525Y213167D01*
X311192Y213042D01*
X310900Y213000D01*
G01X317983Y217000D02*
Y219500D01*
X316942D01*
X316608Y219375D01*
X316400Y219208D01*
X316317Y218875D01*
X316400Y218542D01*
X316650Y218333D01*
X316942Y218208D01*
X317983D01*
G01X316942D02*
X316317Y217000D01*
G01X314842Y219083D02*
X314592Y219333D01*
X314300Y219458D01*
X313967Y219500D01*
X313550Y219417D01*
X313258Y219208D01*
X313175Y218958D01*
X313217Y218708D01*
X313383Y218500D01*
X314217Y218083D01*
X314592Y217792D01*
X314842Y217375D01*
X314925Y217000D01*
X313175D01*
G01X311742Y218042D02*
X311450Y218333D01*
X311200Y218500D01*
X310867Y218583D01*
X310575Y218500D01*
X310367Y218333D01*
X310200Y218083D01*
X310158Y217792D01*
X310200Y217542D01*
X310367Y217292D01*
X310617Y217083D01*
X310908Y217000D01*
X311242Y217083D01*
X311533Y217333D01*
X311700Y217708D01*
X311742Y218125D01*
X311658Y218667D01*
X311533Y218958D01*
X311325Y219250D01*
X311033Y219458D01*
X310742Y219500D01*
X310450Y219417D01*
X310242Y219208D01*
G01X307850Y219500D02*
X308183Y219417D01*
X308433Y219208D01*
X308600Y218958D01*
X308725Y218625D01*
X308767Y218250D01*
X308725Y217875D01*
X308600Y217542D01*
X308433Y217292D01*
X308183Y217083D01*
X307850Y217000D01*
X307517Y217083D01*
X307267Y217292D01*
X307100Y217542D01*
X306975Y217875D01*
X306933Y218250D01*
X306975Y218625D01*
X307100Y218958D01*
X307267Y219208D01*
X307517Y219417D01*
X307850Y219500D01*
G01X308000Y233017D02*
X310500D01*
Y234058D01*
X310375Y234392D01*
X310208Y234600D01*
X309875Y234683D01*
X309542Y234600D01*
X309333Y234350D01*
X309208Y234058D01*
Y233017D01*
G01Y234058D02*
X308000Y234683D01*
G01X310083Y236158D02*
X310333Y236408D01*
X310458Y236700D01*
X310500Y237033D01*
X310417Y237450D01*
X310208Y237742D01*
X309958Y237825D01*
X309708Y237783D01*
X309500Y237617D01*
X309083Y236783D01*
X308792Y236408D01*
X308375Y236158D01*
X308000Y236075D01*
Y237825D01*
G01X308292Y239342D02*
X308083Y239633D01*
X308000Y239967D01*
X308083Y240300D01*
X308333Y240592D01*
X308708Y240800D01*
X309083Y240883D01*
X309542D01*
X309917Y240800D01*
X310250Y240592D01*
X310417Y240342D01*
X310500Y240050D01*
X310417Y239717D01*
X310250Y239467D01*
X310000Y239300D01*
X309667Y239217D01*
X309375Y239300D01*
X309083Y239508D01*
X308917Y239758D01*
X308875Y240050D01*
X308958Y240383D01*
X309167Y240633D01*
X309542Y240883D01*
G01X308000Y243150D02*
X310500D01*
X310000Y242650D01*
G01X308000D02*
Y243650D01*
G01X299792Y252317D02*
X299917Y252067D01*
X300000Y251775D01*
Y251442D01*
X299875Y251067D01*
X299667Y250775D01*
X299417Y250567D01*
X299000Y250400D01*
X298625Y250358D01*
X298250Y250442D01*
X298000Y250567D01*
X297750Y250817D01*
X297583Y251108D01*
X297500Y251400D01*
Y251692D01*
X297583Y251983D01*
X297708Y252233D01*
X297875Y252442D01*
G01X297500Y254500D02*
X297542Y254792D01*
X297667Y255125D01*
X297875Y255333D01*
X298167Y255417D01*
X298458Y255333D01*
X298708Y255083D01*
X298833Y254708D01*
Y254292D01*
X298917Y254042D01*
X299125Y253833D01*
X299417Y253750D01*
X299708Y253875D01*
X299917Y254167D01*
X300000Y254500D01*
X299917Y254833D01*
X299708Y255125D01*
X299417Y255250D01*
X299125Y255167D01*
X298917Y254958D01*
X298833Y254708D01*
Y254292D01*
X298708Y253917D01*
X298458Y253667D01*
X298167Y253583D01*
X297875Y253667D01*
X297667Y253875D01*
X297542Y254208D01*
X297500Y254500D01*
G01X298542Y256808D02*
X298833Y257100D01*
X299000Y257350D01*
X299083Y257683D01*
X299000Y257975D01*
X298833Y258183D01*
X298583Y258350D01*
X298292Y258392D01*
X298042Y258350D01*
X297792Y258183D01*
X297583Y257933D01*
X297500Y257642D01*
X297583Y257308D01*
X297833Y257017D01*
X298208Y256850D01*
X298625Y256808D01*
X299167Y256892D01*
X299458Y257017D01*
X299750Y257225D01*
X299958Y257517D01*
X300000Y257808D01*
X299917Y258100D01*
X299708Y258308D01*
G01X304792Y252317D02*
X304917Y252067D01*
X305000Y251775D01*
Y251442D01*
X304875Y251067D01*
X304667Y250775D01*
X304417Y250567D01*
X304000Y250400D01*
X303625Y250358D01*
X303250Y250442D01*
X303000Y250567D01*
X302750Y250817D01*
X302583Y251108D01*
X302500Y251400D01*
Y251692D01*
X302583Y251983D01*
X302708Y252233D01*
X302875Y252442D01*
G01X302500Y254500D02*
X302542Y254792D01*
X302667Y255125D01*
X302875Y255333D01*
X303167Y255417D01*
X303458Y255333D01*
X303708Y255083D01*
X303833Y254708D01*
Y254292D01*
X303917Y254042D01*
X304125Y253833D01*
X304417Y253750D01*
X304708Y253875D01*
X304917Y254167D01*
X305000Y254500D01*
X304917Y254833D01*
X304708Y255125D01*
X304417Y255250D01*
X304125Y255167D01*
X303917Y254958D01*
X303833Y254708D01*
Y254292D01*
X303708Y253917D01*
X303458Y253667D01*
X303167Y253583D01*
X302875Y253667D01*
X302667Y253875D01*
X302542Y254208D01*
X302500Y254500D01*
G01X302875Y256683D02*
X302667Y256933D01*
X302542Y257225D01*
X302500Y257600D01*
X302583Y257975D01*
X302750Y258267D01*
X303042Y258475D01*
X303375Y258517D01*
X303708Y258433D01*
X303917Y258225D01*
X304083Y257933D01*
X304125Y257642D01*
X304083Y257350D01*
X303917Y256975D01*
X305000Y257100D01*
Y258225D01*
G01X323292Y43267D02*
X323417Y43017D01*
X323500Y42725D01*
Y42392D01*
X323375Y42017D01*
X323167Y41725D01*
X322917Y41517D01*
X322500Y41350D01*
X322125Y41308D01*
X321750Y41392D01*
X321500Y41517D01*
X321250Y41767D01*
X321083Y42058D01*
X321000Y42350D01*
Y42642D01*
X321083Y42933D01*
X321208Y43183D01*
X321375Y43392D01*
G01X323083Y44658D02*
X323333Y44908D01*
X323458Y45200D01*
X323500Y45533D01*
X323417Y45950D01*
X323208Y46242D01*
X322958Y46325D01*
X322708Y46283D01*
X322500Y46117D01*
X322083Y45283D01*
X321792Y44908D01*
X321375Y44658D01*
X321000Y44575D01*
Y46325D01*
G01Y48467D02*
X321542Y48550D01*
X322000Y48675D01*
X322417Y48842D01*
X322875Y49050D01*
X323500Y49383D01*
Y47717D01*
G01X321000Y52150D02*
X323500D01*
X321708Y50608D01*
Y52692D01*
G01X325500Y41517D02*
X328000D01*
Y42517D01*
X327875Y42850D01*
X327583Y43100D01*
X327250Y43183D01*
X326917Y43100D01*
X326667Y42892D01*
X326542Y42517D01*
Y41517D01*
G01X328000Y44533D02*
X326208D01*
X325833Y44700D01*
X325583Y45033D01*
X325500Y45450D01*
X325583Y45867D01*
X325833Y46200D01*
X326208Y46367D01*
X328000D01*
G01X325500Y48550D02*
X328000D01*
X327500Y48050D01*
G01X325500D02*
Y49050D01*
G01X326542Y50858D02*
X326833Y51150D01*
X327000Y51400D01*
X327083Y51733D01*
X327000Y52025D01*
X326833Y52233D01*
X326583Y52400D01*
X326292Y52442D01*
X326042Y52400D01*
X325792Y52233D01*
X325583Y51983D01*
X325500Y51692D01*
X325583Y51358D01*
X325833Y51067D01*
X326208Y50900D01*
X326625Y50858D01*
X327167Y50942D01*
X327458Y51067D01*
X327750Y51275D01*
X327958Y51567D01*
X328000Y51858D01*
X327917Y52150D01*
X327708Y52358D01*
G01X311500Y82500D02*
Y71000D01*
G01X319500Y86500D02*
Y84000D01*
G01X335033Y87500D02*
Y90000D01*
X334033D01*
X333700Y89875D01*
X333450Y89583D01*
X333367Y89250D01*
X333450Y88917D01*
X333658Y88667D01*
X334033Y88542D01*
X335033D01*
G01X330183Y89792D02*
X330433Y89917D01*
X330725Y90000D01*
X331058D01*
X331433Y89875D01*
X331725Y89667D01*
X331933Y89417D01*
X332100Y89000D01*
X332142Y88625D01*
X332058Y88250D01*
X331933Y88000D01*
X331683Y87750D01*
X331392Y87583D01*
X331100Y87500D01*
X330808D01*
X330517Y87583D01*
X330267Y87708D01*
X330058Y87875D01*
G01X328000Y87500D02*
Y90000D01*
X328500Y89500D01*
G01Y87500D02*
X327500D01*
G01X325608Y87792D02*
X325317Y87583D01*
X324983Y87500D01*
X324650Y87583D01*
X324358Y87833D01*
X324150Y88208D01*
X324067Y88583D01*
Y89042D01*
X324150Y89417D01*
X324358Y89750D01*
X324608Y89917D01*
X324900Y90000D01*
X325233Y89917D01*
X325483Y89750D01*
X325650Y89500D01*
X325733Y89167D01*
X325650Y88875D01*
X325442Y88583D01*
X325192Y88417D01*
X324900Y88375D01*
X324567Y88458D01*
X324317Y88667D01*
X324067Y89042D01*
G01X321300Y87500D02*
Y90000D01*
X322842Y88208D01*
X320758D01*
G01X345000Y98500D02*
X329500D01*
Y91500D01*
X320000D01*
Y90500D01*
G01X311000Y106000D02*
X315000D01*
Y112000D01*
X325500D01*
G01X329150Y122000D02*
Y119500D01*
G01X330108Y122000D02*
X328192D01*
G01X326883Y119500D02*
Y122000D01*
X325883D01*
X325550Y121875D01*
X325300Y121583D01*
X325217Y121250D01*
X325300Y120917D01*
X325508Y120667D01*
X325883Y120542D01*
X326883D01*
G01X322450Y119500D02*
Y122000D01*
X323992Y120208D01*
X321908D01*
G01X320558Y119792D02*
X320267Y119583D01*
X319933Y119500D01*
X319600Y119583D01*
X319308Y119833D01*
X319100Y120208D01*
X319017Y120583D01*
Y121042D01*
X319100Y121417D01*
X319308Y121750D01*
X319558Y121917D01*
X319850Y122000D01*
X320183Y121917D01*
X320433Y121750D01*
X320600Y121500D01*
X320683Y121167D01*
X320600Y120875D01*
X320392Y120583D01*
X320142Y120417D01*
X319850Y120375D01*
X319517Y120458D01*
X319267Y120667D01*
X319017Y121042D01*
G01X323500Y131350D02*
X321000D01*
G01X323500Y130392D02*
Y132308D01*
G01X321000Y133617D02*
X323500D01*
Y134617D01*
X323375Y134950D01*
X323083Y135200D01*
X322750Y135283D01*
X322417Y135200D01*
X322167Y134992D01*
X322042Y134617D01*
Y133617D01*
G01X321000Y138050D02*
X323500D01*
X321708Y136508D01*
Y138592D01*
G01X322042Y139858D02*
X322333Y140150D01*
X322500Y140400D01*
X322583Y140733D01*
X322500Y141025D01*
X322333Y141233D01*
X322083Y141400D01*
X321792Y141442D01*
X321542Y141400D01*
X321292Y141233D01*
X321083Y140983D01*
X321000Y140692D01*
X321083Y140358D01*
X321333Y140067D01*
X321708Y139900D01*
X322125Y139858D01*
X322667Y139942D01*
X322958Y140067D01*
X323250Y140275D01*
X323458Y140567D01*
X323500Y140858D01*
X323417Y141150D01*
X323208Y141358D01*
G01X325000Y125517D02*
X327500D01*
Y126558D01*
X327375Y126892D01*
X327208Y127100D01*
X326875Y127183D01*
X326542Y127100D01*
X326333Y126850D01*
X326208Y126558D01*
Y125517D01*
G01Y126558D02*
X325000Y127183D01*
G01X325500Y128533D02*
X325208Y128783D01*
X325042Y129117D01*
X325000Y129492D01*
X325042Y129825D01*
X325250Y130158D01*
X325500Y130367D01*
X325750Y130408D01*
X326042Y130325D01*
X326250Y130033D01*
X326333Y129742D01*
Y129367D01*
G01Y129742D02*
X326458Y129992D01*
X326667Y130200D01*
X326917Y130283D01*
X327167Y130200D01*
X327375Y129992D01*
X327500Y129617D01*
X327458Y129242D01*
X327292Y128867D01*
G01X326042Y131758D02*
X326333Y132050D01*
X326500Y132300D01*
X326583Y132633D01*
X326500Y132925D01*
X326333Y133133D01*
X326083Y133300D01*
X325792Y133342D01*
X325542Y133300D01*
X325292Y133133D01*
X325083Y132883D01*
X325000Y132592D01*
X325083Y132258D01*
X325333Y131967D01*
X325708Y131800D01*
X326125Y131758D01*
X326667Y131842D01*
X326958Y131967D01*
X327250Y132175D01*
X327458Y132467D01*
X327500Y132758D01*
X327417Y133050D01*
X327208Y133258D01*
G01X325375Y134733D02*
X325167Y134983D01*
X325042Y135275D01*
X325000Y135650D01*
X325083Y136025D01*
X325250Y136317D01*
X325542Y136525D01*
X325875Y136567D01*
X326208Y136483D01*
X326417Y136275D01*
X326583Y135983D01*
X326625Y135692D01*
X326583Y135400D01*
X326417Y135025D01*
X327500Y135150D01*
Y136275D01*
G01X331983Y151500D02*
Y154000D01*
X330942D01*
X330608Y153875D01*
X330400Y153708D01*
X330317Y153375D01*
X330400Y153042D01*
X330650Y152833D01*
X330942Y152708D01*
X331983D01*
G01X330942D02*
X330317Y151500D01*
G01X328967Y152000D02*
X328717Y151708D01*
X328383Y151542D01*
X328008Y151500D01*
X327675Y151542D01*
X327342Y151750D01*
X327133Y152000D01*
X327092Y152250D01*
X327175Y152542D01*
X327467Y152750D01*
X327758Y152833D01*
X328133D01*
G01X327758D02*
X327508Y152958D01*
X327300Y153167D01*
X327217Y153417D01*
X327300Y153667D01*
X327508Y153875D01*
X327883Y154000D01*
X328258Y153958D01*
X328633Y153792D01*
G01X325867Y152000D02*
X325617Y151708D01*
X325283Y151542D01*
X324908Y151500D01*
X324575Y151542D01*
X324242Y151750D01*
X324033Y152000D01*
X323992Y152250D01*
X324075Y152542D01*
X324367Y152750D01*
X324658Y152833D01*
X325033D01*
G01X324658D02*
X324408Y152958D01*
X324200Y153167D01*
X324117Y153417D01*
X324200Y153667D01*
X324408Y153875D01*
X324783Y154000D01*
X325158Y153958D01*
X325533Y153792D01*
G01X321850Y151500D02*
Y154000D01*
X322350Y153500D01*
G01Y151500D02*
X321350D01*
G01X319000Y149000D02*
X320000D01*
Y160500D01*
X314000D01*
G01X324000Y156850D02*
X321500D01*
G01X324000Y155892D02*
Y157808D01*
G01X321500Y159117D02*
X324000D01*
Y160117D01*
X323875Y160450D01*
X323583Y160700D01*
X323250Y160783D01*
X322917Y160700D01*
X322667Y160492D01*
X322542Y160117D01*
Y159117D01*
G01X322000Y162133D02*
X321708Y162383D01*
X321542Y162717D01*
X321500Y163092D01*
X321542Y163425D01*
X321750Y163758D01*
X322000Y163967D01*
X322250Y164008D01*
X322542Y163925D01*
X322750Y163633D01*
X322833Y163342D01*
Y162967D01*
G01Y163342D02*
X322958Y163592D01*
X323167Y163800D01*
X323417Y163883D01*
X323667Y163800D01*
X323875Y163592D01*
X324000Y163217D01*
X323958Y162842D01*
X323792Y162467D01*
G01X322542Y165358D02*
X322833Y165650D01*
X323000Y165900D01*
X323083Y166233D01*
X323000Y166525D01*
X322833Y166733D01*
X322583Y166900D01*
X322292Y166942D01*
X322042Y166900D01*
X321792Y166733D01*
X321583Y166483D01*
X321500Y166192D01*
X321583Y165858D01*
X321833Y165567D01*
X322208Y165400D01*
X322625Y165358D01*
X323167Y165442D01*
X323458Y165567D01*
X323750Y165775D01*
X323958Y166067D01*
X324000Y166358D01*
X323917Y166650D01*
X323708Y166858D01*
G01X334150Y173000D02*
Y170500D01*
G01X335108Y173000D02*
X333192D01*
G01X331883Y170500D02*
Y173000D01*
X330883D01*
X330550Y172875D01*
X330300Y172583D01*
X330217Y172250D01*
X330300Y171917D01*
X330508Y171667D01*
X330883Y171542D01*
X331883D01*
G01X328742D02*
X328450Y171833D01*
X328200Y172000D01*
X327867Y172083D01*
X327575Y172000D01*
X327367Y171833D01*
X327200Y171583D01*
X327158Y171292D01*
X327200Y171042D01*
X327367Y170792D01*
X327617Y170583D01*
X327908Y170500D01*
X328242Y170583D01*
X328533Y170833D01*
X328700Y171208D01*
X328742Y171625D01*
X328658Y172167D01*
X328533Y172458D01*
X328325Y172750D01*
X328033Y172958D01*
X327742Y173000D01*
X327450Y172917D01*
X327242Y172708D01*
G01X325642Y171542D02*
X325350Y171833D01*
X325100Y172000D01*
X324767Y172083D01*
X324475Y172000D01*
X324267Y171833D01*
X324100Y171583D01*
X324058Y171292D01*
X324100Y171042D01*
X324267Y170792D01*
X324517Y170583D01*
X324808Y170500D01*
X325142Y170583D01*
X325433Y170833D01*
X325600Y171208D01*
X325642Y171625D01*
X325558Y172167D01*
X325433Y172458D01*
X325225Y172750D01*
X324933Y172958D01*
X324642Y173000D01*
X324350Y172917D01*
X324142Y172708D01*
G01X334150Y177000D02*
Y174500D01*
G01X335108Y177000D02*
X333192D01*
G01X331883Y174500D02*
Y177000D01*
X330883D01*
X330550Y176875D01*
X330300Y176583D01*
X330217Y176250D01*
X330300Y175917D01*
X330508Y175667D01*
X330883Y175542D01*
X331883D01*
G01X328742Y176583D02*
X328492Y176833D01*
X328200Y176958D01*
X327867Y177000D01*
X327450Y176917D01*
X327158Y176708D01*
X327075Y176458D01*
X327117Y176208D01*
X327283Y176000D01*
X328117Y175583D01*
X328492Y175292D01*
X328742Y174875D01*
X328825Y174500D01*
X327075D01*
G01X325767Y174875D02*
X325517Y174667D01*
X325225Y174542D01*
X324850Y174500D01*
X324475Y174583D01*
X324183Y174750D01*
X323975Y175042D01*
X323933Y175375D01*
X324017Y175708D01*
X324225Y175917D01*
X324517Y176083D01*
X324808Y176125D01*
X325100Y176083D01*
X325475Y175917D01*
X325350Y177000D01*
X324225D01*
G01X340000Y179000D02*
X338500D01*
Y186000D01*
X318000D01*
Y200500D01*
X326500D01*
Y202000D01*
X339500D01*
Y196500D01*
X351000D01*
Y201500D01*
X352500D01*
G01X324000Y188017D02*
X326500D01*
Y189058D01*
X326375Y189392D01*
X326208Y189600D01*
X325875Y189683D01*
X325542Y189600D01*
X325333Y189350D01*
X325208Y189058D01*
Y188017D01*
G01Y189058D02*
X324000Y189683D01*
G01X326083Y191158D02*
X326333Y191408D01*
X326458Y191700D01*
X326500Y192033D01*
X326417Y192450D01*
X326208Y192742D01*
X325958Y192825D01*
X325708Y192783D01*
X325500Y192617D01*
X325083Y191783D01*
X324792Y191408D01*
X324375Y191158D01*
X324000Y191075D01*
Y192825D01*
G01X324292Y194342D02*
X324083Y194633D01*
X324000Y194967D01*
X324083Y195300D01*
X324333Y195592D01*
X324708Y195800D01*
X325083Y195883D01*
X325542D01*
X325917Y195800D01*
X326250Y195592D01*
X326417Y195342D01*
X326500Y195050D01*
X326417Y194717D01*
X326250Y194467D01*
X326000Y194300D01*
X325667Y194217D01*
X325375Y194300D01*
X325083Y194508D01*
X324917Y194758D01*
X324875Y195050D01*
X324958Y195383D01*
X325167Y195633D01*
X325542Y195883D01*
G01X325042Y197358D02*
X325333Y197650D01*
X325500Y197900D01*
X325583Y198233D01*
X325500Y198525D01*
X325333Y198733D01*
X325083Y198900D01*
X324792Y198942D01*
X324542Y198900D01*
X324292Y198733D01*
X324083Y198483D01*
X324000Y198192D01*
X324083Y197858D01*
X324333Y197567D01*
X324708Y197400D01*
X325125Y197358D01*
X325667Y197442D01*
X325958Y197567D01*
X326250Y197775D01*
X326458Y198067D01*
X326500Y198358D01*
X326417Y198650D01*
X326208Y198858D01*
G01X319500Y188517D02*
X322000D01*
Y189558D01*
X321875Y189892D01*
X321708Y190100D01*
X321375Y190183D01*
X321042Y190100D01*
X320833Y189850D01*
X320708Y189558D01*
Y188517D01*
G01Y189558D02*
X319500Y190183D01*
G01X320000Y191533D02*
X319708Y191783D01*
X319542Y192117D01*
X319500Y192492D01*
X319542Y192825D01*
X319750Y193158D01*
X320000Y193367D01*
X320250Y193408D01*
X320542Y193325D01*
X320750Y193033D01*
X320833Y192742D01*
Y192367D01*
G01Y192742D02*
X320958Y192992D01*
X321167Y193200D01*
X321417Y193283D01*
X321667Y193200D01*
X321875Y192992D01*
X322000Y192617D01*
X321958Y192242D01*
X321792Y191867D01*
G01X319500Y195550D02*
X322000D01*
X321500Y195050D01*
G01X319500D02*
Y196050D01*
G01Y198650D02*
X322000D01*
X321500Y198150D01*
G01X319500D02*
Y199150D01*
G01X325000Y230517D02*
X327500D01*
Y231558D01*
X327375Y231892D01*
X327208Y232100D01*
X326875Y232183D01*
X326542Y232100D01*
X326333Y231850D01*
X326208Y231558D01*
Y230517D01*
G01Y231558D02*
X325000Y232183D01*
G01X327083Y233658D02*
X327333Y233908D01*
X327458Y234200D01*
X327500Y234533D01*
X327417Y234950D01*
X327208Y235242D01*
X326958Y235325D01*
X326708Y235283D01*
X326500Y235117D01*
X326083Y234283D01*
X325792Y233908D01*
X325375Y233658D01*
X325000Y233575D01*
Y235325D01*
G01X326042Y236758D02*
X326333Y237050D01*
X326500Y237300D01*
X326583Y237633D01*
X326500Y237925D01*
X326333Y238133D01*
X326083Y238300D01*
X325792Y238342D01*
X325542Y238300D01*
X325292Y238133D01*
X325083Y237883D01*
X325000Y237592D01*
X325083Y237258D01*
X325333Y236967D01*
X325708Y236800D01*
X326125Y236758D01*
X326667Y236842D01*
X326958Y236967D01*
X327250Y237175D01*
X327458Y237467D01*
X327500Y237758D01*
X327417Y238050D01*
X327208Y238258D01*
G01X326042Y239858D02*
X326333Y240150D01*
X326500Y240400D01*
X326583Y240733D01*
X326500Y241025D01*
X326333Y241233D01*
X326083Y241400D01*
X325792Y241442D01*
X325542Y241400D01*
X325292Y241233D01*
X325083Y240983D01*
X325000Y240692D01*
X325083Y240358D01*
X325333Y240067D01*
X325708Y239900D01*
X326125Y239858D01*
X326667Y239942D01*
X326958Y240067D01*
X327250Y240275D01*
X327458Y240567D01*
X327500Y240858D01*
X327417Y241150D01*
X327208Y241358D01*
G01X316000Y233017D02*
X318500D01*
Y234058D01*
X318375Y234392D01*
X318208Y234600D01*
X317875Y234683D01*
X317542Y234600D01*
X317333Y234350D01*
X317208Y234058D01*
Y233017D01*
G01Y234058D02*
X316000Y234683D01*
G01X318083Y236158D02*
X318333Y236408D01*
X318458Y236700D01*
X318500Y237033D01*
X318417Y237450D01*
X318208Y237742D01*
X317958Y237825D01*
X317708Y237783D01*
X317500Y237617D01*
X317083Y236783D01*
X316792Y236408D01*
X316375Y236158D01*
X316000Y236075D01*
Y237825D01*
G01Y240050D02*
X316042Y240342D01*
X316167Y240675D01*
X316375Y240883D01*
X316667Y240967D01*
X316958Y240883D01*
X317208Y240633D01*
X317333Y240258D01*
Y239842D01*
X317417Y239592D01*
X317625Y239383D01*
X317917Y239300D01*
X318208Y239425D01*
X318417Y239717D01*
X318500Y240050D01*
X318417Y240383D01*
X318208Y240675D01*
X317917Y240800D01*
X317625Y240717D01*
X317417Y240508D01*
X317333Y240258D01*
Y239842D01*
X317208Y239467D01*
X316958Y239217D01*
X316667Y239133D01*
X316375Y239217D01*
X316167Y239425D01*
X316042Y239758D01*
X316000Y240050D01*
G01X316500Y242233D02*
X316208Y242483D01*
X316042Y242817D01*
X316000Y243192D01*
X316042Y243525D01*
X316250Y243858D01*
X316500Y244067D01*
X316750Y244108D01*
X317042Y244025D01*
X317250Y243733D01*
X317333Y243442D01*
Y243067D01*
G01Y243442D02*
X317458Y243692D01*
X317667Y243900D01*
X317917Y243983D01*
X318167Y243900D01*
X318375Y243692D01*
X318500Y243317D01*
X318458Y242942D01*
X318292Y242567D01*
G01X312000Y233017D02*
X314500D01*
Y234058D01*
X314375Y234392D01*
X314208Y234600D01*
X313875Y234683D01*
X313542Y234600D01*
X313333Y234350D01*
X313208Y234058D01*
Y233017D01*
G01Y234058D02*
X312000Y234683D01*
G01X314083Y236158D02*
X314333Y236408D01*
X314458Y236700D01*
X314500Y237033D01*
X314417Y237450D01*
X314208Y237742D01*
X313958Y237825D01*
X313708Y237783D01*
X313500Y237617D01*
X313083Y236783D01*
X312792Y236408D01*
X312375Y236158D01*
X312000Y236075D01*
Y237825D01*
G01Y240050D02*
X312042Y240342D01*
X312167Y240675D01*
X312375Y240883D01*
X312667Y240967D01*
X312958Y240883D01*
X313208Y240633D01*
X313333Y240258D01*
Y239842D01*
X313417Y239592D01*
X313625Y239383D01*
X313917Y239300D01*
X314208Y239425D01*
X314417Y239717D01*
X314500Y240050D01*
X314417Y240383D01*
X314208Y240675D01*
X313917Y240800D01*
X313625Y240717D01*
X313417Y240508D01*
X313333Y240258D01*
Y239842D01*
X313208Y239467D01*
X312958Y239217D01*
X312667Y239133D01*
X312375Y239217D01*
X312167Y239425D01*
X312042Y239758D01*
X312000Y240050D01*
G01Y243150D02*
X312042Y243442D01*
X312167Y243775D01*
X312375Y243983D01*
X312667Y244067D01*
X312958Y243983D01*
X313208Y243733D01*
X313333Y243358D01*
Y242942D01*
X313417Y242692D01*
X313625Y242483D01*
X313917Y242400D01*
X314208Y242525D01*
X314417Y242817D01*
X314500Y243150D01*
X314417Y243483D01*
X314208Y243775D01*
X313917Y243900D01*
X313625Y243817D01*
X313417Y243608D01*
X313333Y243358D01*
Y242942D01*
X313208Y242567D01*
X312958Y242317D01*
X312667Y242233D01*
X312375Y242317D01*
X312167Y242525D01*
X312042Y242858D01*
X312000Y243150D01*
G01X336483Y257500D02*
Y260000D01*
X335442D01*
X335108Y259875D01*
X334900Y259708D01*
X334817Y259375D01*
X334900Y259042D01*
X335150Y258833D01*
X335442Y258708D01*
X336483D01*
G01X335442D02*
X334817Y257500D01*
G01X333342Y259583D02*
X333092Y259833D01*
X332800Y259958D01*
X332467Y260000D01*
X332050Y259917D01*
X331758Y259708D01*
X331675Y259458D01*
X331717Y259208D01*
X331883Y259000D01*
X332717Y258583D01*
X333092Y258292D01*
X333342Y257875D01*
X333425Y257500D01*
X331675D01*
G01X329450D02*
X329158Y257542D01*
X328825Y257667D01*
X328617Y257875D01*
X328533Y258167D01*
X328617Y258458D01*
X328867Y258708D01*
X329242Y258833D01*
X329658D01*
X329908Y258917D01*
X330117Y259125D01*
X330200Y259417D01*
X330075Y259708D01*
X329783Y259917D01*
X329450Y260000D01*
X329117Y259917D01*
X328825Y259708D01*
X328700Y259417D01*
X328783Y259125D01*
X328992Y258917D01*
X329242Y258833D01*
X329658D01*
X330033Y258708D01*
X330283Y258458D01*
X330367Y258167D01*
X330283Y257875D01*
X330075Y257667D01*
X329742Y257542D01*
X329450Y257500D01*
G01X326350Y260000D02*
X326683Y259917D01*
X326933Y259708D01*
X327100Y259458D01*
X327225Y259125D01*
X327267Y258750D01*
X327225Y258375D01*
X327100Y258042D01*
X326933Y257792D01*
X326683Y257583D01*
X326350Y257500D01*
X326017Y257583D01*
X325767Y257792D01*
X325600Y258042D01*
X325475Y258375D01*
X325433Y258750D01*
X325475Y259125D01*
X325600Y259458D01*
X325767Y259708D01*
X326017Y259917D01*
X326350Y260000D01*
G01X317500Y263517D02*
X320000D01*
Y264558D01*
X319875Y264892D01*
X319708Y265100D01*
X319375Y265183D01*
X319042Y265100D01*
X318833Y264850D01*
X318708Y264558D01*
Y263517D01*
G01Y264558D02*
X317500Y265183D01*
G01X319583Y266658D02*
X319833Y266908D01*
X319958Y267200D01*
X320000Y267533D01*
X319917Y267950D01*
X319708Y268242D01*
X319458Y268325D01*
X319208Y268283D01*
X319000Y268117D01*
X318583Y267283D01*
X318292Y266908D01*
X317875Y266658D01*
X317500Y266575D01*
Y268325D01*
G01Y270550D02*
X317542Y270842D01*
X317667Y271175D01*
X317875Y271383D01*
X318167Y271467D01*
X318458Y271383D01*
X318708Y271133D01*
X318833Y270758D01*
Y270342D01*
X318917Y270092D01*
X319125Y269883D01*
X319417Y269800D01*
X319708Y269925D01*
X319917Y270217D01*
X320000Y270550D01*
X319917Y270883D01*
X319708Y271175D01*
X319417Y271300D01*
X319125Y271217D01*
X318917Y271008D01*
X318833Y270758D01*
Y270342D01*
X318708Y269967D01*
X318458Y269717D01*
X318167Y269633D01*
X317875Y269717D01*
X317667Y269925D01*
X317542Y270258D01*
X317500Y270550D01*
G01X317792Y272942D02*
X317583Y273233D01*
X317500Y273567D01*
X317583Y273900D01*
X317833Y274192D01*
X318208Y274400D01*
X318583Y274483D01*
X319042D01*
X319417Y274400D01*
X319750Y274192D01*
X319917Y273942D01*
X320000Y273650D01*
X319917Y273317D01*
X319750Y273067D01*
X319500Y272900D01*
X319167Y272817D01*
X318875Y272900D01*
X318583Y273108D01*
X318417Y273358D01*
X318375Y273650D01*
X318458Y273983D01*
X318667Y274233D01*
X319042Y274483D01*
G01X321500Y263517D02*
X324000D01*
Y264558D01*
X323875Y264892D01*
X323708Y265100D01*
X323375Y265183D01*
X323042Y265100D01*
X322833Y264850D01*
X322708Y264558D01*
Y263517D01*
G01Y264558D02*
X321500Y265183D01*
G01X323583Y266658D02*
X323833Y266908D01*
X323958Y267200D01*
X324000Y267533D01*
X323917Y267950D01*
X323708Y268242D01*
X323458Y268325D01*
X323208Y268283D01*
X323000Y268117D01*
X322583Y267283D01*
X322292Y266908D01*
X321875Y266658D01*
X321500Y266575D01*
Y268325D01*
G01Y270550D02*
X321542Y270842D01*
X321667Y271175D01*
X321875Y271383D01*
X322167Y271467D01*
X322458Y271383D01*
X322708Y271133D01*
X322833Y270758D01*
Y270342D01*
X322917Y270092D01*
X323125Y269883D01*
X323417Y269800D01*
X323708Y269925D01*
X323917Y270217D01*
X324000Y270550D01*
X323917Y270883D01*
X323708Y271175D01*
X323417Y271300D01*
X323125Y271217D01*
X322917Y271008D01*
X322833Y270758D01*
Y270342D01*
X322708Y269967D01*
X322458Y269717D01*
X322167Y269633D01*
X321875Y269717D01*
X321667Y269925D01*
X321542Y270258D01*
X321500Y270550D01*
G01Y274150D02*
X324000D01*
X322208Y272608D01*
Y274692D01*
G01X313500Y263517D02*
X316000D01*
Y264558D01*
X315875Y264892D01*
X315708Y265100D01*
X315375Y265183D01*
X315042Y265100D01*
X314833Y264850D01*
X314708Y264558D01*
Y263517D01*
G01Y264558D02*
X313500Y265183D01*
G01X315583Y266658D02*
X315833Y266908D01*
X315958Y267200D01*
X316000Y267533D01*
X315917Y267950D01*
X315708Y268242D01*
X315458Y268325D01*
X315208Y268283D01*
X315000Y268117D01*
X314583Y267283D01*
X314292Y266908D01*
X313875Y266658D01*
X313500Y266575D01*
Y268325D01*
G01X313792Y269842D02*
X313583Y270133D01*
X313500Y270467D01*
X313583Y270800D01*
X313833Y271092D01*
X314208Y271300D01*
X314583Y271383D01*
X315042D01*
X315417Y271300D01*
X315750Y271092D01*
X315917Y270842D01*
X316000Y270550D01*
X315917Y270217D01*
X315750Y269967D01*
X315500Y269800D01*
X315167Y269717D01*
X314875Y269800D01*
X314583Y270008D01*
X314417Y270258D01*
X314375Y270550D01*
X314458Y270883D01*
X314667Y271133D01*
X315042Y271383D01*
G01X314000Y272733D02*
X313708Y272983D01*
X313542Y273317D01*
X313500Y273692D01*
X313542Y274025D01*
X313750Y274358D01*
X314000Y274567D01*
X314250Y274608D01*
X314542Y274525D01*
X314750Y274233D01*
X314833Y273942D01*
Y273567D01*
G01Y273942D02*
X314958Y274192D01*
X315167Y274400D01*
X315417Y274483D01*
X315667Y274400D01*
X315875Y274192D01*
X316000Y273817D01*
X315958Y273442D01*
X315792Y273067D01*
G01X329500Y41967D02*
X332000D01*
Y42967D01*
X331875Y43300D01*
X331583Y43550D01*
X331250Y43633D01*
X330917Y43550D01*
X330667Y43342D01*
X330542Y42967D01*
Y41967D01*
G01X331792Y46817D02*
X331917Y46567D01*
X332000Y46275D01*
Y45942D01*
X331875Y45567D01*
X331667Y45275D01*
X331417Y45067D01*
X331000Y44900D01*
X330625Y44858D01*
X330250Y44942D01*
X330000Y45067D01*
X329750Y45317D01*
X329583Y45608D01*
X329500Y45900D01*
Y46192D01*
X329583Y46483D01*
X329708Y46733D01*
X329875Y46942D01*
G01X331583Y48208D02*
X331833Y48458D01*
X331958Y48750D01*
X332000Y49083D01*
X331917Y49500D01*
X331708Y49792D01*
X331458Y49875D01*
X331208Y49833D01*
X331000Y49667D01*
X330583Y48833D01*
X330292Y48458D01*
X329875Y48208D01*
X329500Y48125D01*
Y49875D01*
G01X332000Y52100D02*
X331917Y51767D01*
X331708Y51517D01*
X331458Y51350D01*
X331125Y51225D01*
X330750Y51183D01*
X330375Y51225D01*
X330042Y51350D01*
X329792Y51517D01*
X329583Y51767D01*
X329500Y52100D01*
X329583Y52433D01*
X329792Y52683D01*
X330042Y52850D01*
X330375Y52975D01*
X330750Y53017D01*
X331125Y52975D01*
X331458Y52850D01*
X331708Y52683D01*
X331917Y52433D01*
X332000Y52100D01*
G01X330000Y54283D02*
X329708Y54533D01*
X329542Y54867D01*
X329500Y55242D01*
X329542Y55575D01*
X329750Y55908D01*
X330000Y56117D01*
X330250Y56158D01*
X330542Y56075D01*
X330750Y55783D01*
X330833Y55492D01*
Y55117D01*
G01Y55492D02*
X330958Y55742D01*
X331167Y55950D01*
X331417Y56033D01*
X331667Y55950D01*
X331875Y55742D01*
X332000Y55367D01*
X331958Y54992D01*
X331792Y54617D01*
G01X352033Y45500D02*
Y48000D01*
X351033D01*
X350700Y47875D01*
X350450Y47583D01*
X350367Y47250D01*
X350450Y46917D01*
X350658Y46667D01*
X351033Y46542D01*
X352033D01*
G01X347183Y47792D02*
X347433Y47917D01*
X347725Y48000D01*
X348058D01*
X348433Y47875D01*
X348725Y47667D01*
X348933Y47417D01*
X349100Y47000D01*
X349142Y46625D01*
X349058Y46250D01*
X348933Y46000D01*
X348683Y45750D01*
X348392Y45583D01*
X348100Y45500D01*
X347808D01*
X347517Y45583D01*
X347267Y45708D01*
X347058Y45875D01*
G01X345792Y47583D02*
X345542Y47833D01*
X345250Y47958D01*
X344917Y48000D01*
X344500Y47917D01*
X344208Y47708D01*
X344125Y47458D01*
X344167Y47208D01*
X344333Y47000D01*
X345167Y46583D01*
X345542Y46292D01*
X345792Y45875D01*
X345875Y45500D01*
X344125D01*
G01X341900Y48000D02*
X342233Y47917D01*
X342483Y47708D01*
X342650Y47458D01*
X342775Y47125D01*
X342817Y46750D01*
X342775Y46375D01*
X342650Y46042D01*
X342483Y45792D01*
X342233Y45583D01*
X341900Y45500D01*
X341567Y45583D01*
X341317Y45792D01*
X341150Y46042D01*
X341025Y46375D01*
X340983Y46750D01*
X341025Y47125D01*
X341150Y47458D01*
X341317Y47708D01*
X341567Y47917D01*
X341900Y48000D01*
G01X338800Y45500D02*
Y48000D01*
X339300Y47500D01*
G01Y45500D02*
X338300D01*
G01X349533Y50000D02*
Y52500D01*
X348533D01*
X348200Y52375D01*
X347950Y52083D01*
X347867Y51750D01*
X347950Y51417D01*
X348158Y51167D01*
X348533Y51042D01*
X349533D01*
G01X344683Y52292D02*
X344933Y52417D01*
X345225Y52500D01*
X345558D01*
X345933Y52375D01*
X346225Y52167D01*
X346433Y51917D01*
X346600Y51500D01*
X346642Y51125D01*
X346558Y50750D01*
X346433Y50500D01*
X346183Y50250D01*
X345892Y50083D01*
X345600Y50000D01*
X345308D01*
X345017Y50083D01*
X344767Y50208D01*
X344558Y50375D01*
G01X343292Y52083D02*
X343042Y52333D01*
X342750Y52458D01*
X342417Y52500D01*
X342000Y52417D01*
X341708Y52208D01*
X341625Y51958D01*
X341667Y51708D01*
X341833Y51500D01*
X342667Y51083D01*
X343042Y50792D01*
X343292Y50375D01*
X343375Y50000D01*
X341625D01*
G01X339400Y52500D02*
X339733Y52417D01*
X339983Y52208D01*
X340150Y51958D01*
X340275Y51625D01*
X340317Y51250D01*
X340275Y50875D01*
X340150Y50542D01*
X339983Y50292D01*
X339733Y50083D01*
X339400Y50000D01*
X339067Y50083D01*
X338817Y50292D01*
X338650Y50542D01*
X338525Y50875D01*
X338483Y51250D01*
X338525Y51625D01*
X338650Y51958D01*
X338817Y52208D01*
X339067Y52417D01*
X339400Y52500D01*
G01X337092Y52083D02*
X336842Y52333D01*
X336550Y52458D01*
X336217Y52500D01*
X335800Y52417D01*
X335508Y52208D01*
X335425Y51958D01*
X335467Y51708D01*
X335633Y51500D01*
X336467Y51083D01*
X336842Y50792D01*
X337092Y50375D01*
X337175Y50000D01*
X335425D01*
G01X341000Y66500D02*
X336500D01*
Y75500D01*
G01X340000Y86500D02*
X343500D01*
Y83000D01*
X384500D01*
Y65000D01*
X382500D01*
G01X332000Y110000D02*
X334000D01*
G01X338500Y112000D02*
X344000D01*
Y110500D01*
G01X331500Y111517D02*
X334000D01*
Y112558D01*
X333875Y112892D01*
X333708Y113100D01*
X333375Y113183D01*
X333042Y113100D01*
X332833Y112850D01*
X332708Y112558D01*
Y111517D01*
G01Y112558D02*
X331500Y113183D01*
G01X332000Y114533D02*
X331708Y114783D01*
X331542Y115117D01*
X331500Y115492D01*
X331542Y115825D01*
X331750Y116158D01*
X332000Y116367D01*
X332250Y116408D01*
X332542Y116325D01*
X332750Y116033D01*
X332833Y115742D01*
Y115367D01*
G01Y115742D02*
X332958Y115992D01*
X333167Y116200D01*
X333417Y116283D01*
X333667Y116200D01*
X333875Y115992D01*
X334000Y115617D01*
X333958Y115242D01*
X333792Y114867D01*
G01X331875Y117633D02*
X331667Y117883D01*
X331542Y118175D01*
X331500Y118550D01*
X331583Y118925D01*
X331750Y119217D01*
X332042Y119425D01*
X332375Y119467D01*
X332708Y119383D01*
X332917Y119175D01*
X333083Y118883D01*
X333125Y118592D01*
X333083Y118300D01*
X332917Y117925D01*
X334000Y118050D01*
Y119175D01*
G01X331500Y121567D02*
X332042Y121650D01*
X332500Y121775D01*
X332917Y121942D01*
X333375Y122150D01*
X334000Y122483D01*
Y120817D01*
G01X339000Y135850D02*
X336500D01*
G01X339000Y134892D02*
Y136808D01*
G01X336500Y138117D02*
X339000D01*
Y139117D01*
X338875Y139450D01*
X338583Y139700D01*
X338250Y139783D01*
X337917Y139700D01*
X337667Y139492D01*
X337542Y139117D01*
Y138117D01*
G01Y141258D02*
X337833Y141550D01*
X338000Y141800D01*
X338083Y142133D01*
X338000Y142425D01*
X337833Y142633D01*
X337583Y142800D01*
X337292Y142842D01*
X337042Y142800D01*
X336792Y142633D01*
X336583Y142383D01*
X336500Y142092D01*
X336583Y141758D01*
X336833Y141467D01*
X337208Y141300D01*
X337625Y141258D01*
X338167Y141342D01*
X338458Y141467D01*
X338750Y141675D01*
X338958Y141967D01*
X339000Y142258D01*
X338917Y142550D01*
X338708Y142758D01*
G01X339000Y145150D02*
X338917Y144817D01*
X338708Y144567D01*
X338458Y144400D01*
X338125Y144275D01*
X337750Y144233D01*
X337375Y144275D01*
X337042Y144400D01*
X336792Y144567D01*
X336583Y144817D01*
X336500Y145150D01*
X336583Y145483D01*
X336792Y145733D01*
X337042Y145900D01*
X337375Y146025D01*
X337750Y146067D01*
X338125Y146025D01*
X338458Y145900D01*
X338708Y145733D01*
X338917Y145483D01*
X339000Y145150D01*
G01X327000Y138517D02*
X329500D01*
Y139558D01*
X329375Y139892D01*
X329208Y140100D01*
X328875Y140183D01*
X328542Y140100D01*
X328333Y139850D01*
X328208Y139558D01*
Y138517D01*
G01Y139558D02*
X327000Y140183D01*
G01X327500Y141533D02*
X327208Y141783D01*
X327042Y142117D01*
X327000Y142492D01*
X327042Y142825D01*
X327250Y143158D01*
X327500Y143367D01*
X327750Y143408D01*
X328042Y143325D01*
X328250Y143033D01*
X328333Y142742D01*
Y142367D01*
G01Y142742D02*
X328458Y142992D01*
X328667Y143200D01*
X328917Y143283D01*
X329167Y143200D01*
X329375Y142992D01*
X329500Y142617D01*
X329458Y142242D01*
X329292Y141867D01*
G01X327000Y146050D02*
X329500D01*
X327708Y144508D01*
Y146592D01*
G01X327375Y147733D02*
X327167Y147983D01*
X327042Y148275D01*
X327000Y148650D01*
X327083Y149025D01*
X327250Y149317D01*
X327542Y149525D01*
X327875Y149567D01*
X328208Y149483D01*
X328417Y149275D01*
X328583Y148983D01*
X328625Y148692D01*
X328583Y148400D01*
X328417Y148025D01*
X329500Y148150D01*
Y149275D01*
G01X327000Y157517D02*
X329500D01*
Y158558D01*
X329375Y158892D01*
X329208Y159100D01*
X328875Y159183D01*
X328542Y159100D01*
X328333Y158850D01*
X328208Y158558D01*
Y157517D01*
G01Y158558D02*
X327000Y159183D01*
G01X327500Y160533D02*
X327208Y160783D01*
X327042Y161117D01*
X327000Y161492D01*
X327042Y161825D01*
X327250Y162158D01*
X327500Y162367D01*
X327750Y162408D01*
X328042Y162325D01*
X328250Y162033D01*
X328333Y161742D01*
Y161367D01*
G01Y161742D02*
X328458Y161992D01*
X328667Y162200D01*
X328917Y162283D01*
X329167Y162200D01*
X329375Y161992D01*
X329500Y161617D01*
X329458Y161242D01*
X329292Y160867D01*
G01X329500Y164550D02*
X329417Y164217D01*
X329208Y163967D01*
X328958Y163800D01*
X328625Y163675D01*
X328250Y163633D01*
X327875Y163675D01*
X327542Y163800D01*
X327292Y163967D01*
X327083Y164217D01*
X327000Y164550D01*
X327083Y164883D01*
X327292Y165133D01*
X327542Y165300D01*
X327875Y165425D01*
X328250Y165467D01*
X328625Y165425D01*
X328958Y165300D01*
X329208Y165133D01*
X329417Y164883D01*
X329500Y164550D01*
G01X329083Y166858D02*
X329333Y167108D01*
X329458Y167400D01*
X329500Y167733D01*
X329417Y168150D01*
X329208Y168442D01*
X328958Y168525D01*
X328708Y168483D01*
X328500Y168317D01*
X328083Y167483D01*
X327792Y167108D01*
X327375Y166858D01*
X327000Y166775D01*
Y168525D01*
G01X331500Y157517D02*
X334000D01*
Y158558D01*
X333875Y158892D01*
X333708Y159100D01*
X333375Y159183D01*
X333042Y159100D01*
X332833Y158850D01*
X332708Y158558D01*
Y157517D01*
G01Y158558D02*
X331500Y159183D01*
G01X332000Y160533D02*
X331708Y160783D01*
X331542Y161117D01*
X331500Y161492D01*
X331542Y161825D01*
X331750Y162158D01*
X332000Y162367D01*
X332250Y162408D01*
X332542Y162325D01*
X332750Y162033D01*
X332833Y161742D01*
Y161367D01*
G01Y161742D02*
X332958Y161992D01*
X333167Y162200D01*
X333417Y162283D01*
X333667Y162200D01*
X333875Y161992D01*
X334000Y161617D01*
X333958Y161242D01*
X333792Y160867D01*
G01X333583Y163758D02*
X333833Y164008D01*
X333958Y164300D01*
X334000Y164633D01*
X333917Y165050D01*
X333708Y165342D01*
X333458Y165425D01*
X333208Y165383D01*
X333000Y165217D01*
X332583Y164383D01*
X332292Y164008D01*
X331875Y163758D01*
X331500Y163675D01*
Y165425D01*
G01Y167650D02*
X334000D01*
X333500Y167150D01*
G01X331500D02*
Y168150D01*
G01X334292Y190767D02*
X334417Y190517D01*
X334500Y190225D01*
Y189892D01*
X334375Y189517D01*
X334167Y189225D01*
X333917Y189017D01*
X333500Y188850D01*
X333125Y188808D01*
X332750Y188892D01*
X332500Y189017D01*
X332250Y189267D01*
X332083Y189558D01*
X332000Y189850D01*
Y190142D01*
X332083Y190433D01*
X332208Y190683D01*
X332375Y190892D01*
G01X332000Y192950D02*
X334500D01*
X334000Y192450D01*
G01X332000D02*
Y193450D01*
G01Y196550D02*
X334500D01*
X332708Y195008D01*
Y197092D01*
G01X333042Y198358D02*
X333333Y198650D01*
X333500Y198900D01*
X333583Y199233D01*
X333500Y199525D01*
X333333Y199733D01*
X333083Y199900D01*
X332792Y199942D01*
X332542Y199900D01*
X332292Y199733D01*
X332083Y199483D01*
X332000Y199192D01*
X332083Y198858D01*
X332333Y198567D01*
X332708Y198400D01*
X333125Y198358D01*
X333667Y198442D01*
X333958Y198567D01*
X334250Y198775D01*
X334458Y199067D01*
X334500Y199358D01*
X334417Y199650D01*
X334208Y199858D01*
G01X349733Y193992D02*
X349983Y194117D01*
X350275Y194200D01*
X350608D01*
X350983Y194075D01*
X351275Y193867D01*
X351483Y193617D01*
X351650Y193200D01*
X351692Y192825D01*
X351608Y192450D01*
X351483Y192200D01*
X351233Y191950D01*
X350942Y191783D01*
X350650Y191700D01*
X350358D01*
X350067Y191783D01*
X349817Y191908D01*
X349608Y192075D01*
G01X347550Y191700D02*
Y194200D01*
X348050Y193700D01*
G01Y191700D02*
X347050D01*
G01X345367Y192075D02*
X345117Y191867D01*
X344825Y191742D01*
X344450Y191700D01*
X344075Y191783D01*
X343783Y191950D01*
X343575Y192242D01*
X343533Y192575D01*
X343617Y192908D01*
X343825Y193117D01*
X344117Y193283D01*
X344408Y193325D01*
X344700Y193283D01*
X345075Y193117D01*
X344950Y194200D01*
X343825D01*
G01X341350D02*
X341683Y194117D01*
X341933Y193908D01*
X342100Y193658D01*
X342225Y193325D01*
X342267Y192950D01*
X342225Y192575D01*
X342100Y192242D01*
X341933Y191992D01*
X341683Y191783D01*
X341350Y191700D01*
X341017Y191783D01*
X340767Y191992D01*
X340600Y192242D01*
X340475Y192575D01*
X340433Y192950D01*
X340475Y193325D01*
X340600Y193658D01*
X340767Y193908D01*
X341017Y194117D01*
X341350Y194200D01*
G01X349733Y189992D02*
X349983Y190117D01*
X350275Y190200D01*
X350608D01*
X350983Y190075D01*
X351275Y189867D01*
X351483Y189617D01*
X351650Y189200D01*
X351692Y188825D01*
X351608Y188450D01*
X351483Y188200D01*
X351233Y187950D01*
X350942Y187783D01*
X350650Y187700D01*
X350358D01*
X350067Y187783D01*
X349817Y187908D01*
X349608Y188075D01*
G01X347550Y187700D02*
Y190200D01*
X348050Y189700D01*
G01Y187700D02*
X347050D01*
G01X345367Y188075D02*
X345117Y187867D01*
X344825Y187742D01*
X344450Y187700D01*
X344075Y187783D01*
X343783Y187950D01*
X343575Y188242D01*
X343533Y188575D01*
X343617Y188908D01*
X343825Y189117D01*
X344117Y189283D01*
X344408Y189325D01*
X344700Y189283D01*
X345075Y189117D01*
X344950Y190200D01*
X343825D01*
G01X342267Y188075D02*
X342017Y187867D01*
X341725Y187742D01*
X341350Y187700D01*
X340975Y187783D01*
X340683Y187950D01*
X340475Y188242D01*
X340433Y188575D01*
X340517Y188908D01*
X340725Y189117D01*
X341017Y189283D01*
X341308Y189325D01*
X341600Y189283D01*
X341975Y189117D01*
X341850Y190200D01*
X340725D01*
G01X338292Y190767D02*
X338417Y190517D01*
X338500Y190225D01*
Y189892D01*
X338375Y189517D01*
X338167Y189225D01*
X337917Y189017D01*
X337500Y188850D01*
X337125Y188808D01*
X336750Y188892D01*
X336500Y189017D01*
X336250Y189267D01*
X336083Y189558D01*
X336000Y189850D01*
Y190142D01*
X336083Y190433D01*
X336208Y190683D01*
X336375Y190892D01*
G01X336000Y192950D02*
X338500D01*
X338000Y192450D01*
G01X336000D02*
Y193450D01*
G01Y196550D02*
X338500D01*
X336708Y195008D01*
Y197092D01*
G01X336500Y198233D02*
X336208Y198483D01*
X336042Y198817D01*
X336000Y199192D01*
X336042Y199525D01*
X336250Y199858D01*
X336500Y200067D01*
X336750Y200108D01*
X337042Y200025D01*
X337250Y199733D01*
X337333Y199442D01*
Y199067D01*
G01Y199442D02*
X337458Y199692D01*
X337667Y199900D01*
X337917Y199983D01*
X338167Y199900D01*
X338375Y199692D01*
X338500Y199317D01*
X338458Y198942D01*
X338292Y198567D01*
G01X328000Y189017D02*
X330500D01*
Y190058D01*
X330375Y190392D01*
X330208Y190600D01*
X329875Y190683D01*
X329542Y190600D01*
X329333Y190350D01*
X329208Y190058D01*
Y189017D01*
G01Y190058D02*
X328000Y190683D01*
G01X330083Y192158D02*
X330333Y192408D01*
X330458Y192700D01*
X330500Y193033D01*
X330417Y193450D01*
X330208Y193742D01*
X329958Y193825D01*
X329708Y193783D01*
X329500Y193617D01*
X329083Y192783D01*
X328792Y192408D01*
X328375Y192158D01*
X328000Y192075D01*
Y193825D01*
G01X328292Y195342D02*
X328083Y195633D01*
X328000Y195967D01*
X328083Y196300D01*
X328333Y196592D01*
X328708Y196800D01*
X329083Y196883D01*
X329542D01*
X329917Y196800D01*
X330250Y196592D01*
X330417Y196342D01*
X330500Y196050D01*
X330417Y195717D01*
X330250Y195467D01*
X330000Y195300D01*
X329667Y195217D01*
X329375Y195300D01*
X329083Y195508D01*
X328917Y195758D01*
X328875Y196050D01*
X328958Y196383D01*
X329167Y196633D01*
X329542Y196883D01*
G01X328000Y199150D02*
X328042Y199442D01*
X328167Y199775D01*
X328375Y199983D01*
X328667Y200067D01*
X328958Y199983D01*
X329208Y199733D01*
X329333Y199358D01*
Y198942D01*
X329417Y198692D01*
X329625Y198483D01*
X329917Y198400D01*
X330208Y198525D01*
X330417Y198817D01*
X330500Y199150D01*
X330417Y199483D01*
X330208Y199775D01*
X329917Y199900D01*
X329625Y199817D01*
X329417Y199608D01*
X329333Y199358D01*
Y198942D01*
X329208Y198567D01*
X328958Y198317D01*
X328667Y198233D01*
X328375Y198317D01*
X328167Y198525D01*
X328042Y198858D01*
X328000Y199150D01*
G01X351483Y207000D02*
Y209500D01*
X350442D01*
X350108Y209375D01*
X349900Y209208D01*
X349817Y208875D01*
X349900Y208542D01*
X350150Y208333D01*
X350442Y208208D01*
X351483D01*
G01X350442D02*
X349817Y207000D01*
G01X348342Y209083D02*
X348092Y209333D01*
X347800Y209458D01*
X347467Y209500D01*
X347050Y209417D01*
X346758Y209208D01*
X346675Y208958D01*
X346717Y208708D01*
X346883Y208500D01*
X347717Y208083D01*
X348092Y207792D01*
X348342Y207375D01*
X348425Y207000D01*
X346675D01*
G01X344533D02*
X344450Y207542D01*
X344325Y208000D01*
X344158Y208417D01*
X343950Y208875D01*
X343617Y209500D01*
X345283D01*
G01X341350Y207000D02*
X341058Y207042D01*
X340725Y207167D01*
X340517Y207375D01*
X340433Y207667D01*
X340517Y207958D01*
X340767Y208208D01*
X341142Y208333D01*
X341558D01*
X341808Y208417D01*
X342017Y208625D01*
X342100Y208917D01*
X341975Y209208D01*
X341683Y209417D01*
X341350Y209500D01*
X341017Y209417D01*
X340725Y209208D01*
X340600Y208917D01*
X340683Y208625D01*
X340892Y208417D01*
X341142Y208333D01*
X341558D01*
X341933Y208208D01*
X342183Y207958D01*
X342267Y207667D01*
X342183Y207375D01*
X341975Y207167D01*
X341642Y207042D01*
X341350Y207000D01*
G01X351483Y203000D02*
Y205500D01*
X350442D01*
X350108Y205375D01*
X349900Y205208D01*
X349817Y204875D01*
X349900Y204542D01*
X350150Y204333D01*
X350442Y204208D01*
X351483D01*
G01X350442D02*
X349817Y203000D01*
G01X348342Y205083D02*
X348092Y205333D01*
X347800Y205458D01*
X347467Y205500D01*
X347050Y205417D01*
X346758Y205208D01*
X346675Y204958D01*
X346717Y204708D01*
X346883Y204500D01*
X347717Y204083D01*
X348092Y203792D01*
X348342Y203375D01*
X348425Y203000D01*
X346675D01*
G01X344450D02*
X344158Y203042D01*
X343825Y203167D01*
X343617Y203375D01*
X343533Y203667D01*
X343617Y203958D01*
X343867Y204208D01*
X344242Y204333D01*
X344658D01*
X344908Y204417D01*
X345117Y204625D01*
X345200Y204917D01*
X345075Y205208D01*
X344783Y205417D01*
X344450Y205500D01*
X344117Y205417D01*
X343825Y205208D01*
X343700Y204917D01*
X343783Y204625D01*
X343992Y204417D01*
X344242Y204333D01*
X344658D01*
X345033Y204208D01*
X345283Y203958D01*
X345367Y203667D01*
X345283Y203375D01*
X345075Y203167D01*
X344742Y203042D01*
X344450Y203000D01*
G01X342142Y205083D02*
X341892Y205333D01*
X341600Y205458D01*
X341267Y205500D01*
X340850Y205417D01*
X340558Y205208D01*
X340475Y204958D01*
X340517Y204708D01*
X340683Y204500D01*
X341517Y204083D01*
X341892Y203792D01*
X342142Y203375D01*
X342225Y203000D01*
X340475D01*
G01X340600Y239000D02*
X340933Y239042D01*
X341225Y239208D01*
X341475Y239458D01*
X341642Y239750D01*
X341725Y240083D01*
Y240417D01*
X341642Y240750D01*
X341475Y241042D01*
X341225Y241292D01*
X340933Y241458D01*
X340600Y241500D01*
X340267Y241458D01*
X339975Y241292D01*
X339725Y241042D01*
X339558Y240750D01*
X339475Y240417D01*
Y240083D01*
X339558Y239750D01*
X339725Y239458D01*
X339975Y239208D01*
X340267Y239042D01*
X340600Y239000D01*
G01X340267Y239667D02*
X339767Y239000D01*
G01X337500D02*
Y241500D01*
X338000Y241000D01*
G01Y239000D02*
X337000D01*
G01X335192Y241083D02*
X334942Y241333D01*
X334650Y241458D01*
X334317Y241500D01*
X333900Y241417D01*
X333608Y241208D01*
X333525Y240958D01*
X333567Y240708D01*
X333733Y240500D01*
X334567Y240083D01*
X334942Y239792D01*
X335192Y239375D01*
X335275Y239000D01*
X333525D01*
G01X338500Y253017D02*
X341000D01*
Y254058D01*
X340875Y254392D01*
X340708Y254600D01*
X340375Y254683D01*
X340042Y254600D01*
X339833Y254350D01*
X339708Y254058D01*
Y253017D01*
G01Y254058D02*
X338500Y254683D01*
G01X340583Y256158D02*
X340833Y256408D01*
X340958Y256700D01*
X341000Y257033D01*
X340917Y257450D01*
X340708Y257742D01*
X340458Y257825D01*
X340208Y257783D01*
X340000Y257617D01*
X339583Y256783D01*
X339292Y256408D01*
X338875Y256158D01*
X338500Y256075D01*
Y257825D01*
G01Y259967D02*
X339042Y260050D01*
X339500Y260175D01*
X339917Y260342D01*
X340375Y260550D01*
X341000Y260883D01*
Y259217D01*
G01X339542Y262358D02*
X339833Y262650D01*
X340000Y262900D01*
X340083Y263233D01*
X340000Y263525D01*
X339833Y263733D01*
X339583Y263900D01*
X339292Y263942D01*
X339042Y263900D01*
X338792Y263733D01*
X338583Y263483D01*
X338500Y263192D01*
X338583Y262858D01*
X338833Y262567D01*
X339208Y262400D01*
X339625Y262358D01*
X340167Y262442D01*
X340458Y262567D01*
X340750Y262775D01*
X340958Y263067D01*
X341000Y263358D01*
X340917Y263650D01*
X340708Y263858D01*
G01X348983Y276000D02*
Y278500D01*
X347983D01*
X347650Y278375D01*
X347400Y278083D01*
X347317Y277750D01*
X347400Y277417D01*
X347608Y277167D01*
X347983Y277042D01*
X348983D01*
G01X345883Y276000D02*
Y278500D01*
X344842D01*
X344508Y278375D01*
X344300Y278208D01*
X344217Y277875D01*
X344300Y277542D01*
X344550Y277333D01*
X344842Y277208D01*
X345883D01*
G01X344842D02*
X344217Y276000D01*
G01X342867Y276500D02*
X342617Y276208D01*
X342283Y276042D01*
X341908Y276000D01*
X341575Y276042D01*
X341242Y276250D01*
X341033Y276500D01*
X340992Y276750D01*
X341075Y277042D01*
X341367Y277250D01*
X341658Y277333D01*
X342033D01*
G01X341658D02*
X341408Y277458D01*
X341200Y277667D01*
X341117Y277917D01*
X341200Y278167D01*
X341408Y278375D01*
X341783Y278500D01*
X342158Y278458D01*
X342533Y278292D01*
G01X338850Y276000D02*
Y278500D01*
X339350Y278000D01*
G01Y276000D02*
X338350D01*
G01X366983Y41500D02*
Y44000D01*
X365942D01*
X365608Y43875D01*
X365400Y43708D01*
X365317Y43375D01*
X365400Y43042D01*
X365650Y42833D01*
X365942Y42708D01*
X366983D01*
G01X365942D02*
X365317Y41500D01*
G01X363967Y42000D02*
X363717Y41708D01*
X363383Y41542D01*
X363008Y41500D01*
X362675Y41542D01*
X362342Y41750D01*
X362133Y42000D01*
X362092Y42250D01*
X362175Y42542D01*
X362467Y42750D01*
X362758Y42833D01*
X363133D01*
G01X362758D02*
X362508Y42958D01*
X362300Y43167D01*
X362217Y43417D01*
X362300Y43667D01*
X362508Y43875D01*
X362883Y44000D01*
X363258Y43958D01*
X363633Y43792D01*
G01X359450Y41500D02*
Y44000D01*
X360992Y42208D01*
X358908D01*
G01X356850Y44000D02*
X357183Y43917D01*
X357433Y43708D01*
X357600Y43458D01*
X357725Y43125D01*
X357767Y42750D01*
X357725Y42375D01*
X357600Y42042D01*
X357433Y41792D01*
X357183Y41583D01*
X356850Y41500D01*
X356517Y41583D01*
X356267Y41792D01*
X356100Y42042D01*
X355975Y42375D01*
X355933Y42750D01*
X355975Y43125D01*
X356100Y43458D01*
X356267Y43708D01*
X356517Y43917D01*
X356850Y44000D01*
G01X357500Y77167D02*
X353500D01*
X357500Y72500D01*
X353500D01*
G01X375000Y64000D02*
X365000D01*
Y68500D01*
X351500D01*
Y68000D01*
G01X343650Y74500D02*
X349350D01*
G01X343650Y71500D02*
Y74500D01*
G01X349350Y71500D02*
X343650D01*
G01X349350Y74500D02*
Y71500D01*
G01X363233Y86459D02*
X363483Y86584D01*
X363775Y86667D01*
X364108D01*
X364483Y86542D01*
X364775Y86334D01*
X364983Y86084D01*
X365150Y85667D01*
X365192Y85292D01*
X365108Y84917D01*
X364983Y84667D01*
X364733Y84417D01*
X364442Y84250D01*
X364150Y84167D01*
X363858D01*
X363567Y84250D01*
X363317Y84375D01*
X363108Y84542D01*
G01X361842Y86250D02*
X361592Y86500D01*
X361300Y86625D01*
X360967Y86667D01*
X360550Y86584D01*
X360258Y86375D01*
X360175Y86125D01*
X360217Y85875D01*
X360383Y85667D01*
X361217Y85250D01*
X361592Y84959D01*
X361842Y84542D01*
X361925Y84167D01*
X360175D01*
G01X358867Y84542D02*
X358617Y84334D01*
X358325Y84209D01*
X357950Y84167D01*
X357575Y84250D01*
X357283Y84417D01*
X357075Y84709D01*
X357033Y85042D01*
X357117Y85375D01*
X357325Y85584D01*
X357617Y85750D01*
X357908Y85792D01*
X358200Y85750D01*
X358575Y85584D01*
X358450Y86667D01*
X357325D01*
G01X354350Y84167D02*
Y86667D01*
X355892Y84875D01*
X353808D01*
G01X363233Y90459D02*
X363483Y90584D01*
X363775Y90667D01*
X364108D01*
X364483Y90542D01*
X364775Y90334D01*
X364983Y90084D01*
X365150Y89667D01*
X365192Y89292D01*
X365108Y88917D01*
X364983Y88667D01*
X364733Y88417D01*
X364442Y88250D01*
X364150Y88167D01*
X363858D01*
X363567Y88250D01*
X363317Y88375D01*
X363108Y88542D01*
G01X361842Y90250D02*
X361592Y90500D01*
X361300Y90625D01*
X360967Y90667D01*
X360550Y90584D01*
X360258Y90375D01*
X360175Y90125D01*
X360217Y89875D01*
X360383Y89667D01*
X361217Y89250D01*
X361592Y88959D01*
X361842Y88542D01*
X361925Y88167D01*
X360175D01*
G01X358867Y88542D02*
X358617Y88334D01*
X358325Y88209D01*
X357950Y88167D01*
X357575Y88250D01*
X357283Y88417D01*
X357075Y88709D01*
X357033Y89042D01*
X357117Y89375D01*
X357325Y89584D01*
X357617Y89750D01*
X357908Y89792D01*
X358200Y89750D01*
X358575Y89584D01*
X358450Y90667D01*
X357325D01*
G01X354850Y88167D02*
Y90667D01*
X355350Y90167D01*
G01Y88167D02*
X354350D01*
G01X349000Y108500D02*
X355000D01*
Y100500D01*
G01X363233Y98459D02*
X363483Y98584D01*
X363775Y98667D01*
X364108D01*
X364483Y98542D01*
X364775Y98334D01*
X364983Y98084D01*
X365150Y97667D01*
X365192Y97292D01*
X365108Y96917D01*
X364983Y96667D01*
X364733Y96417D01*
X364442Y96250D01*
X364150Y96167D01*
X363858D01*
X363567Y96250D01*
X363317Y96375D01*
X363108Y96542D01*
G01X361842Y98250D02*
X361592Y98500D01*
X361300Y98625D01*
X360967Y98667D01*
X360550Y98584D01*
X360258Y98375D01*
X360175Y98125D01*
X360217Y97875D01*
X360383Y97667D01*
X361217Y97250D01*
X361592Y96959D01*
X361842Y96542D01*
X361925Y96167D01*
X360175D01*
G01X358867Y96542D02*
X358617Y96334D01*
X358325Y96209D01*
X357950Y96167D01*
X357575Y96250D01*
X357283Y96417D01*
X357075Y96709D01*
X357033Y97042D01*
X357117Y97375D01*
X357325Y97584D01*
X357617Y97750D01*
X357908Y97792D01*
X358200Y97750D01*
X358575Y97584D01*
X358450Y98667D01*
X357325D01*
G01X355558Y96459D02*
X355267Y96250D01*
X354933Y96167D01*
X354600Y96250D01*
X354308Y96500D01*
X354100Y96875D01*
X354017Y97250D01*
Y97709D01*
X354100Y98084D01*
X354308Y98417D01*
X354558Y98584D01*
X354850Y98667D01*
X355183Y98584D01*
X355433Y98417D01*
X355600Y98167D01*
X355683Y97834D01*
X355600Y97542D01*
X355392Y97250D01*
X355142Y97084D01*
X354850Y97042D01*
X354517Y97125D01*
X354267Y97334D01*
X354017Y97709D01*
G01X363233Y94459D02*
X363483Y94584D01*
X363775Y94667D01*
X364108D01*
X364483Y94542D01*
X364775Y94334D01*
X364983Y94084D01*
X365150Y93667D01*
X365192Y93292D01*
X365108Y92917D01*
X364983Y92667D01*
X364733Y92417D01*
X364442Y92250D01*
X364150Y92167D01*
X363858D01*
X363567Y92250D01*
X363317Y92375D01*
X363108Y92542D01*
G01X361842Y94250D02*
X361592Y94500D01*
X361300Y94625D01*
X360967Y94667D01*
X360550Y94584D01*
X360258Y94375D01*
X360175Y94125D01*
X360217Y93875D01*
X360383Y93667D01*
X361217Y93250D01*
X361592Y92959D01*
X361842Y92542D01*
X361925Y92167D01*
X360175D01*
G01X358742Y93209D02*
X358450Y93500D01*
X358200Y93667D01*
X357867Y93750D01*
X357575Y93667D01*
X357367Y93500D01*
X357200Y93250D01*
X357158Y92959D01*
X357200Y92709D01*
X357367Y92459D01*
X357617Y92250D01*
X357908Y92167D01*
X358242Y92250D01*
X358533Y92500D01*
X358700Y92875D01*
X358742Y93292D01*
X358658Y93834D01*
X358533Y94125D01*
X358325Y94417D01*
X358033Y94625D01*
X357742Y94667D01*
X357450Y94584D01*
X357242Y94375D01*
G01X354850Y92167D02*
Y94667D01*
X355350Y94167D01*
G01Y92167D02*
X354350D01*
G01X346500Y111017D02*
X349000D01*
Y112058D01*
X348875Y112392D01*
X348708Y112600D01*
X348375Y112683D01*
X348042Y112600D01*
X347833Y112350D01*
X347708Y112058D01*
Y111017D01*
G01Y112058D02*
X346500Y112683D01*
G01X347000Y114033D02*
X346708Y114283D01*
X346542Y114617D01*
X346500Y114992D01*
X346542Y115325D01*
X346750Y115658D01*
X347000Y115867D01*
X347250Y115908D01*
X347542Y115825D01*
X347750Y115533D01*
X347833Y115242D01*
Y114867D01*
G01Y115242D02*
X347958Y115492D01*
X348167Y115700D01*
X348417Y115783D01*
X348667Y115700D01*
X348875Y115492D01*
X349000Y115117D01*
X348958Y114742D01*
X348792Y114367D01*
G01X347542Y117258D02*
X347833Y117550D01*
X348000Y117800D01*
X348083Y118133D01*
X348000Y118425D01*
X347833Y118633D01*
X347583Y118800D01*
X347292Y118842D01*
X347042Y118800D01*
X346792Y118633D01*
X346583Y118383D01*
X346500Y118092D01*
X346583Y117758D01*
X346833Y117467D01*
X347208Y117300D01*
X347625Y117258D01*
X348167Y117342D01*
X348458Y117467D01*
X348750Y117675D01*
X348958Y117967D01*
X349000Y118258D01*
X348917Y118550D01*
X348708Y118758D01*
G01X347542Y120358D02*
X347833Y120650D01*
X348000Y120900D01*
X348083Y121233D01*
X348000Y121525D01*
X347833Y121733D01*
X347583Y121900D01*
X347292Y121942D01*
X347042Y121900D01*
X346792Y121733D01*
X346583Y121483D01*
X346500Y121192D01*
X346583Y120858D01*
X346833Y120567D01*
X347208Y120400D01*
X347625Y120358D01*
X348167Y120442D01*
X348458Y120567D01*
X348750Y120775D01*
X348958Y121067D01*
X349000Y121358D01*
X348917Y121650D01*
X348708Y121858D01*
G01X364733Y115292D02*
X364983Y115417D01*
X365275Y115500D01*
X365608D01*
X365983Y115375D01*
X366275Y115167D01*
X366483Y114917D01*
X366650Y114500D01*
X366692Y114125D01*
X366608Y113750D01*
X366483Y113500D01*
X366233Y113250D01*
X365942Y113083D01*
X365650Y113000D01*
X365358D01*
X365067Y113083D01*
X364817Y113208D01*
X364608Y113375D01*
G01X363342Y115083D02*
X363092Y115333D01*
X362800Y115458D01*
X362467Y115500D01*
X362050Y115417D01*
X361758Y115208D01*
X361675Y114958D01*
X361717Y114708D01*
X361883Y114500D01*
X362717Y114083D01*
X363092Y113792D01*
X363342Y113375D01*
X363425Y113000D01*
X361675D01*
G01X360242Y115083D02*
X359992Y115333D01*
X359700Y115458D01*
X359367Y115500D01*
X358950Y115417D01*
X358658Y115208D01*
X358575Y114958D01*
X358617Y114708D01*
X358783Y114500D01*
X359617Y114083D01*
X359992Y113792D01*
X360242Y113375D01*
X360325Y113000D01*
X358575D01*
G01X357058Y113292D02*
X356767Y113083D01*
X356433Y113000D01*
X356100Y113083D01*
X355808Y113333D01*
X355600Y113708D01*
X355517Y114083D01*
Y114542D01*
X355600Y114917D01*
X355808Y115250D01*
X356058Y115417D01*
X356350Y115500D01*
X356683Y115417D01*
X356933Y115250D01*
X357100Y115000D01*
X357183Y114667D01*
X357100Y114375D01*
X356892Y114083D01*
X356642Y113917D01*
X356350Y113875D01*
X356017Y113958D01*
X355767Y114167D01*
X355517Y114542D01*
G01X367500Y128000D02*
Y126000D01*
X348500D01*
Y127500D01*
X346000D01*
Y134000D01*
X342500D01*
Y141500D01*
X350000D01*
G01X351000Y157500D02*
Y137500D01*
X358000D01*
G01X349500Y169500D02*
X352500D01*
Y161500D01*
X354000D01*
G01X350500Y178000D02*
X347000D01*
Y171000D01*
G01X362733Y187792D02*
X362983Y187917D01*
X363275Y188000D01*
X363608D01*
X363983Y187875D01*
X364275Y187667D01*
X364483Y187417D01*
X364650Y187000D01*
X364692Y186625D01*
X364608Y186250D01*
X364483Y186000D01*
X364233Y185750D01*
X363942Y185583D01*
X363650Y185500D01*
X363358D01*
X363067Y185583D01*
X362817Y185708D01*
X362608Y185875D01*
G01X360550Y185500D02*
Y188000D01*
X361050Y187500D01*
G01Y185500D02*
X360050D01*
G01X356950D02*
Y188000D01*
X358492Y186208D01*
X356408D01*
G01X354433Y185500D02*
X354350Y186042D01*
X354225Y186500D01*
X354058Y186917D01*
X353850Y187375D01*
X353517Y188000D01*
X355183D01*
G01X358792Y191267D02*
X358917Y191017D01*
X359000Y190725D01*
Y190392D01*
X358875Y190017D01*
X358667Y189725D01*
X358417Y189517D01*
X358000Y189350D01*
X357625Y189308D01*
X357250Y189392D01*
X357000Y189517D01*
X356750Y189767D01*
X356583Y190058D01*
X356500Y190350D01*
Y190642D01*
X356583Y190933D01*
X356708Y191183D01*
X356875Y191392D01*
G01X356500Y193450D02*
X359000D01*
X358500Y192950D01*
G01X356500D02*
Y193950D01*
G01Y197050D02*
X359000D01*
X357208Y195508D01*
Y197592D01*
G01X356875Y198733D02*
X356667Y198983D01*
X356542Y199275D01*
X356500Y199650D01*
X356583Y200025D01*
X356750Y200317D01*
X357042Y200525D01*
X357375Y200567D01*
X357708Y200483D01*
X357917Y200275D01*
X358083Y199983D01*
X358125Y199692D01*
X358083Y199400D01*
X357917Y199025D01*
X359000Y199150D01*
Y200275D01*
G01X355292Y191267D02*
X355417Y191017D01*
X355500Y190725D01*
Y190392D01*
X355375Y190017D01*
X355167Y189725D01*
X354917Y189517D01*
X354500Y189350D01*
X354125Y189308D01*
X353750Y189392D01*
X353500Y189517D01*
X353250Y189767D01*
X353083Y190058D01*
X353000Y190350D01*
Y190642D01*
X353083Y190933D01*
X353208Y191183D01*
X353375Y191392D01*
G01X353000Y193450D02*
X355500D01*
X355000Y192950D01*
G01X353000D02*
Y193950D01*
G01X353500Y195633D02*
X353208Y195883D01*
X353042Y196217D01*
X353000Y196592D01*
X353042Y196925D01*
X353250Y197258D01*
X353500Y197467D01*
X353750Y197508D01*
X354042Y197425D01*
X354250Y197133D01*
X354333Y196842D01*
Y196467D01*
G01Y196842D02*
X354458Y197092D01*
X354667Y197300D01*
X354917Y197383D01*
X355167Y197300D01*
X355375Y197092D01*
X355500Y196717D01*
X355458Y196342D01*
X355292Y195967D01*
G01X353500Y198733D02*
X353208Y198983D01*
X353042Y199317D01*
X353000Y199692D01*
X353042Y200025D01*
X353250Y200358D01*
X353500Y200567D01*
X353750Y200608D01*
X354042Y200525D01*
X354250Y200233D01*
X354333Y199942D01*
Y199567D01*
G01Y199942D02*
X354458Y200192D01*
X354667Y200400D01*
X354917Y200483D01*
X355167Y200400D01*
X355375Y200192D01*
X355500Y199817D01*
X355458Y199442D01*
X355292Y199067D01*
G01X352933Y246000D02*
Y248500D01*
X351933D01*
X351600Y248375D01*
X351350Y248083D01*
X351267Y247750D01*
X351350Y247417D01*
X351558Y247167D01*
X351933Y247042D01*
X352933D01*
G01X348083Y248292D02*
X348333Y248417D01*
X348625Y248500D01*
X348958D01*
X349333Y248375D01*
X349625Y248167D01*
X349833Y247917D01*
X350000Y247500D01*
X350042Y247125D01*
X349958Y246750D01*
X349833Y246500D01*
X349583Y246250D01*
X349292Y246083D01*
X349000Y246000D01*
X348708D01*
X348417Y246083D01*
X348167Y246208D01*
X347958Y246375D01*
G01X345983Y246000D02*
X345900Y246542D01*
X345775Y247000D01*
X345608Y247417D01*
X345400Y247875D01*
X345067Y248500D01*
X346733D01*
G01X354483Y253000D02*
Y255500D01*
X353483D01*
X353150Y255375D01*
X352900Y255083D01*
X352817Y254750D01*
X352900Y254417D01*
X353108Y254167D01*
X353483Y254042D01*
X354483D01*
G01X349633Y255292D02*
X349883Y255417D01*
X350175Y255500D01*
X350508D01*
X350883Y255375D01*
X351175Y255167D01*
X351383Y254917D01*
X351550Y254500D01*
X351592Y254125D01*
X351508Y253750D01*
X351383Y253500D01*
X351133Y253250D01*
X350842Y253083D01*
X350550Y253000D01*
X350258D01*
X349967Y253083D01*
X349717Y253208D01*
X349508Y253375D01*
G01X348242Y255083D02*
X347992Y255333D01*
X347700Y255458D01*
X347367Y255500D01*
X346950Y255417D01*
X346658Y255208D01*
X346575Y254958D01*
X346617Y254708D01*
X346783Y254500D01*
X347617Y254083D01*
X347992Y253792D01*
X348242Y253375D01*
X348325Y253000D01*
X346575D01*
G01X344350D02*
Y255500D01*
X344850Y255000D01*
G01Y253000D02*
X343850D01*
G01X346000Y272350D02*
Y266650D01*
G01X343000Y272350D02*
X346000D01*
G01X343000Y266650D02*
Y272350D01*
G01X346000Y266650D02*
X343000D01*
G01X355500Y274517D02*
X358000D01*
Y275517D01*
X357875Y275850D01*
X357583Y276100D01*
X357250Y276183D01*
X356917Y276100D01*
X356667Y275892D01*
X356542Y275517D01*
Y274517D01*
G01X357792Y279367D02*
X357917Y279117D01*
X358000Y278825D01*
Y278492D01*
X357875Y278117D01*
X357667Y277825D01*
X357417Y277617D01*
X357000Y277450D01*
X356625Y277408D01*
X356250Y277492D01*
X356000Y277617D01*
X355750Y277867D01*
X355583Y278158D01*
X355500Y278450D01*
Y278742D01*
X355583Y279033D01*
X355708Y279283D01*
X355875Y279492D01*
G01X357583Y280758D02*
X357833Y281008D01*
X357958Y281300D01*
X358000Y281633D01*
X357917Y282050D01*
X357708Y282342D01*
X357458Y282425D01*
X357208Y282383D01*
X357000Y282217D01*
X356583Y281383D01*
X356292Y281008D01*
X355875Y280758D01*
X355500Y280675D01*
Y282425D01*
G01X356542Y283858D02*
X356833Y284150D01*
X357000Y284400D01*
X357083Y284733D01*
X357000Y285025D01*
X356833Y285233D01*
X356583Y285400D01*
X356292Y285442D01*
X356042Y285400D01*
X355792Y285233D01*
X355583Y284983D01*
X355500Y284692D01*
X355583Y284358D01*
X355833Y284067D01*
X356208Y283900D01*
X356625Y283858D01*
X357167Y283942D01*
X357458Y284067D01*
X357750Y284275D01*
X357958Y284567D01*
X358000Y284858D01*
X357917Y285150D01*
X357708Y285358D01*
G01X360292Y57767D02*
X360417Y57517D01*
X360500Y57225D01*
Y56892D01*
X360375Y56517D01*
X360167Y56225D01*
X359917Y56017D01*
X359500Y55850D01*
X359125Y55808D01*
X358750Y55892D01*
X358500Y56017D01*
X358250Y56267D01*
X358083Y56558D01*
X358000Y56850D01*
Y57142D01*
X358083Y57433D01*
X358208Y57683D01*
X358375Y57892D01*
G01X360083Y59158D02*
X360333Y59408D01*
X360458Y59700D01*
X360500Y60033D01*
X360417Y60450D01*
X360208Y60742D01*
X359958Y60825D01*
X359708Y60783D01*
X359500Y60617D01*
X359083Y59783D01*
X358792Y59408D01*
X358375Y59158D01*
X358000Y59075D01*
Y60825D01*
G01X358375Y62133D02*
X358167Y62383D01*
X358042Y62675D01*
X358000Y63050D01*
X358083Y63425D01*
X358250Y63717D01*
X358542Y63925D01*
X358875Y63967D01*
X359208Y63883D01*
X359417Y63675D01*
X359583Y63383D01*
X359625Y63092D01*
X359583Y62800D01*
X359417Y62425D01*
X360500Y62550D01*
Y63675D01*
G01X358500Y65233D02*
X358208Y65483D01*
X358042Y65817D01*
X358000Y66192D01*
X358042Y66525D01*
X358250Y66858D01*
X358500Y67067D01*
X358750Y67108D01*
X359042Y67025D01*
X359250Y66733D01*
X359333Y66442D01*
Y66067D01*
G01Y66442D02*
X359458Y66692D01*
X359667Y66900D01*
X359917Y66983D01*
X360167Y66900D01*
X360375Y66692D01*
X360500Y66317D01*
X360458Y65942D01*
X360292Y65567D01*
G01X374733Y48292D02*
X374983Y48417D01*
X375275Y48500D01*
X375608D01*
X375983Y48375D01*
X376275Y48167D01*
X376483Y47917D01*
X376650Y47500D01*
X376692Y47125D01*
X376608Y46750D01*
X376483Y46500D01*
X376233Y46250D01*
X375942Y46083D01*
X375650Y46000D01*
X375358D01*
X375067Y46083D01*
X374817Y46208D01*
X374608Y46375D01*
G01X373467Y46500D02*
X373217Y46208D01*
X372883Y46042D01*
X372508Y46000D01*
X372175Y46042D01*
X371842Y46250D01*
X371633Y46500D01*
X371592Y46750D01*
X371675Y47042D01*
X371967Y47250D01*
X372258Y47333D01*
X372633D01*
G01X372258D02*
X372008Y47458D01*
X371800Y47667D01*
X371717Y47917D01*
X371800Y48167D01*
X372008Y48375D01*
X372383Y48500D01*
X372758Y48458D01*
X373133Y48292D01*
G01X370242Y48083D02*
X369992Y48333D01*
X369700Y48458D01*
X369367Y48500D01*
X368950Y48417D01*
X368658Y48208D01*
X368575Y47958D01*
X368617Y47708D01*
X368783Y47500D01*
X369617Y47083D01*
X369992Y46792D01*
X370242Y46375D01*
X370325Y46000D01*
X368575D01*
G01X366350Y48500D02*
X366683Y48417D01*
X366933Y48208D01*
X367100Y47958D01*
X367225Y47625D01*
X367267Y47250D01*
X367225Y46875D01*
X367100Y46542D01*
X366933Y46292D01*
X366683Y46083D01*
X366350Y46000D01*
X366017Y46083D01*
X365767Y46292D01*
X365600Y46542D01*
X365475Y46875D01*
X365433Y47250D01*
X365475Y47625D01*
X365600Y47958D01*
X365767Y48208D01*
X366017Y48417D01*
X366350Y48500D01*
G01X380233Y96792D02*
X380483Y96917D01*
X380775Y97000D01*
X381108D01*
X381483Y96875D01*
X381775Y96667D01*
X381983Y96417D01*
X382150Y96000D01*
X382192Y95625D01*
X382108Y95250D01*
X381983Y95000D01*
X381733Y94750D01*
X381442Y94583D01*
X381150Y94500D01*
X380858D01*
X380567Y94583D01*
X380317Y94708D01*
X380108Y94875D01*
G01X378842Y96583D02*
X378592Y96833D01*
X378300Y96958D01*
X377967Y97000D01*
X377550Y96917D01*
X377258Y96708D01*
X377175Y96458D01*
X377217Y96208D01*
X377383Y96000D01*
X378217Y95583D01*
X378592Y95292D01*
X378842Y94875D01*
X378925Y94500D01*
X377175D01*
G01X374450D02*
Y97000D01*
X375992Y95208D01*
X373908D01*
G01X372642Y95542D02*
X372350Y95833D01*
X372100Y96000D01*
X371767Y96083D01*
X371475Y96000D01*
X371267Y95833D01*
X371100Y95583D01*
X371058Y95292D01*
X371100Y95042D01*
X371267Y94792D01*
X371517Y94583D01*
X371808Y94500D01*
X372142Y94583D01*
X372433Y94833D01*
X372600Y95208D01*
X372642Y95625D01*
X372558Y96167D01*
X372433Y96458D01*
X372225Y96750D01*
X371933Y96958D01*
X371642Y97000D01*
X371350Y96917D01*
X371142Y96708D01*
G01X366233Y110792D02*
X366483Y110917D01*
X366775Y111000D01*
X367108D01*
X367483Y110875D01*
X367775Y110667D01*
X367983Y110417D01*
X368150Y110000D01*
X368192Y109625D01*
X368108Y109250D01*
X367983Y109000D01*
X367733Y108750D01*
X367442Y108583D01*
X367150Y108500D01*
X366858D01*
X366567Y108583D01*
X366317Y108708D01*
X366108Y108875D01*
G01X364842Y110583D02*
X364592Y110833D01*
X364300Y110958D01*
X363967Y111000D01*
X363550Y110917D01*
X363258Y110708D01*
X363175Y110458D01*
X363217Y110208D01*
X363383Y110000D01*
X364217Y109583D01*
X364592Y109292D01*
X364842Y108875D01*
X364925Y108500D01*
X363175D01*
G01X361742Y110583D02*
X361492Y110833D01*
X361200Y110958D01*
X360867Y111000D01*
X360450Y110917D01*
X360158Y110708D01*
X360075Y110458D01*
X360117Y110208D01*
X360283Y110000D01*
X361117Y109583D01*
X361492Y109292D01*
X361742Y108875D01*
X361825Y108500D01*
X360075D01*
G01X358767Y108875D02*
X358517Y108667D01*
X358225Y108542D01*
X357850Y108500D01*
X357475Y108583D01*
X357183Y108750D01*
X356975Y109042D01*
X356933Y109375D01*
X357017Y109708D01*
X357225Y109917D01*
X357517Y110083D01*
X357808Y110125D01*
X358100Y110083D01*
X358475Y109917D01*
X358350Y111000D01*
X357225D01*
G01X368500Y113517D02*
X371000D01*
Y114558D01*
X370875Y114892D01*
X370708Y115100D01*
X370375Y115183D01*
X370042Y115100D01*
X369833Y114850D01*
X369708Y114558D01*
Y113517D01*
G01Y114558D02*
X368500Y115183D01*
G01X369000Y116533D02*
X368708Y116783D01*
X368542Y117117D01*
X368500Y117492D01*
X368542Y117825D01*
X368750Y118158D01*
X369000Y118367D01*
X369250Y118408D01*
X369542Y118325D01*
X369750Y118033D01*
X369833Y117742D01*
Y117367D01*
G01Y117742D02*
X369958Y117992D01*
X370167Y118200D01*
X370417Y118283D01*
X370667Y118200D01*
X370875Y117992D01*
X371000Y117617D01*
X370958Y117242D01*
X370792Y116867D01*
G01X368875Y119633D02*
X368667Y119883D01*
X368542Y120175D01*
X368500Y120550D01*
X368583Y120925D01*
X368750Y121217D01*
X369042Y121425D01*
X369375Y121467D01*
X369708Y121383D01*
X369917Y121175D01*
X370083Y120883D01*
X370125Y120592D01*
X370083Y120300D01*
X369917Y119925D01*
X371000Y120050D01*
Y121175D01*
G01Y123650D02*
X370917Y123317D01*
X370708Y123067D01*
X370458Y122900D01*
X370125Y122775D01*
X369750Y122733D01*
X369375Y122775D01*
X369042Y122900D01*
X368792Y123067D01*
X368583Y123317D01*
X368500Y123650D01*
X368583Y123983D01*
X368792Y124233D01*
X369042Y124400D01*
X369375Y124525D01*
X369750Y124567D01*
X370125Y124525D01*
X370458Y124400D01*
X370708Y124233D01*
X370917Y123983D01*
X371000Y123650D01*
G01X364200Y140500D02*
X361533D01*
Y138400D01*
X362333Y137700D01*
X363267Y137233D01*
X364600Y137000D01*
X365933Y137233D01*
X366867Y137700D01*
X367667Y138400D01*
X368200Y139217D01*
X368467Y140150D01*
Y140967D01*
X368200Y141667D01*
X367667Y142483D01*
X366867Y143183D01*
X366067Y143650D01*
X365000Y144000D01*
X364067D01*
X363000Y143767D01*
X362200Y143300D01*
G01X364000Y135000D02*
X367500D01*
G01X368000Y149500D02*
X381000D01*
Y154500D01*
X382000D01*
G01X372500Y168500D02*
X365500D01*
Y177500D01*
X361500D01*
G01X361000Y196000D02*
Y190500D01*
X368000D01*
Y194500D01*
X380000D01*
Y182500D01*
X373000D01*
G01X368792Y213367D02*
X368917Y213117D01*
X369000Y212825D01*
Y212492D01*
X368875Y212117D01*
X368667Y211825D01*
X368417Y211617D01*
X368000Y211450D01*
X367625Y211408D01*
X367250Y211492D01*
X367000Y211617D01*
X366750Y211867D01*
X366583Y212158D01*
X366500Y212450D01*
Y212742D01*
X366583Y213033D01*
X366708Y213283D01*
X366875Y213492D01*
G01X366500Y215550D02*
X369000D01*
X368500Y215050D01*
G01X366500D02*
Y216050D01*
G01Y218650D02*
X369000D01*
X368500Y218150D01*
G01X366500D02*
Y219150D01*
G01X366792Y221042D02*
X366583Y221333D01*
X366500Y221667D01*
X366583Y222000D01*
X366833Y222292D01*
X367208Y222500D01*
X367583Y222583D01*
X368042D01*
X368417Y222500D01*
X368750Y222292D01*
X368917Y222042D01*
X369000Y221750D01*
X368917Y221417D01*
X368750Y221167D01*
X368500Y221000D01*
X368167Y220917D01*
X367875Y221000D01*
X367583Y221208D01*
X367417Y221458D01*
X367375Y221750D01*
X367458Y222083D01*
X367667Y222333D01*
X368042Y222583D01*
G01X365000Y211617D02*
X362500D01*
Y213283D01*
G01X362875Y214633D02*
X362667Y214883D01*
X362542Y215175D01*
X362500Y215550D01*
X362583Y215925D01*
X362750Y216217D01*
X363042Y216425D01*
X363375Y216467D01*
X363708Y216383D01*
X363917Y216175D01*
X364083Y215883D01*
X364125Y215592D01*
X364083Y215300D01*
X363917Y214925D01*
X365000Y215050D01*
Y216175D01*
G01X372792Y213367D02*
X372917Y213117D01*
X373000Y212825D01*
Y212492D01*
X372875Y212117D01*
X372667Y211825D01*
X372417Y211617D01*
X372000Y211450D01*
X371625Y211408D01*
X371250Y211492D01*
X371000Y211617D01*
X370750Y211867D01*
X370583Y212158D01*
X370500Y212450D01*
Y212742D01*
X370583Y213033D01*
X370708Y213283D01*
X370875Y213492D01*
G01X370500Y215550D02*
X373000D01*
X372500Y215050D01*
G01X370500D02*
Y216050D01*
G01Y218650D02*
X373000D01*
X372500Y218150D01*
G01X370500D02*
Y219150D01*
G01Y221667D02*
X371042Y221750D01*
X371500Y221875D01*
X371917Y222042D01*
X372375Y222250D01*
X373000Y222583D01*
Y220917D01*
G01X363000Y274517D02*
X365500D01*
Y275517D01*
X365375Y275850D01*
X365083Y276100D01*
X364750Y276183D01*
X364417Y276100D01*
X364167Y275892D01*
X364042Y275517D01*
Y274517D01*
G01X365292Y279367D02*
X365417Y279117D01*
X365500Y278825D01*
Y278492D01*
X365375Y278117D01*
X365167Y277825D01*
X364917Y277617D01*
X364500Y277450D01*
X364125Y277408D01*
X363750Y277492D01*
X363500Y277617D01*
X363250Y277867D01*
X363083Y278158D01*
X363000Y278450D01*
Y278742D01*
X363083Y279033D01*
X363208Y279283D01*
X363375Y279492D01*
G01X363000Y281550D02*
X365500D01*
X365000Y281050D01*
G01X363000D02*
Y282050D01*
G01X363292Y283942D02*
X363083Y284233D01*
X363000Y284567D01*
X363083Y284900D01*
X363333Y285192D01*
X363708Y285400D01*
X364083Y285483D01*
X364542D01*
X364917Y285400D01*
X365250Y285192D01*
X365417Y284942D01*
X365500Y284650D01*
X365417Y284317D01*
X365250Y284067D01*
X365000Y283900D01*
X364667Y283817D01*
X364375Y283900D01*
X364083Y284108D01*
X363917Y284358D01*
X363875Y284650D01*
X363958Y284983D01*
X364167Y285233D01*
X364542Y285483D01*
G01X389292Y50267D02*
X389417Y50017D01*
X389500Y49725D01*
Y49392D01*
X389375Y49017D01*
X389167Y48725D01*
X388917Y48517D01*
X388500Y48350D01*
X388125Y48308D01*
X387750Y48392D01*
X387500Y48517D01*
X387250Y48767D01*
X387083Y49058D01*
X387000Y49350D01*
Y49642D01*
X387083Y49933D01*
X387208Y50183D01*
X387375Y50392D01*
G01X387500Y51533D02*
X387208Y51783D01*
X387042Y52117D01*
X387000Y52492D01*
X387042Y52825D01*
X387250Y53158D01*
X387500Y53367D01*
X387750Y53408D01*
X388042Y53325D01*
X388250Y53033D01*
X388333Y52742D01*
Y52367D01*
G01Y52742D02*
X388458Y52992D01*
X388667Y53200D01*
X388917Y53283D01*
X389167Y53200D01*
X389375Y52992D01*
X389500Y52617D01*
X389458Y52242D01*
X389292Y51867D01*
G01X387000Y55550D02*
X389500D01*
X389000Y55050D01*
G01X387000D02*
Y56050D01*
G01Y58650D02*
X387042Y58942D01*
X387167Y59275D01*
X387375Y59483D01*
X387667Y59567D01*
X387958Y59483D01*
X388208Y59233D01*
X388333Y58858D01*
Y58442D01*
X388417Y58192D01*
X388625Y57983D01*
X388917Y57900D01*
X389208Y58025D01*
X389417Y58317D01*
X389500Y58650D01*
X389417Y58983D01*
X389208Y59275D01*
X388917Y59400D01*
X388625Y59317D01*
X388417Y59108D01*
X388333Y58858D01*
Y58442D01*
X388208Y58067D01*
X387958Y57817D01*
X387667Y57733D01*
X387375Y57817D01*
X387167Y58025D01*
X387042Y58358D01*
X387000Y58650D01*
G01X388292Y69267D02*
X388417Y69017D01*
X388500Y68725D01*
Y68392D01*
X388375Y68017D01*
X388167Y67725D01*
X387917Y67517D01*
X387500Y67350D01*
X387125Y67308D01*
X386750Y67392D01*
X386500Y67517D01*
X386250Y67767D01*
X386083Y68058D01*
X386000Y68350D01*
Y68642D01*
X386083Y68933D01*
X386208Y69183D01*
X386375Y69392D01*
G01X388083Y70658D02*
X388333Y70908D01*
X388458Y71200D01*
X388500Y71533D01*
X388417Y71950D01*
X388208Y72242D01*
X387958Y72325D01*
X387708Y72283D01*
X387500Y72117D01*
X387083Y71283D01*
X386792Y70908D01*
X386375Y70658D01*
X386000Y70575D01*
Y72325D01*
G01X386375Y73633D02*
X386167Y73883D01*
X386042Y74175D01*
X386000Y74550D01*
X386083Y74925D01*
X386250Y75217D01*
X386542Y75425D01*
X386875Y75467D01*
X387208Y75383D01*
X387417Y75175D01*
X387583Y74883D01*
X387625Y74592D01*
X387583Y74300D01*
X387417Y73925D01*
X388500Y74050D01*
Y75175D01*
G01X386000Y77567D02*
X386542Y77650D01*
X387000Y77775D01*
X387417Y77942D01*
X387875Y78150D01*
X388500Y78483D01*
Y76817D01*
G01X389983Y84667D02*
Y87167D01*
X388942D01*
X388608Y87042D01*
X388400Y86875D01*
X388317Y86542D01*
X388400Y86209D01*
X388650Y86000D01*
X388942Y85875D01*
X389983D01*
G01X388942D02*
X388317Y84667D01*
G01X386967Y85167D02*
X386717Y84875D01*
X386383Y84709D01*
X386008Y84667D01*
X385675Y84709D01*
X385342Y84917D01*
X385133Y85167D01*
X385092Y85417D01*
X385175Y85709D01*
X385467Y85917D01*
X385758Y86000D01*
X386133D01*
G01X385758D02*
X385508Y86125D01*
X385300Y86334D01*
X385217Y86584D01*
X385300Y86834D01*
X385508Y87042D01*
X385883Y87167D01*
X386258Y87125D01*
X386633Y86959D01*
G01X382950Y84667D02*
X382658Y84709D01*
X382325Y84834D01*
X382117Y85042D01*
X382033Y85334D01*
X382117Y85625D01*
X382367Y85875D01*
X382742Y86000D01*
X383158D01*
X383408Y86084D01*
X383617Y86292D01*
X383700Y86584D01*
X383575Y86875D01*
X383283Y87084D01*
X382950Y87167D01*
X382617Y87084D01*
X382325Y86875D01*
X382200Y86584D01*
X382283Y86292D01*
X382492Y86084D01*
X382742Y86000D01*
X383158D01*
X383533Y85875D01*
X383783Y85625D01*
X383867Y85334D01*
X383783Y85042D01*
X383575Y84834D01*
X383242Y84709D01*
X382950Y84667D01*
G01X379850D02*
Y87167D01*
X380350Y86667D01*
G01Y84667D02*
X379350D01*
G01X381733Y101292D02*
X381983Y101417D01*
X382275Y101500D01*
X382608D01*
X382983Y101375D01*
X383275Y101167D01*
X383483Y100917D01*
X383650Y100500D01*
X383692Y100125D01*
X383608Y99750D01*
X383483Y99500D01*
X383233Y99250D01*
X382942Y99083D01*
X382650Y99000D01*
X382358D01*
X382067Y99083D01*
X381817Y99208D01*
X381608Y99375D01*
G01X380342Y101083D02*
X380092Y101333D01*
X379800Y101458D01*
X379467Y101500D01*
X379050Y101417D01*
X378758Y101208D01*
X378675Y100958D01*
X378717Y100708D01*
X378883Y100500D01*
X379717Y100083D01*
X380092Y99792D01*
X380342Y99375D01*
X380425Y99000D01*
X378675D01*
G01X375950D02*
Y101500D01*
X377492Y99708D01*
X375408D01*
G01X374267Y99375D02*
X374017Y99167D01*
X373725Y99042D01*
X373350Y99000D01*
X372975Y99083D01*
X372683Y99250D01*
X372475Y99542D01*
X372433Y99875D01*
X372517Y100208D01*
X372725Y100417D01*
X373017Y100583D01*
X373308Y100625D01*
X373600Y100583D01*
X373975Y100417D01*
X373850Y101500D01*
X372725D01*
G01X381733Y105792D02*
X381983Y105917D01*
X382275Y106000D01*
X382608D01*
X382983Y105875D01*
X383275Y105667D01*
X383483Y105417D01*
X383650Y105000D01*
X383692Y104625D01*
X383608Y104250D01*
X383483Y104000D01*
X383233Y103750D01*
X382942Y103583D01*
X382650Y103500D01*
X382358D01*
X382067Y103583D01*
X381817Y103708D01*
X381608Y103875D01*
G01X380342Y105583D02*
X380092Y105833D01*
X379800Y105958D01*
X379467Y106000D01*
X379050Y105917D01*
X378758Y105708D01*
X378675Y105458D01*
X378717Y105208D01*
X378883Y105000D01*
X379717Y104583D01*
X380092Y104292D01*
X380342Y103875D01*
X380425Y103500D01*
X378675D01*
G01X377242Y105583D02*
X376992Y105833D01*
X376700Y105958D01*
X376367Y106000D01*
X375950Y105917D01*
X375658Y105708D01*
X375575Y105458D01*
X375617Y105208D01*
X375783Y105000D01*
X376617Y104583D01*
X376992Y104292D01*
X377242Y103875D01*
X377325Y103500D01*
X375575D01*
G01X374142Y104542D02*
X373850Y104833D01*
X373600Y105000D01*
X373267Y105083D01*
X372975Y105000D01*
X372767Y104833D01*
X372600Y104583D01*
X372558Y104292D01*
X372600Y104042D01*
X372767Y103792D01*
X373017Y103583D01*
X373308Y103500D01*
X373642Y103583D01*
X373933Y103833D01*
X374100Y104208D01*
X374142Y104625D01*
X374058Y105167D01*
X373933Y105458D01*
X373725Y105750D01*
X373433Y105958D01*
X373142Y106000D01*
X372850Y105917D01*
X372642Y105708D01*
G01X389150Y122500D02*
Y120000D01*
G01X390108Y122500D02*
X388192D01*
G01X386883Y120000D02*
Y122500D01*
X385883D01*
X385550Y122375D01*
X385300Y122083D01*
X385217Y121750D01*
X385300Y121417D01*
X385508Y121167D01*
X385883Y121042D01*
X386883D01*
G01X382450Y120000D02*
Y122500D01*
X383992Y120708D01*
X381908D01*
G01X379933Y120000D02*
X379850Y120542D01*
X379725Y121000D01*
X379558Y121417D01*
X379350Y121875D01*
X379017Y122500D01*
X380683D01*
G01X389150Y118500D02*
Y116000D01*
G01X390108Y118500D02*
X388192D01*
G01X386883Y116000D02*
Y118500D01*
X385883D01*
X385550Y118375D01*
X385300Y118083D01*
X385217Y117750D01*
X385300Y117417D01*
X385508Y117167D01*
X385883Y117042D01*
X386883D01*
G01X382450Y116000D02*
Y118500D01*
X383992Y116708D01*
X381908D01*
G01X379850Y116000D02*
X379558Y116042D01*
X379225Y116167D01*
X379017Y116375D01*
X378933Y116667D01*
X379017Y116958D01*
X379267Y117208D01*
X379642Y117333D01*
X380058D01*
X380308Y117417D01*
X380517Y117625D01*
X380600Y117917D01*
X380475Y118208D01*
X380183Y118417D01*
X379850Y118500D01*
X379517Y118417D01*
X379225Y118208D01*
X379100Y117917D01*
X379183Y117625D01*
X379392Y117417D01*
X379642Y117333D01*
X380058D01*
X380433Y117208D01*
X380683Y116958D01*
X380767Y116667D01*
X380683Y116375D01*
X380475Y116167D01*
X380142Y116042D01*
X379850Y116000D01*
G01X389150Y114500D02*
Y112000D01*
G01X390108Y114500D02*
X388192D01*
G01X386883Y112000D02*
Y114500D01*
X385883D01*
X385550Y114375D01*
X385300Y114083D01*
X385217Y113750D01*
X385300Y113417D01*
X385508Y113167D01*
X385883Y113042D01*
X386883D01*
G01X383867Y112375D02*
X383617Y112167D01*
X383325Y112042D01*
X382950Y112000D01*
X382575Y112083D01*
X382283Y112250D01*
X382075Y112542D01*
X382033Y112875D01*
X382117Y113208D01*
X382325Y113417D01*
X382617Y113583D01*
X382908Y113625D01*
X383200Y113583D01*
X383575Y113417D01*
X383450Y114500D01*
X382325D01*
G01X379850Y112000D02*
Y114500D01*
X380350Y114000D01*
G01Y112000D02*
X379350D01*
G01X389150Y110500D02*
Y108000D01*
G01X390108Y110500D02*
X388192D01*
G01X386883Y108000D02*
Y110500D01*
X385883D01*
X385550Y110375D01*
X385300Y110083D01*
X385217Y109750D01*
X385300Y109417D01*
X385508Y109167D01*
X385883Y109042D01*
X386883D01*
G01X383867Y108375D02*
X383617Y108167D01*
X383325Y108042D01*
X382950Y108000D01*
X382575Y108083D01*
X382283Y108250D01*
X382075Y108542D01*
X382033Y108875D01*
X382117Y109208D01*
X382325Y109417D01*
X382617Y109583D01*
X382908Y109625D01*
X383200Y109583D01*
X383575Y109417D01*
X383450Y110500D01*
X382325D01*
G01X380642Y110083D02*
X380392Y110333D01*
X380100Y110458D01*
X379767Y110500D01*
X379350Y110417D01*
X379058Y110208D01*
X378975Y109958D01*
X379017Y109708D01*
X379183Y109500D01*
X380017Y109083D01*
X380392Y108792D01*
X380642Y108375D01*
X380725Y108000D01*
X378975D01*
G01X387967Y128000D02*
Y135000D01*
X384500Y129167D01*
X381033Y135000D01*
Y128000D01*
G01X379500Y128500D02*
Y126000D01*
X389500D01*
Y137000D01*
X386000D01*
Y143500D01*
X391500D01*
Y160000D01*
X392500D01*
Y173500D01*
X386000D01*
G01X383292Y168767D02*
X383417Y168517D01*
X383500Y168225D01*
Y167892D01*
X383375Y167517D01*
X383167Y167225D01*
X382917Y167017D01*
X382500Y166850D01*
X382125Y166808D01*
X381750Y166892D01*
X381500Y167017D01*
X381250Y167267D01*
X381083Y167558D01*
X381000Y167850D01*
Y168142D01*
X381083Y168433D01*
X381208Y168683D01*
X381375Y168892D01*
G01X381000Y170950D02*
X383500D01*
X383000Y170450D01*
G01X381000D02*
Y171450D01*
G01X383083Y173258D02*
X383333Y173508D01*
X383458Y173800D01*
X383500Y174133D01*
X383417Y174550D01*
X383208Y174842D01*
X382958Y174925D01*
X382708Y174883D01*
X382500Y174717D01*
X382083Y173883D01*
X381792Y173508D01*
X381375Y173258D01*
X381000Y173175D01*
Y174925D01*
G01Y177650D02*
X383500D01*
X381708Y176108D01*
Y178192D01*
G01X385500Y167000D02*
Y164500D01*
G01X387500Y154500D02*
Y164500D01*
X380000D01*
G01X377383Y181600D02*
Y179100D01*
X375717D01*
G01X374242Y180142D02*
X373950Y180433D01*
X373700Y180600D01*
X373367Y180683D01*
X373075Y180600D01*
X372867Y180433D01*
X372700Y180183D01*
X372658Y179892D01*
X372700Y179642D01*
X372867Y179392D01*
X373117Y179183D01*
X373408Y179100D01*
X373742Y179183D01*
X374033Y179433D01*
X374200Y179808D01*
X374242Y180225D01*
X374158Y180767D01*
X374033Y181058D01*
X373825Y181350D01*
X373533Y181558D01*
X373242Y181600D01*
X372950Y181517D01*
X372742Y181308D01*
G01X376792Y213367D02*
X376917Y213117D01*
X377000Y212825D01*
Y212492D01*
X376875Y212117D01*
X376667Y211825D01*
X376417Y211617D01*
X376000Y211450D01*
X375625Y211408D01*
X375250Y211492D01*
X375000Y211617D01*
X374750Y211867D01*
X374583Y212158D01*
X374500Y212450D01*
Y212742D01*
X374583Y213033D01*
X374708Y213283D01*
X374875Y213492D01*
G01X374500Y215550D02*
X377000D01*
X376500Y215050D01*
G01X374500D02*
Y216050D01*
G01Y218650D02*
X377000D01*
X376500Y218150D01*
G01X374500D02*
Y219150D01*
G01Y221750D02*
X374542Y222042D01*
X374667Y222375D01*
X374875Y222583D01*
X375167Y222667D01*
X375458Y222583D01*
X375708Y222333D01*
X375833Y221958D01*
Y221542D01*
X375917Y221292D01*
X376125Y221083D01*
X376417Y221000D01*
X376708Y221125D01*
X376917Y221417D01*
X377000Y221750D01*
X376917Y222083D01*
X376708Y222375D01*
X376417Y222500D01*
X376125Y222417D01*
X375917Y222208D01*
X375833Y221958D01*
Y221542D01*
X375708Y221167D01*
X375458Y220917D01*
X375167Y220833D01*
X374875Y220917D01*
X374667Y221125D01*
X374542Y221458D01*
X374500Y221750D01*
G01X393483Y214000D02*
Y216500D01*
X392442D01*
X392108Y216375D01*
X391900Y216208D01*
X391817Y215875D01*
X391900Y215542D01*
X392150Y215333D01*
X392442Y215208D01*
X393483D01*
G01X392442D02*
X391817Y214000D01*
G01X390342Y216083D02*
X390092Y216333D01*
X389800Y216458D01*
X389467Y216500D01*
X389050Y216417D01*
X388758Y216208D01*
X388675Y215958D01*
X388717Y215708D01*
X388883Y215500D01*
X389717Y215083D01*
X390092Y214792D01*
X390342Y214375D01*
X390425Y214000D01*
X388675D01*
G01X386450D02*
X386158Y214042D01*
X385825Y214167D01*
X385617Y214375D01*
X385533Y214667D01*
X385617Y214958D01*
X385867Y215208D01*
X386242Y215333D01*
X386658D01*
X386908Y215417D01*
X387117Y215625D01*
X387200Y215917D01*
X387075Y216208D01*
X386783Y216417D01*
X386450Y216500D01*
X386117Y216417D01*
X385825Y216208D01*
X385700Y215917D01*
X385783Y215625D01*
X385992Y215417D01*
X386242Y215333D01*
X386658D01*
X387033Y215208D01*
X387283Y214958D01*
X387367Y214667D01*
X387283Y214375D01*
X387075Y214167D01*
X386742Y214042D01*
X386450Y214000D01*
G01X383350D02*
Y216500D01*
X383850Y216000D01*
G01Y214000D02*
X382850D01*
G01X378500Y211617D02*
X381000D01*
Y212658D01*
X380875Y212992D01*
X380708Y213200D01*
X380375Y213283D01*
X380042Y213200D01*
X379833Y212950D01*
X379708Y212658D01*
Y211617D01*
G01Y212658D02*
X378500Y213283D01*
G01X380583Y214758D02*
X380833Y215008D01*
X380958Y215300D01*
X381000Y215633D01*
X380917Y216050D01*
X380708Y216342D01*
X380458Y216425D01*
X380208Y216383D01*
X380000Y216217D01*
X379583Y215383D01*
X379292Y215008D01*
X378875Y214758D01*
X378500Y214675D01*
Y216425D01*
G01Y218567D02*
X379042Y218650D01*
X379500Y218775D01*
X379917Y218942D01*
X380375Y219150D01*
X381000Y219483D01*
Y217817D01*
G01X378792Y221042D02*
X378583Y221333D01*
X378500Y221667D01*
X378583Y222000D01*
X378833Y222292D01*
X379208Y222500D01*
X379583Y222583D01*
X380042D01*
X380417Y222500D01*
X380750Y222292D01*
X380917Y222042D01*
X381000Y221750D01*
X380917Y221417D01*
X380750Y221167D01*
X380500Y221000D01*
X380167Y220917D01*
X379875Y221000D01*
X379583Y221208D01*
X379417Y221458D01*
X379375Y221750D01*
X379458Y222083D01*
X379667Y222333D01*
X380042Y222583D01*
G01X392233Y220792D02*
X392483Y220917D01*
X392775Y221000D01*
X393108D01*
X393483Y220875D01*
X393775Y220667D01*
X393983Y220417D01*
X394150Y220000D01*
X394192Y219625D01*
X394108Y219250D01*
X393983Y219000D01*
X393733Y218750D01*
X393442Y218583D01*
X393150Y218500D01*
X392858D01*
X392567Y218583D01*
X392317Y218708D01*
X392108Y218875D01*
G01X390050Y218500D02*
Y221000D01*
X390550Y220500D01*
G01Y218500D02*
X389550D01*
G01X387742Y220583D02*
X387492Y220833D01*
X387200Y220958D01*
X386867Y221000D01*
X386450Y220917D01*
X386158Y220708D01*
X386075Y220458D01*
X386117Y220208D01*
X386283Y220000D01*
X387117Y219583D01*
X387492Y219292D01*
X387742Y218875D01*
X387825Y218500D01*
X386075D01*
G01X384767Y218875D02*
X384517Y218667D01*
X384225Y218542D01*
X383850Y218500D01*
X383475Y218583D01*
X383183Y218750D01*
X382975Y219042D01*
X382933Y219375D01*
X383017Y219708D01*
X383225Y219917D01*
X383517Y220083D01*
X383808Y220125D01*
X384100Y220083D01*
X384475Y219917D01*
X384350Y221000D01*
X383225D01*
G01X398483Y230500D02*
Y233000D01*
X397442D01*
X397108Y232875D01*
X396900Y232708D01*
X396817Y232375D01*
X396900Y232042D01*
X397150Y231833D01*
X397442Y231708D01*
X398483D01*
G01X397442D02*
X396817Y230500D01*
G01X395342Y232583D02*
X395092Y232833D01*
X394800Y232958D01*
X394467Y233000D01*
X394050Y232917D01*
X393758Y232708D01*
X393675Y232458D01*
X393717Y232208D01*
X393883Y232000D01*
X394717Y231583D01*
X395092Y231292D01*
X395342Y230875D01*
X395425Y230500D01*
X393675D01*
G01X392367Y230875D02*
X392117Y230667D01*
X391825Y230542D01*
X391450Y230500D01*
X391075Y230583D01*
X390783Y230750D01*
X390575Y231042D01*
X390533Y231375D01*
X390617Y231708D01*
X390825Y231917D01*
X391117Y232083D01*
X391408Y232125D01*
X391700Y232083D01*
X392075Y231917D01*
X391950Y233000D01*
X390825D01*
G01X389058Y230792D02*
X388767Y230583D01*
X388433Y230500D01*
X388100Y230583D01*
X387808Y230833D01*
X387600Y231208D01*
X387517Y231583D01*
Y232042D01*
X387600Y232417D01*
X387808Y232750D01*
X388058Y232917D01*
X388350Y233000D01*
X388683Y232917D01*
X388933Y232750D01*
X389100Y232500D01*
X389183Y232167D01*
X389100Y231875D01*
X388892Y231583D01*
X388642Y231417D01*
X388350Y231375D01*
X388017Y231458D01*
X387767Y231667D01*
X387517Y232042D01*
G01X383933Y276000D02*
Y278500D01*
X382933D01*
X382600Y278375D01*
X382350Y278083D01*
X382267Y277750D01*
X382350Y277417D01*
X382558Y277167D01*
X382933Y277042D01*
X383933D01*
G01X380917Y278500D02*
Y276708D01*
X380750Y276333D01*
X380417Y276083D01*
X380000Y276000D01*
X379583Y276083D01*
X379250Y276333D01*
X379083Y276708D01*
Y278500D01*
G01X376900Y276000D02*
Y278500D01*
X377400Y278000D01*
G01Y276000D02*
X376400D01*
G01X400233Y72292D02*
X400483Y72417D01*
X400775Y72500D01*
X401108D01*
X401483Y72375D01*
X401775Y72167D01*
X401983Y71917D01*
X402150Y71500D01*
X402192Y71125D01*
X402108Y70750D01*
X401983Y70500D01*
X401733Y70250D01*
X401442Y70083D01*
X401150Y70000D01*
X400858D01*
X400567Y70083D01*
X400317Y70208D01*
X400108Y70375D01*
G01X398842Y72083D02*
X398592Y72333D01*
X398300Y72458D01*
X397967Y72500D01*
X397550Y72417D01*
X397258Y72208D01*
X397175Y71958D01*
X397217Y71708D01*
X397383Y71500D01*
X398217Y71083D01*
X398592Y70792D01*
X398842Y70375D01*
X398925Y70000D01*
X397175D01*
G01X395867Y70375D02*
X395617Y70167D01*
X395325Y70042D01*
X394950Y70000D01*
X394575Y70083D01*
X394283Y70250D01*
X394075Y70542D01*
X394033Y70875D01*
X394117Y71208D01*
X394325Y71417D01*
X394617Y71583D01*
X394908Y71625D01*
X395200Y71583D01*
X395575Y71417D01*
X395450Y72500D01*
X394325D01*
G01X392642Y71042D02*
X392350Y71333D01*
X392100Y71500D01*
X391767Y71583D01*
X391475Y71500D01*
X391267Y71333D01*
X391100Y71083D01*
X391058Y70792D01*
X391100Y70542D01*
X391267Y70292D01*
X391517Y70083D01*
X391808Y70000D01*
X392142Y70083D01*
X392433Y70333D01*
X392600Y70708D01*
X392642Y71125D01*
X392558Y71667D01*
X392433Y71958D01*
X392225Y72250D01*
X391933Y72458D01*
X391642Y72500D01*
X391350Y72417D01*
X391142Y72208D01*
G01X405483Y80500D02*
Y83000D01*
X404442D01*
X404108Y82875D01*
X403900Y82708D01*
X403817Y82375D01*
X403900Y82042D01*
X404150Y81833D01*
X404442Y81708D01*
X405483D01*
G01X404442D02*
X403817Y80500D01*
G01X402467Y81000D02*
X402217Y80708D01*
X401883Y80542D01*
X401508Y80500D01*
X401175Y80542D01*
X400842Y80750D01*
X400633Y81000D01*
X400592Y81250D01*
X400675Y81542D01*
X400967Y81750D01*
X401258Y81833D01*
X401633D01*
G01X401258D02*
X401008Y81958D01*
X400800Y82167D01*
X400717Y82417D01*
X400800Y82667D01*
X401008Y82875D01*
X401383Y83000D01*
X401758Y82958D01*
X402133Y82792D01*
G01X398450Y80500D02*
X398158Y80542D01*
X397825Y80667D01*
X397617Y80875D01*
X397533Y81167D01*
X397617Y81458D01*
X397867Y81708D01*
X398242Y81833D01*
X398658D01*
X398908Y81917D01*
X399117Y82125D01*
X399200Y82417D01*
X399075Y82708D01*
X398783Y82917D01*
X398450Y83000D01*
X398117Y82917D01*
X397825Y82708D01*
X397700Y82417D01*
X397783Y82125D01*
X397992Y81917D01*
X398242Y81833D01*
X398658D01*
X399033Y81708D01*
X399283Y81458D01*
X399367Y81167D01*
X399283Y80875D01*
X399075Y80667D01*
X398742Y80542D01*
X398450Y80500D01*
G01X395350Y83000D02*
X395683Y82917D01*
X395933Y82708D01*
X396100Y82458D01*
X396225Y82125D01*
X396267Y81750D01*
X396225Y81375D01*
X396100Y81042D01*
X395933Y80792D01*
X395683Y80583D01*
X395350Y80500D01*
X395017Y80583D01*
X394767Y80792D01*
X394600Y81042D01*
X394475Y81375D01*
X394433Y81750D01*
X394475Y82125D01*
X394600Y82458D01*
X394767Y82708D01*
X395017Y82917D01*
X395350Y83000D01*
G01X393292Y94267D02*
X393417Y94017D01*
X393500Y93725D01*
Y93392D01*
X393375Y93017D01*
X393167Y92725D01*
X392917Y92517D01*
X392500Y92350D01*
X392125Y92308D01*
X391750Y92392D01*
X391500Y92517D01*
X391250Y92767D01*
X391083Y93058D01*
X391000Y93350D01*
Y93642D01*
X391083Y93933D01*
X391208Y94183D01*
X391375Y94392D01*
G01X393083Y95658D02*
X393333Y95908D01*
X393458Y96200D01*
X393500Y96533D01*
X393417Y96950D01*
X393208Y97242D01*
X392958Y97325D01*
X392708Y97283D01*
X392500Y97117D01*
X392083Y96283D01*
X391792Y95908D01*
X391375Y95658D01*
X391000Y95575D01*
Y97325D01*
G01Y100050D02*
X393500D01*
X391708Y98508D01*
Y100592D01*
G01X391000Y103150D02*
X393500D01*
X391708Y101608D01*
Y103692D01*
G01X401000Y91517D02*
X403500D01*
Y92558D01*
X403375Y92892D01*
X403208Y93100D01*
X402875Y93183D01*
X402542Y93100D01*
X402333Y92850D01*
X402208Y92558D01*
Y91517D01*
G01Y92558D02*
X401000Y93183D01*
G01X401500Y94533D02*
X401208Y94783D01*
X401042Y95117D01*
X401000Y95492D01*
X401042Y95825D01*
X401250Y96158D01*
X401500Y96367D01*
X401750Y96408D01*
X402042Y96325D01*
X402250Y96033D01*
X402333Y95742D01*
Y95367D01*
G01Y95742D02*
X402458Y95992D01*
X402667Y96200D01*
X402917Y96283D01*
X403167Y96200D01*
X403375Y95992D01*
X403500Y95617D01*
X403458Y95242D01*
X403292Y94867D01*
G01X401000Y98467D02*
X401542Y98550D01*
X402000Y98675D01*
X402417Y98842D01*
X402875Y99050D01*
X403500Y99383D01*
Y97717D01*
G01X401500Y100733D02*
X401208Y100983D01*
X401042Y101317D01*
X401000Y101692D01*
X401042Y102025D01*
X401250Y102358D01*
X401500Y102567D01*
X401750Y102608D01*
X402042Y102525D01*
X402250Y102233D01*
X402333Y101942D01*
Y101567D01*
G01Y101942D02*
X402458Y102192D01*
X402667Y102400D01*
X402917Y102483D01*
X403167Y102400D01*
X403375Y102192D01*
X403500Y101817D01*
X403458Y101442D01*
X403292Y101067D01*
G01X395000Y92517D02*
X397500D01*
Y93558D01*
X397375Y93892D01*
X397208Y94100D01*
X396875Y94183D01*
X396542Y94100D01*
X396333Y93850D01*
X396208Y93558D01*
Y92517D01*
G01Y93558D02*
X395000Y94183D01*
G01X395500Y95533D02*
X395208Y95783D01*
X395042Y96117D01*
X395000Y96492D01*
X395042Y96825D01*
X395250Y97158D01*
X395500Y97367D01*
X395750Y97408D01*
X396042Y97325D01*
X396250Y97033D01*
X396333Y96742D01*
Y96367D01*
G01Y96742D02*
X396458Y96992D01*
X396667Y97200D01*
X396917Y97283D01*
X397167Y97200D01*
X397375Y96992D01*
X397500Y96617D01*
X397458Y96242D01*
X397292Y95867D01*
G01X395000Y99467D02*
X395542Y99550D01*
X396000Y99675D01*
X396417Y99842D01*
X396875Y100050D01*
X397500Y100383D01*
Y98717D01*
G01X395000Y103150D02*
X397500D01*
X395708Y101608D01*
Y103692D01*
G01X402792Y119267D02*
X402917Y119017D01*
X403000Y118725D01*
Y118392D01*
X402875Y118017D01*
X402667Y117725D01*
X402417Y117517D01*
X402000Y117350D01*
X401625Y117308D01*
X401250Y117392D01*
X401000Y117517D01*
X400750Y117767D01*
X400583Y118058D01*
X400500Y118350D01*
Y118642D01*
X400583Y118933D01*
X400708Y119183D01*
X400875Y119392D01*
G01X402583Y120658D02*
X402833Y120908D01*
X402958Y121200D01*
X403000Y121533D01*
X402917Y121950D01*
X402708Y122242D01*
X402458Y122325D01*
X402208Y122283D01*
X402000Y122117D01*
X401583Y121283D01*
X401292Y120908D01*
X400875Y120658D01*
X400500Y120575D01*
Y122325D01*
G01Y124550D02*
X403000D01*
X402500Y124050D01*
G01X400500D02*
Y125050D01*
G01Y127650D02*
X400542Y127942D01*
X400667Y128275D01*
X400875Y128483D01*
X401167Y128567D01*
X401458Y128483D01*
X401708Y128233D01*
X401833Y127858D01*
Y127442D01*
X401917Y127192D01*
X402125Y126983D01*
X402417Y126900D01*
X402708Y127025D01*
X402917Y127317D01*
X403000Y127650D01*
X402917Y127983D01*
X402708Y128275D01*
X402417Y128400D01*
X402125Y128317D01*
X401917Y128108D01*
X401833Y127858D01*
Y127442D01*
X401708Y127067D01*
X401458Y126817D01*
X401167Y126733D01*
X400875Y126817D01*
X400667Y127025D01*
X400542Y127358D01*
X400500Y127650D01*
G01X394792Y119267D02*
X394917Y119017D01*
X395000Y118725D01*
Y118392D01*
X394875Y118017D01*
X394667Y117725D01*
X394417Y117517D01*
X394000Y117350D01*
X393625Y117308D01*
X393250Y117392D01*
X393000Y117517D01*
X392750Y117767D01*
X392583Y118058D01*
X392500Y118350D01*
Y118642D01*
X392583Y118933D01*
X392708Y119183D01*
X392875Y119392D01*
G01X394583Y120658D02*
X394833Y120908D01*
X394958Y121200D01*
X395000Y121533D01*
X394917Y121950D01*
X394708Y122242D01*
X394458Y122325D01*
X394208Y122283D01*
X394000Y122117D01*
X393583Y121283D01*
X393292Y120908D01*
X392875Y120658D01*
X392500Y120575D01*
Y122325D01*
G01Y124550D02*
X395000D01*
X394500Y124050D01*
G01X392500D02*
Y125050D01*
G01X392792Y126942D02*
X392583Y127233D01*
X392500Y127567D01*
X392583Y127900D01*
X392833Y128192D01*
X393208Y128400D01*
X393583Y128483D01*
X394042D01*
X394417Y128400D01*
X394750Y128192D01*
X394917Y127942D01*
X395000Y127650D01*
X394917Y127317D01*
X394750Y127067D01*
X394500Y126900D01*
X394167Y126817D01*
X393875Y126900D01*
X393583Y127108D01*
X393417Y127358D01*
X393375Y127650D01*
X393458Y127983D01*
X393667Y128233D01*
X394042Y128483D01*
G01X401150Y136500D02*
Y134000D01*
G01X402108Y136500D02*
X400192D01*
G01X398883Y134000D02*
Y136500D01*
X397883D01*
X397550Y136375D01*
X397300Y136083D01*
X397217Y135750D01*
X397300Y135417D01*
X397508Y135167D01*
X397883Y135042D01*
X398883D01*
G01X395867Y134500D02*
X395617Y134208D01*
X395283Y134042D01*
X394908Y134000D01*
X394575Y134042D01*
X394242Y134250D01*
X394033Y134500D01*
X393992Y134750D01*
X394075Y135042D01*
X394367Y135250D01*
X394658Y135333D01*
X395033D01*
G01X394658D02*
X394408Y135458D01*
X394200Y135667D01*
X394117Y135917D01*
X394200Y136167D01*
X394408Y136375D01*
X394783Y136500D01*
X395158Y136458D01*
X395533Y136292D01*
G01X391350Y134000D02*
Y136500D01*
X392892Y134708D01*
X390808D01*
G01X407733Y154292D02*
X407983Y154417D01*
X408275Y154500D01*
X408608D01*
X408983Y154375D01*
X409275Y154167D01*
X409483Y153917D01*
X409650Y153500D01*
X409692Y153125D01*
X409608Y152750D01*
X409483Y152500D01*
X409233Y152250D01*
X408942Y152083D01*
X408650Y152000D01*
X408358D01*
X408067Y152083D01*
X407817Y152208D01*
X407608Y152375D01*
G01X405550Y152000D02*
Y154500D01*
X406050Y154000D01*
G01Y152000D02*
X405050D01*
G01X402533D02*
X402450Y152542D01*
X402325Y153000D01*
X402158Y153417D01*
X401950Y153875D01*
X401617Y154500D01*
X403283D01*
G01X398850Y152000D02*
Y154500D01*
X400392Y152708D01*
X398308D01*
G01X402733Y148792D02*
X402983Y148917D01*
X403275Y149000D01*
X403608D01*
X403983Y148875D01*
X404275Y148667D01*
X404483Y148417D01*
X404650Y148000D01*
X404692Y147625D01*
X404608Y147250D01*
X404483Y147000D01*
X404233Y146750D01*
X403942Y146583D01*
X403650Y146500D01*
X403358D01*
X403067Y146583D01*
X402817Y146708D01*
X402608Y146875D01*
G01X400550Y146500D02*
Y149000D01*
X401050Y148500D01*
G01Y146500D02*
X400050D01*
G01X398158Y146792D02*
X397867Y146583D01*
X397533Y146500D01*
X397200Y146583D01*
X396908Y146833D01*
X396700Y147208D01*
X396617Y147583D01*
Y148042D01*
X396700Y148417D01*
X396908Y148750D01*
X397158Y148917D01*
X397450Y149000D01*
X397783Y148917D01*
X398033Y148750D01*
X398200Y148500D01*
X398283Y148167D01*
X398200Y147875D01*
X397992Y147583D01*
X397742Y147417D01*
X397450Y147375D01*
X397117Y147458D01*
X396867Y147667D01*
X396617Y148042D01*
G01X395058Y146792D02*
X394767Y146583D01*
X394433Y146500D01*
X394100Y146583D01*
X393808Y146833D01*
X393600Y147208D01*
X393517Y147583D01*
Y148042D01*
X393600Y148417D01*
X393808Y148750D01*
X394058Y148917D01*
X394350Y149000D01*
X394683Y148917D01*
X394933Y148750D01*
X395100Y148500D01*
X395183Y148167D01*
X395100Y147875D01*
X394892Y147583D01*
X394642Y147417D01*
X394350Y147375D01*
X394017Y147458D01*
X393767Y147667D01*
X393517Y148042D01*
G01X396292Y153267D02*
X396417Y153017D01*
X396500Y152725D01*
Y152392D01*
X396375Y152017D01*
X396167Y151725D01*
X395917Y151517D01*
X395500Y151350D01*
X395125Y151308D01*
X394750Y151392D01*
X394500Y151517D01*
X394250Y151767D01*
X394083Y152058D01*
X394000Y152350D01*
Y152642D01*
X394083Y152933D01*
X394208Y153183D01*
X394375Y153392D01*
G01X394000Y155450D02*
X396500D01*
X396000Y154950D01*
G01X394000D02*
Y155950D01*
G01Y158467D02*
X394542Y158550D01*
X395000Y158675D01*
X395417Y158842D01*
X395875Y159050D01*
X396500Y159383D01*
Y157717D01*
G01X394000Y161650D02*
X396500D01*
X396000Y161150D01*
G01X394000D02*
Y162150D01*
G01X407733Y158292D02*
X407983Y158417D01*
X408275Y158500D01*
X408608D01*
X408983Y158375D01*
X409275Y158167D01*
X409483Y157917D01*
X409650Y157500D01*
X409692Y157125D01*
X409608Y156750D01*
X409483Y156500D01*
X409233Y156250D01*
X408942Y156083D01*
X408650Y156000D01*
X408358D01*
X408067Y156083D01*
X407817Y156208D01*
X407608Y156375D01*
G01X405550Y156000D02*
Y158500D01*
X406050Y158000D01*
G01Y156000D02*
X405050D01*
G01X403242Y157042D02*
X402950Y157333D01*
X402700Y157500D01*
X402367Y157583D01*
X402075Y157500D01*
X401867Y157333D01*
X401700Y157083D01*
X401658Y156792D01*
X401700Y156542D01*
X401867Y156292D01*
X402117Y156083D01*
X402408Y156000D01*
X402742Y156083D01*
X403033Y156333D01*
X403200Y156708D01*
X403242Y157125D01*
X403158Y157667D01*
X403033Y157958D01*
X402825Y158250D01*
X402533Y158458D01*
X402242Y158500D01*
X401950Y158417D01*
X401742Y158208D01*
G01X400142Y157042D02*
X399850Y157333D01*
X399600Y157500D01*
X399267Y157583D01*
X398975Y157500D01*
X398767Y157333D01*
X398600Y157083D01*
X398558Y156792D01*
X398600Y156542D01*
X398767Y156292D01*
X399017Y156083D01*
X399308Y156000D01*
X399642Y156083D01*
X399933Y156333D01*
X400100Y156708D01*
X400142Y157125D01*
X400058Y157667D01*
X399933Y157958D01*
X399725Y158250D01*
X399433Y158458D01*
X399142Y158500D01*
X398850Y158417D01*
X398642Y158208D01*
G01X411933Y183355D02*
X412183Y183480D01*
X412475Y183563D01*
X412808D01*
X413183Y183438D01*
X413475Y183230D01*
X413683Y182980D01*
X413850Y182563D01*
X413892Y182188D01*
X413808Y181813D01*
X413683Y181563D01*
X413433Y181313D01*
X413142Y181146D01*
X412850Y181063D01*
X412558D01*
X412267Y181146D01*
X412017Y181271D01*
X411808Y181438D01*
G01X409750Y181063D02*
Y183563D01*
X410250Y183063D01*
G01Y181063D02*
X409250D01*
G01X407442Y182105D02*
X407150Y182396D01*
X406900Y182563D01*
X406567Y182646D01*
X406275Y182563D01*
X406067Y182396D01*
X405900Y182146D01*
X405858Y181855D01*
X405900Y181605D01*
X406067Y181355D01*
X406317Y181146D01*
X406608Y181063D01*
X406942Y181146D01*
X407233Y181396D01*
X407400Y181771D01*
X407442Y182188D01*
X407358Y182730D01*
X407233Y183021D01*
X407025Y183313D01*
X406733Y183521D01*
X406442Y183563D01*
X406150Y183480D01*
X405942Y183271D01*
G01X404467Y181563D02*
X404217Y181271D01*
X403883Y181105D01*
X403508Y181063D01*
X403175Y181105D01*
X402842Y181313D01*
X402633Y181563D01*
X402592Y181813D01*
X402675Y182105D01*
X402967Y182313D01*
X403258Y182396D01*
X403633D01*
G01X403258D02*
X403008Y182521D01*
X402800Y182730D01*
X402717Y182980D01*
X402800Y183230D01*
X403008Y183438D01*
X403383Y183563D01*
X403758Y183521D01*
X404133Y183355D01*
G01X394883Y184500D02*
Y182000D01*
X393217D01*
G01X390450D02*
Y184500D01*
X391992Y182708D01*
X389908D01*
G01X398000Y181517D02*
X400500D01*
Y182558D01*
X400375Y182892D01*
X400208Y183100D01*
X399875Y183183D01*
X399542Y183100D01*
X399333Y182850D01*
X399208Y182558D01*
Y181517D01*
G01Y182558D02*
X398000Y183183D01*
G01X398500Y184533D02*
X398208Y184783D01*
X398042Y185117D01*
X398000Y185492D01*
X398042Y185825D01*
X398250Y186158D01*
X398500Y186367D01*
X398750Y186408D01*
X399042Y186325D01*
X399250Y186033D01*
X399333Y185742D01*
Y185367D01*
G01Y185742D02*
X399458Y185992D01*
X399667Y186200D01*
X399917Y186283D01*
X400167Y186200D01*
X400375Y185992D01*
X400500Y185617D01*
X400458Y185242D01*
X400292Y184867D01*
G01X400500Y188550D02*
X400417Y188217D01*
X400208Y187967D01*
X399958Y187800D01*
X399625Y187675D01*
X399250Y187633D01*
X398875Y187675D01*
X398542Y187800D01*
X398292Y187967D01*
X398083Y188217D01*
X398000Y188550D01*
X398083Y188883D01*
X398292Y189133D01*
X398542Y189300D01*
X398875Y189425D01*
X399250Y189467D01*
X399625Y189425D01*
X399958Y189300D01*
X400208Y189133D01*
X400417Y188883D01*
X400500Y188550D01*
G01X398292Y190942D02*
X398083Y191233D01*
X398000Y191567D01*
X398083Y191900D01*
X398333Y192192D01*
X398708Y192400D01*
X399083Y192483D01*
X399542D01*
X399917Y192400D01*
X400250Y192192D01*
X400417Y191942D01*
X400500Y191650D01*
X400417Y191317D01*
X400250Y191067D01*
X400000Y190900D01*
X399667Y190817D01*
X399375Y190900D01*
X399083Y191108D01*
X398917Y191358D01*
X398875Y191650D01*
X398958Y191983D01*
X399167Y192233D01*
X399542Y192483D01*
G01X396500Y194500D02*
X416000D01*
Y211000D01*
X437500D01*
Y230000D01*
X401000D01*
Y213000D01*
X394000D01*
Y199000D01*
X390500D01*
G01X412233Y187792D02*
X412483Y187917D01*
X412775Y188000D01*
X413108D01*
X413483Y187875D01*
X413775Y187667D01*
X413983Y187417D01*
X414150Y187000D01*
X414192Y186625D01*
X414108Y186250D01*
X413983Y186000D01*
X413733Y185750D01*
X413442Y185583D01*
X413150Y185500D01*
X412858D01*
X412567Y185583D01*
X412317Y185708D01*
X412108Y185875D01*
G01X410050Y185500D02*
Y188000D01*
X410550Y187500D01*
G01Y185500D02*
X409550D01*
G01X407867Y185875D02*
X407617Y185667D01*
X407325Y185542D01*
X406950Y185500D01*
X406575Y185583D01*
X406283Y185750D01*
X406075Y186042D01*
X406033Y186375D01*
X406117Y186708D01*
X406325Y186917D01*
X406617Y187083D01*
X406908Y187125D01*
X407200Y187083D01*
X407575Y186917D01*
X407450Y188000D01*
X406325D01*
G01X404767Y186000D02*
X404517Y185708D01*
X404183Y185542D01*
X403808Y185500D01*
X403475Y185542D01*
X403142Y185750D01*
X402933Y186000D01*
X402892Y186250D01*
X402975Y186542D01*
X403267Y186750D01*
X403558Y186833D01*
X403933D01*
G01X403558D02*
X403308Y186958D01*
X403100Y187167D01*
X403017Y187417D01*
X403100Y187667D01*
X403308Y187875D01*
X403683Y188000D01*
X404058Y187958D01*
X404433Y187792D01*
G01X413983Y213000D02*
Y215500D01*
X412942D01*
X412608Y215375D01*
X412400Y215208D01*
X412317Y214875D01*
X412400Y214542D01*
X412650Y214333D01*
X412942Y214208D01*
X413983D01*
G01X412942D02*
X412317Y213000D01*
G01X410842Y215083D02*
X410592Y215333D01*
X410300Y215458D01*
X409967Y215500D01*
X409550Y215417D01*
X409258Y215208D01*
X409175Y214958D01*
X409217Y214708D01*
X409383Y214500D01*
X410217Y214083D01*
X410592Y213792D01*
X410842Y213375D01*
X410925Y213000D01*
X409175D01*
G01X406950D02*
X406658Y213042D01*
X406325Y213167D01*
X406117Y213375D01*
X406033Y213667D01*
X406117Y213958D01*
X406367Y214208D01*
X406742Y214333D01*
X407158D01*
X407408Y214417D01*
X407617Y214625D01*
X407700Y214917D01*
X407575Y215208D01*
X407283Y215417D01*
X406950Y215500D01*
X406617Y215417D01*
X406325Y215208D01*
X406200Y214917D01*
X406283Y214625D01*
X406492Y214417D01*
X406742Y214333D01*
X407158D01*
X407533Y214208D01*
X407783Y213958D01*
X407867Y213667D01*
X407783Y213375D01*
X407575Y213167D01*
X407242Y213042D01*
X406950Y213000D01*
G01X403933D02*
X403850Y213542D01*
X403725Y214000D01*
X403558Y214417D01*
X403350Y214875D01*
X403017Y215500D01*
X404683D01*
G01X413983Y217000D02*
Y219500D01*
X412942D01*
X412608Y219375D01*
X412400Y219208D01*
X412317Y218875D01*
X412400Y218542D01*
X412650Y218333D01*
X412942Y218208D01*
X413983D01*
G01X412942D02*
X412317Y217000D01*
G01X410842Y219083D02*
X410592Y219333D01*
X410300Y219458D01*
X409967Y219500D01*
X409550Y219417D01*
X409258Y219208D01*
X409175Y218958D01*
X409217Y218708D01*
X409383Y218500D01*
X410217Y218083D01*
X410592Y217792D01*
X410842Y217375D01*
X410925Y217000D01*
X409175D01*
G01X407867Y217375D02*
X407617Y217167D01*
X407325Y217042D01*
X406950Y217000D01*
X406575Y217083D01*
X406283Y217250D01*
X406075Y217542D01*
X406033Y217875D01*
X406117Y218208D01*
X406325Y218417D01*
X406617Y218583D01*
X406908Y218625D01*
X407200Y218583D01*
X407575Y218417D01*
X407450Y219500D01*
X406325D01*
G01X403850Y217000D02*
X403558Y217042D01*
X403225Y217167D01*
X403017Y217375D01*
X402933Y217667D01*
X403017Y217958D01*
X403267Y218208D01*
X403642Y218333D01*
X404058D01*
X404308Y218417D01*
X404517Y218625D01*
X404600Y218917D01*
X404475Y219208D01*
X404183Y219417D01*
X403850Y219500D01*
X403517Y219417D01*
X403225Y219208D01*
X403100Y218917D01*
X403183Y218625D01*
X403392Y218417D01*
X403642Y218333D01*
X404058D01*
X404433Y218208D01*
X404683Y217958D01*
X404767Y217667D01*
X404683Y217375D01*
X404475Y217167D01*
X404142Y217042D01*
X403850Y217000D01*
G01X413983Y221000D02*
Y223500D01*
X412942D01*
X412608Y223375D01*
X412400Y223208D01*
X412317Y222875D01*
X412400Y222542D01*
X412650Y222333D01*
X412942Y222208D01*
X413983D01*
G01X412942D02*
X412317Y221000D01*
G01X410842Y223083D02*
X410592Y223333D01*
X410300Y223458D01*
X409967Y223500D01*
X409550Y223417D01*
X409258Y223208D01*
X409175Y222958D01*
X409217Y222708D01*
X409383Y222500D01*
X410217Y222083D01*
X410592Y221792D01*
X410842Y221375D01*
X410925Y221000D01*
X409175D01*
G01X407742Y222042D02*
X407450Y222333D01*
X407200Y222500D01*
X406867Y222583D01*
X406575Y222500D01*
X406367Y222333D01*
X406200Y222083D01*
X406158Y221792D01*
X406200Y221542D01*
X406367Y221292D01*
X406617Y221083D01*
X406908Y221000D01*
X407242Y221083D01*
X407533Y221333D01*
X407700Y221708D01*
X407742Y222125D01*
X407658Y222667D01*
X407533Y222958D01*
X407325Y223250D01*
X407033Y223458D01*
X406742Y223500D01*
X406450Y223417D01*
X406242Y223208D01*
G01X403850Y221000D02*
Y223500D01*
X404350Y223000D01*
G01Y221000D02*
X403350D01*
G01X390000Y270967D02*
X392500D01*
Y271967D01*
X392375Y272300D01*
X392083Y272550D01*
X391750Y272633D01*
X391417Y272550D01*
X391167Y272342D01*
X391042Y271967D01*
Y270967D01*
G01X392292Y275817D02*
X392417Y275567D01*
X392500Y275275D01*
Y274942D01*
X392375Y274567D01*
X392167Y274275D01*
X391917Y274067D01*
X391500Y273900D01*
X391125Y273858D01*
X390750Y273942D01*
X390500Y274067D01*
X390250Y274317D01*
X390083Y274608D01*
X390000Y274900D01*
Y275192D01*
X390083Y275483D01*
X390208Y275733D01*
X390375Y275942D01*
G01X390000Y278000D02*
X392500D01*
X392000Y277500D01*
G01X390000D02*
Y278500D01*
G01X392083Y280308D02*
X392333Y280558D01*
X392458Y280850D01*
X392500Y281183D01*
X392417Y281600D01*
X392208Y281892D01*
X391958Y281975D01*
X391708Y281933D01*
X391500Y281767D01*
X391083Y280933D01*
X390792Y280558D01*
X390375Y280308D01*
X390000Y280225D01*
Y281975D01*
G01X392083Y283408D02*
X392333Y283658D01*
X392458Y283950D01*
X392500Y284283D01*
X392417Y284700D01*
X392208Y284992D01*
X391958Y285075D01*
X391708Y285033D01*
X391500Y284867D01*
X391083Y284033D01*
X390792Y283658D01*
X390375Y283408D01*
X390000Y283325D01*
Y285075D01*
G01X398500Y274067D02*
X401000D01*
Y275067D01*
X400875Y275400D01*
X400583Y275650D01*
X400250Y275733D01*
X399917Y275650D01*
X399667Y275442D01*
X399542Y275067D01*
Y274067D01*
G01X398500Y277167D02*
X401000D01*
Y278208D01*
X400875Y278542D01*
X400708Y278750D01*
X400375Y278833D01*
X400042Y278750D01*
X399833Y278500D01*
X399708Y278208D01*
Y277167D01*
G01Y278208D02*
X398500Y278833D01*
G01X399000Y280183D02*
X398708Y280433D01*
X398542Y280767D01*
X398500Y281142D01*
X398542Y281475D01*
X398750Y281808D01*
X399000Y282017D01*
X399250Y282058D01*
X399542Y281975D01*
X399750Y281683D01*
X399833Y281392D01*
Y281017D01*
G01Y281392D02*
X399958Y281642D01*
X400167Y281850D01*
X400417Y281933D01*
X400667Y281850D01*
X400875Y281642D01*
X401000Y281267D01*
X400958Y280892D01*
X400792Y280517D01*
G01X402500Y270067D02*
X405000D01*
Y271067D01*
X404875Y271400D01*
X404583Y271650D01*
X404250Y271733D01*
X403917Y271650D01*
X403667Y271442D01*
X403542Y271067D01*
Y270067D01*
G01X402500Y273167D02*
X405000D01*
Y274208D01*
X404875Y274542D01*
X404708Y274750D01*
X404375Y274833D01*
X404042Y274750D01*
X403833Y274500D01*
X403708Y274208D01*
Y273167D01*
G01Y274208D02*
X402500Y274833D01*
G01X403542Y276308D02*
X403833Y276600D01*
X404000Y276850D01*
X404083Y277183D01*
X404000Y277475D01*
X403833Y277683D01*
X403583Y277850D01*
X403292Y277892D01*
X403042Y277850D01*
X402792Y277683D01*
X402583Y277433D01*
X402500Y277142D01*
X402583Y276808D01*
X402833Y276517D01*
X403208Y276350D01*
X403625Y276308D01*
X404167Y276392D01*
X404458Y276517D01*
X404750Y276725D01*
X404958Y277017D01*
X405000Y277308D01*
X404917Y277600D01*
X404708Y277808D01*
G01X421000Y57983D02*
X419208D01*
X418833Y58150D01*
X418583Y58483D01*
X418500Y58900D01*
X418583Y59317D01*
X418833Y59650D01*
X419208Y59817D01*
X421000D01*
G01X419000Y61083D02*
X418708Y61333D01*
X418542Y61667D01*
X418500Y62042D01*
X418542Y62375D01*
X418750Y62708D01*
X419000Y62917D01*
X419250Y62958D01*
X419542Y62875D01*
X419750Y62583D01*
X419833Y62292D01*
Y61917D01*
G01Y62292D02*
X419958Y62542D01*
X420167Y62750D01*
X420417Y62833D01*
X420667Y62750D01*
X420875Y62542D01*
X421000Y62167D01*
X420958Y61792D01*
X420792Y61417D01*
G01X418792Y64392D02*
X418583Y64683D01*
X418500Y65017D01*
X418583Y65350D01*
X418833Y65642D01*
X419208Y65850D01*
X419583Y65933D01*
X420042D01*
X420417Y65850D01*
X420750Y65642D01*
X420917Y65392D01*
X421000Y65100D01*
X420917Y64767D01*
X420750Y64517D01*
X420500Y64350D01*
X420167Y64267D01*
X419875Y64350D01*
X419583Y64558D01*
X419417Y64808D01*
X419375Y65100D01*
X419458Y65433D01*
X419667Y65683D01*
X420042Y65933D01*
G01X407800Y58050D02*
Y65950D01*
G01X405200Y58050D02*
X407800D01*
G01X405200Y65950D02*
Y58050D01*
G01X427983Y52500D02*
Y55000D01*
X426942D01*
X426608Y54875D01*
X426400Y54708D01*
X426317Y54375D01*
X426400Y54042D01*
X426650Y53833D01*
X426942Y53708D01*
X427983D01*
G01X426942D02*
X426317Y52500D01*
G01X423550D02*
Y55000D01*
X425092Y53208D01*
X423008D01*
G01X421033Y52500D02*
X420950Y53042D01*
X420825Y53500D01*
X420658Y53917D01*
X420450Y54375D01*
X420117Y55000D01*
X421783D01*
G01X417933Y52500D02*
X417850Y53042D01*
X417725Y53500D01*
X417558Y53917D01*
X417350Y54375D01*
X417017Y55000D01*
X418683D01*
G01X418733Y69792D02*
X418983Y69917D01*
X419275Y70000D01*
X419608D01*
X419983Y69875D01*
X420275Y69667D01*
X420483Y69417D01*
X420650Y69000D01*
X420692Y68625D01*
X420608Y68250D01*
X420483Y68000D01*
X420233Y67750D01*
X419942Y67583D01*
X419650Y67500D01*
X419358D01*
X419067Y67583D01*
X418817Y67708D01*
X418608Y67875D01*
G01X417467Y68000D02*
X417217Y67708D01*
X416883Y67542D01*
X416508Y67500D01*
X416175Y67542D01*
X415842Y67750D01*
X415633Y68000D01*
X415592Y68250D01*
X415675Y68542D01*
X415967Y68750D01*
X416258Y68833D01*
X416633D01*
G01X416258D02*
X416008Y68958D01*
X415800Y69167D01*
X415717Y69417D01*
X415800Y69667D01*
X416008Y69875D01*
X416383Y70000D01*
X416758Y69958D01*
X417133Y69792D01*
G01X414367Y68000D02*
X414117Y67708D01*
X413783Y67542D01*
X413408Y67500D01*
X413075Y67542D01*
X412742Y67750D01*
X412533Y68000D01*
X412492Y68250D01*
X412575Y68542D01*
X412867Y68750D01*
X413158Y68833D01*
X413533D01*
G01X413158D02*
X412908Y68958D01*
X412700Y69167D01*
X412617Y69417D01*
X412700Y69667D01*
X412908Y69875D01*
X413283Y70000D01*
X413658Y69958D01*
X414033Y69792D01*
G01X411142Y68542D02*
X410850Y68833D01*
X410600Y69000D01*
X410267Y69083D01*
X409975Y69000D01*
X409767Y68833D01*
X409600Y68583D01*
X409558Y68292D01*
X409600Y68042D01*
X409767Y67792D01*
X410017Y67583D01*
X410308Y67500D01*
X410642Y67583D01*
X410933Y67833D01*
X411100Y68208D01*
X411142Y68625D01*
X411058Y69167D01*
X410933Y69458D01*
X410725Y69750D01*
X410433Y69958D01*
X410142Y70000D01*
X409850Y69917D01*
X409642Y69708D01*
G01X407800Y65950D02*
X405200D01*
G01X409792Y75267D02*
X409917Y75017D01*
X410000Y74725D01*
Y74392D01*
X409875Y74017D01*
X409667Y73725D01*
X409417Y73517D01*
X409000Y73350D01*
X408625Y73308D01*
X408250Y73392D01*
X408000Y73517D01*
X407750Y73767D01*
X407583Y74058D01*
X407500Y74350D01*
Y74642D01*
X407583Y74933D01*
X407708Y75183D01*
X407875Y75392D01*
G01X409583Y76658D02*
X409833Y76908D01*
X409958Y77200D01*
X410000Y77533D01*
X409917Y77950D01*
X409708Y78242D01*
X409458Y78325D01*
X409208Y78283D01*
X409000Y78117D01*
X408583Y77283D01*
X408292Y76908D01*
X407875Y76658D01*
X407500Y76575D01*
Y78325D01*
G01X407875Y79633D02*
X407667Y79883D01*
X407542Y80175D01*
X407500Y80550D01*
X407583Y80925D01*
X407750Y81217D01*
X408042Y81425D01*
X408375Y81467D01*
X408708Y81383D01*
X408917Y81175D01*
X409083Y80883D01*
X409125Y80592D01*
X409083Y80300D01*
X408917Y79925D01*
X410000Y80050D01*
Y81175D01*
G01X407875Y82733D02*
X407667Y82983D01*
X407542Y83275D01*
X407500Y83650D01*
X407583Y84025D01*
X407750Y84317D01*
X408042Y84525D01*
X408375Y84567D01*
X408708Y84483D01*
X408917Y84275D01*
X409083Y83983D01*
X409125Y83692D01*
X409083Y83400D01*
X408917Y83025D01*
X410000Y83150D01*
Y84275D01*
G01X421233Y86292D02*
X421483Y86417D01*
X421775Y86500D01*
X422108D01*
X422483Y86375D01*
X422775Y86167D01*
X422983Y85917D01*
X423150Y85500D01*
X423192Y85125D01*
X423108Y84750D01*
X422983Y84500D01*
X422733Y84250D01*
X422442Y84083D01*
X422150Y84000D01*
X421858D01*
X421567Y84083D01*
X421317Y84208D01*
X421108Y84375D01*
G01X419842Y86083D02*
X419592Y86333D01*
X419300Y86458D01*
X418967Y86500D01*
X418550Y86417D01*
X418258Y86208D01*
X418175Y85958D01*
X418217Y85708D01*
X418383Y85500D01*
X419217Y85083D01*
X419592Y84792D01*
X419842Y84375D01*
X419925Y84000D01*
X418175D01*
G01X416742Y85042D02*
X416450Y85333D01*
X416200Y85500D01*
X415867Y85583D01*
X415575Y85500D01*
X415367Y85333D01*
X415200Y85083D01*
X415158Y84792D01*
X415200Y84542D01*
X415367Y84292D01*
X415617Y84083D01*
X415908Y84000D01*
X416242Y84083D01*
X416533Y84333D01*
X416700Y84708D01*
X416742Y85125D01*
X416658Y85667D01*
X416533Y85958D01*
X416325Y86250D01*
X416033Y86458D01*
X415742Y86500D01*
X415450Y86417D01*
X415242Y86208D01*
G01X412850Y86500D02*
X413183Y86417D01*
X413433Y86208D01*
X413600Y85958D01*
X413725Y85625D01*
X413767Y85250D01*
X413725Y84875D01*
X413600Y84542D01*
X413433Y84292D01*
X413183Y84083D01*
X412850Y84000D01*
X412517Y84083D01*
X412267Y84292D01*
X412100Y84542D01*
X411975Y84875D01*
X411933Y85250D01*
X411975Y85625D01*
X412100Y85958D01*
X412267Y86208D01*
X412517Y86417D01*
X412850Y86500D01*
G01X411292Y93267D02*
X411417Y93017D01*
X411500Y92725D01*
Y92392D01*
X411375Y92017D01*
X411167Y91725D01*
X410917Y91517D01*
X410500Y91350D01*
X410125Y91308D01*
X409750Y91392D01*
X409500Y91517D01*
X409250Y91767D01*
X409083Y92058D01*
X409000Y92350D01*
Y92642D01*
X409083Y92933D01*
X409208Y93183D01*
X409375Y93392D01*
G01X411083Y94658D02*
X411333Y94908D01*
X411458Y95200D01*
X411500Y95533D01*
X411417Y95950D01*
X411208Y96242D01*
X410958Y96325D01*
X410708Y96283D01*
X410500Y96117D01*
X410083Y95283D01*
X409792Y94908D01*
X409375Y94658D01*
X409000Y94575D01*
Y96325D01*
G01Y99050D02*
X411500D01*
X409708Y97508D01*
Y99592D01*
G01X411083Y100858D02*
X411333Y101108D01*
X411458Y101400D01*
X411500Y101733D01*
X411417Y102150D01*
X411208Y102442D01*
X410958Y102525D01*
X410708Y102483D01*
X410500Y102317D01*
X410083Y101483D01*
X409792Y101108D01*
X409375Y100858D01*
X409000Y100775D01*
Y102525D01*
G01X407292Y93267D02*
X407417Y93017D01*
X407500Y92725D01*
Y92392D01*
X407375Y92017D01*
X407167Y91725D01*
X406917Y91517D01*
X406500Y91350D01*
X406125Y91308D01*
X405750Y91392D01*
X405500Y91517D01*
X405250Y91767D01*
X405083Y92058D01*
X405000Y92350D01*
Y92642D01*
X405083Y92933D01*
X405208Y93183D01*
X405375Y93392D01*
G01X407083Y94658D02*
X407333Y94908D01*
X407458Y95200D01*
X407500Y95533D01*
X407417Y95950D01*
X407208Y96242D01*
X406958Y96325D01*
X406708Y96283D01*
X406500Y96117D01*
X406083Y95283D01*
X405792Y94908D01*
X405375Y94658D01*
X405000Y94575D01*
Y96325D01*
G01Y99050D02*
X407500D01*
X405708Y97508D01*
Y99592D01*
G01X405500Y100733D02*
X405208Y100983D01*
X405042Y101317D01*
X405000Y101692D01*
X405042Y102025D01*
X405250Y102358D01*
X405500Y102567D01*
X405750Y102608D01*
X406042Y102525D01*
X406250Y102233D01*
X406333Y101942D01*
Y101567D01*
G01Y101942D02*
X406458Y102192D01*
X406667Y102400D01*
X406917Y102483D01*
X407167Y102400D01*
X407375Y102192D01*
X407500Y101817D01*
X407458Y101442D01*
X407292Y101067D01*
G01X419292Y93267D02*
X419417Y93017D01*
X419500Y92725D01*
Y92392D01*
X419375Y92017D01*
X419167Y91725D01*
X418917Y91517D01*
X418500Y91350D01*
X418125Y91308D01*
X417750Y91392D01*
X417500Y91517D01*
X417250Y91767D01*
X417083Y92058D01*
X417000Y92350D01*
Y92642D01*
X417083Y92933D01*
X417208Y93183D01*
X417375Y93392D01*
G01X419083Y94658D02*
X419333Y94908D01*
X419458Y95200D01*
X419500Y95533D01*
X419417Y95950D01*
X419208Y96242D01*
X418958Y96325D01*
X418708Y96283D01*
X418500Y96117D01*
X418083Y95283D01*
X417792Y94908D01*
X417375Y94658D01*
X417000Y94575D01*
Y96325D01*
G01Y99050D02*
X419500D01*
X417708Y97508D01*
Y99592D01*
G01X419500Y101650D02*
X419417Y101317D01*
X419208Y101067D01*
X418958Y100900D01*
X418625Y100775D01*
X418250Y100733D01*
X417875Y100775D01*
X417542Y100900D01*
X417292Y101067D01*
X417083Y101317D01*
X417000Y101650D01*
X417083Y101983D01*
X417292Y102233D01*
X417542Y102400D01*
X417875Y102525D01*
X418250Y102567D01*
X418625Y102525D01*
X418958Y102400D01*
X419208Y102233D01*
X419417Y101983D01*
X419500Y101650D01*
G01X415292Y93267D02*
X415417Y93017D01*
X415500Y92725D01*
Y92392D01*
X415375Y92017D01*
X415167Y91725D01*
X414917Y91517D01*
X414500Y91350D01*
X414125Y91308D01*
X413750Y91392D01*
X413500Y91517D01*
X413250Y91767D01*
X413083Y92058D01*
X413000Y92350D01*
Y92642D01*
X413083Y92933D01*
X413208Y93183D01*
X413375Y93392D01*
G01X415083Y94658D02*
X415333Y94908D01*
X415458Y95200D01*
X415500Y95533D01*
X415417Y95950D01*
X415208Y96242D01*
X414958Y96325D01*
X414708Y96283D01*
X414500Y96117D01*
X414083Y95283D01*
X413792Y94908D01*
X413375Y94658D01*
X413000Y94575D01*
Y96325D01*
G01Y99050D02*
X415500D01*
X413708Y97508D01*
Y99592D01*
G01X413000Y101650D02*
X415500D01*
X415000Y101150D01*
G01X413000D02*
Y102150D01*
G01X420733Y138792D02*
X420983Y138917D01*
X421275Y139000D01*
X421608D01*
X421983Y138875D01*
X422275Y138667D01*
X422483Y138417D01*
X422650Y138000D01*
X422692Y137625D01*
X422608Y137250D01*
X422483Y137000D01*
X422233Y136750D01*
X421942Y136583D01*
X421650Y136500D01*
X421358D01*
X421067Y136583D01*
X420817Y136708D01*
X420608Y136875D01*
G01X419342Y138583D02*
X419092Y138833D01*
X418800Y138958D01*
X418467Y139000D01*
X418050Y138917D01*
X417758Y138708D01*
X417675Y138458D01*
X417717Y138208D01*
X417883Y138000D01*
X418717Y137583D01*
X419092Y137292D01*
X419342Y136875D01*
X419425Y136500D01*
X417675D01*
G01X415450D02*
Y139000D01*
X415950Y138500D01*
G01Y136500D02*
X414950D01*
G01X411850D02*
Y139000D01*
X413392Y137208D01*
X411308D01*
G01X423733Y133292D02*
X423983Y133417D01*
X424275Y133500D01*
X424608D01*
X424983Y133375D01*
X425275Y133167D01*
X425483Y132917D01*
X425650Y132500D01*
X425692Y132125D01*
X425608Y131750D01*
X425483Y131500D01*
X425233Y131250D01*
X424942Y131083D01*
X424650Y131000D01*
X424358D01*
X424067Y131083D01*
X423817Y131208D01*
X423608Y131375D01*
G01X422342Y133083D02*
X422092Y133333D01*
X421800Y133458D01*
X421467Y133500D01*
X421050Y133417D01*
X420758Y133208D01*
X420675Y132958D01*
X420717Y132708D01*
X420883Y132500D01*
X421717Y132083D01*
X422092Y131792D01*
X422342Y131375D01*
X422425Y131000D01*
X420675D01*
G01X419242Y133083D02*
X418992Y133333D01*
X418700Y133458D01*
X418367Y133500D01*
X417950Y133417D01*
X417658Y133208D01*
X417575Y132958D01*
X417617Y132708D01*
X417783Y132500D01*
X418617Y132083D01*
X418992Y131792D01*
X419242Y131375D01*
X419325Y131000D01*
X417575D01*
G01X416142Y133083D02*
X415892Y133333D01*
X415600Y133458D01*
X415267Y133500D01*
X414850Y133417D01*
X414558Y133208D01*
X414475Y132958D01*
X414517Y132708D01*
X414683Y132500D01*
X415517Y132083D01*
X415892Y131792D01*
X416142Y131375D01*
X416225Y131000D01*
X414475D01*
G01X423983Y123500D02*
Y126000D01*
X422942D01*
X422608Y125875D01*
X422400Y125708D01*
X422317Y125375D01*
X422400Y125042D01*
X422650Y124833D01*
X422942Y124708D01*
X423983D01*
G01X422942D02*
X422317Y123500D01*
G01X420967Y124000D02*
X420717Y123708D01*
X420383Y123542D01*
X420008Y123500D01*
X419675Y123542D01*
X419342Y123750D01*
X419133Y124000D01*
X419092Y124250D01*
X419175Y124542D01*
X419467Y124750D01*
X419758Y124833D01*
X420133D01*
G01X419758D02*
X419508Y124958D01*
X419300Y125167D01*
X419217Y125417D01*
X419300Y125667D01*
X419508Y125875D01*
X419883Y126000D01*
X420258Y125958D01*
X420633Y125792D01*
G01X417867Y123875D02*
X417617Y123667D01*
X417325Y123542D01*
X416950Y123500D01*
X416575Y123583D01*
X416283Y123750D01*
X416075Y124042D01*
X416033Y124375D01*
X416117Y124708D01*
X416325Y124917D01*
X416617Y125083D01*
X416908Y125125D01*
X417200Y125083D01*
X417575Y124917D01*
X417450Y126000D01*
X416325D01*
G01X414642Y124542D02*
X414350Y124833D01*
X414100Y125000D01*
X413767Y125083D01*
X413475Y125000D01*
X413267Y124833D01*
X413100Y124583D01*
X413058Y124292D01*
X413100Y124042D01*
X413267Y123792D01*
X413517Y123583D01*
X413808Y123500D01*
X414142Y123583D01*
X414433Y123833D01*
X414600Y124208D01*
X414642Y124625D01*
X414558Y125167D01*
X414433Y125458D01*
X414225Y125750D01*
X413933Y125958D01*
X413642Y126000D01*
X413350Y125917D01*
X413142Y125708D01*
G01X420733Y146792D02*
X420983Y146917D01*
X421275Y147000D01*
X421608D01*
X421983Y146875D01*
X422275Y146667D01*
X422483Y146417D01*
X422650Y146000D01*
X422692Y145625D01*
X422608Y145250D01*
X422483Y145000D01*
X422233Y144750D01*
X421942Y144583D01*
X421650Y144500D01*
X421358D01*
X421067Y144583D01*
X420817Y144708D01*
X420608Y144875D01*
G01X419342Y146583D02*
X419092Y146833D01*
X418800Y146958D01*
X418467Y147000D01*
X418050Y146917D01*
X417758Y146708D01*
X417675Y146458D01*
X417717Y146208D01*
X417883Y146000D01*
X418717Y145583D01*
X419092Y145292D01*
X419342Y144875D01*
X419425Y144500D01*
X417675D01*
G01X415450Y147000D02*
X415783Y146917D01*
X416033Y146708D01*
X416200Y146458D01*
X416325Y146125D01*
X416367Y145750D01*
X416325Y145375D01*
X416200Y145042D01*
X416033Y144792D01*
X415783Y144583D01*
X415450Y144500D01*
X415117Y144583D01*
X414867Y144792D01*
X414700Y145042D01*
X414575Y145375D01*
X414533Y145750D01*
X414575Y146125D01*
X414700Y146458D01*
X414867Y146708D01*
X415117Y146917D01*
X415450Y147000D01*
G01X413267Y144875D02*
X413017Y144667D01*
X412725Y144542D01*
X412350Y144500D01*
X411975Y144583D01*
X411683Y144750D01*
X411475Y145042D01*
X411433Y145375D01*
X411517Y145708D01*
X411725Y145917D01*
X412017Y146083D01*
X412308Y146125D01*
X412600Y146083D01*
X412975Y145917D01*
X412850Y147000D01*
X411725D01*
G01X420733Y142792D02*
X420983Y142917D01*
X421275Y143000D01*
X421608D01*
X421983Y142875D01*
X422275Y142667D01*
X422483Y142417D01*
X422650Y142000D01*
X422692Y141625D01*
X422608Y141250D01*
X422483Y141000D01*
X422233Y140750D01*
X421942Y140583D01*
X421650Y140500D01*
X421358D01*
X421067Y140583D01*
X420817Y140708D01*
X420608Y140875D01*
G01X419342Y142583D02*
X419092Y142833D01*
X418800Y142958D01*
X418467Y143000D01*
X418050Y142917D01*
X417758Y142708D01*
X417675Y142458D01*
X417717Y142208D01*
X417883Y142000D01*
X418717Y141583D01*
X419092Y141292D01*
X419342Y140875D01*
X419425Y140500D01*
X417675D01*
G01X415450D02*
Y143000D01*
X415950Y142500D01*
G01Y140500D02*
X414950D01*
G01X412350Y143000D02*
X412683Y142917D01*
X412933Y142708D01*
X413100Y142458D01*
X413225Y142125D01*
X413267Y141750D01*
X413225Y141375D01*
X413100Y141042D01*
X412933Y140792D01*
X412683Y140583D01*
X412350Y140500D01*
X412017Y140583D01*
X411767Y140792D01*
X411600Y141042D01*
X411475Y141375D01*
X411433Y141750D01*
X411475Y142125D01*
X411600Y142458D01*
X411767Y142708D01*
X412017Y142917D01*
X412350Y143000D01*
G01X414000Y153350D02*
X411500D01*
G01X414000Y152392D02*
Y154308D01*
G01X411500Y155617D02*
X414000D01*
Y156617D01*
X413875Y156950D01*
X413583Y157200D01*
X413250Y157283D01*
X412917Y157200D01*
X412667Y156992D01*
X412542Y156617D01*
Y155617D01*
G01X413583Y158758D02*
X413833Y159008D01*
X413958Y159300D01*
X414000Y159633D01*
X413917Y160050D01*
X413708Y160342D01*
X413458Y160425D01*
X413208Y160383D01*
X413000Y160217D01*
X412583Y159383D01*
X412292Y159008D01*
X411875Y158758D01*
X411500Y158675D01*
Y160425D01*
G01Y162567D02*
X412042Y162650D01*
X412500Y162775D01*
X412917Y162942D01*
X413375Y163150D01*
X414000Y163483D01*
Y161817D01*
G01X418667Y161643D02*
X416167D01*
G01X418667Y160685D02*
Y162601D01*
G01X416167Y163910D02*
X418667D01*
Y164910D01*
X418542Y165243D01*
X418250Y165493D01*
X417917Y165576D01*
X417584Y165493D01*
X417334Y165285D01*
X417209Y164910D01*
Y163910D01*
G01X418250Y167051D02*
X418500Y167301D01*
X418625Y167593D01*
X418667Y167926D01*
X418584Y168343D01*
X418375Y168635D01*
X418125Y168718D01*
X417875Y168676D01*
X417667Y168510D01*
X417250Y167676D01*
X416959Y167301D01*
X416542Y167051D01*
X416167Y166968D01*
Y168718D01*
G01Y171443D02*
X418667D01*
X416875Y169901D01*
Y171985D01*
G01X416150Y178077D02*
X418650D01*
Y179118D01*
X418525Y179452D01*
X418358Y179660D01*
X418025Y179743D01*
X417692Y179660D01*
X417483Y179410D01*
X417358Y179118D01*
Y178077D01*
G01Y179118D02*
X416150Y179743D01*
G01X416650Y181093D02*
X416358Y181343D01*
X416192Y181677D01*
X416150Y182052D01*
X416192Y182385D01*
X416400Y182718D01*
X416650Y182927D01*
X416900Y182968D01*
X417192Y182885D01*
X417400Y182593D01*
X417483Y182302D01*
Y181927D01*
G01Y182302D02*
X417608Y182552D01*
X417817Y182760D01*
X418067Y182843D01*
X418317Y182760D01*
X418525Y182552D01*
X418650Y182177D01*
X418608Y181802D01*
X418442Y181427D01*
G01X418650Y185110D02*
X418567Y184777D01*
X418358Y184527D01*
X418108Y184360D01*
X417775Y184235D01*
X417400Y184193D01*
X417025Y184235D01*
X416692Y184360D01*
X416442Y184527D01*
X416233Y184777D01*
X416150Y185110D01*
X416233Y185443D01*
X416442Y185693D01*
X416692Y185860D01*
X417025Y185985D01*
X417400Y186027D01*
X417775Y185985D01*
X418108Y185860D01*
X418358Y185693D01*
X418567Y185443D01*
X418650Y185110D01*
G01X416650Y187293D02*
X416358Y187543D01*
X416192Y187877D01*
X416150Y188252D01*
X416192Y188585D01*
X416400Y188918D01*
X416650Y189127D01*
X416900Y189168D01*
X417192Y189085D01*
X417400Y188793D01*
X417483Y188502D01*
Y188127D01*
G01Y188502D02*
X417608Y188752D01*
X417817Y188960D01*
X418067Y189043D01*
X418317Y188960D01*
X418525Y188752D01*
X418650Y188377D01*
X418608Y188002D01*
X418442Y187627D01*
G01X419792Y194267D02*
X419917Y194017D01*
X420000Y193725D01*
Y193392D01*
X419875Y193017D01*
X419667Y192725D01*
X419417Y192517D01*
X419000Y192350D01*
X418625Y192308D01*
X418250Y192392D01*
X418000Y192517D01*
X417750Y192767D01*
X417583Y193058D01*
X417500Y193350D01*
Y193642D01*
X417583Y193933D01*
X417708Y194183D01*
X417875Y194392D01*
G01X417500Y196450D02*
X420000D01*
X419500Y195950D01*
G01X417500D02*
Y196950D01*
G01X418000Y198633D02*
X417708Y198883D01*
X417542Y199217D01*
X417500Y199592D01*
X417542Y199925D01*
X417750Y200258D01*
X418000Y200467D01*
X418250Y200508D01*
X418542Y200425D01*
X418750Y200133D01*
X418833Y199842D01*
Y199467D01*
G01Y199842D02*
X418958Y200092D01*
X419167Y200300D01*
X419417Y200383D01*
X419667Y200300D01*
X419875Y200092D01*
X420000Y199717D01*
X419958Y199342D01*
X419792Y198967D01*
G01X417500Y202650D02*
X420000D01*
X419500Y202150D01*
G01X417500D02*
Y203150D01*
G01X418292Y214867D02*
X418417Y214617D01*
X418500Y214325D01*
Y213992D01*
X418375Y213617D01*
X418167Y213325D01*
X417917Y213117D01*
X417500Y212950D01*
X417125Y212908D01*
X416750Y212992D01*
X416500Y213117D01*
X416250Y213367D01*
X416083Y213658D01*
X416000Y213950D01*
Y214242D01*
X416083Y214533D01*
X416208Y214783D01*
X416375Y214992D01*
G01X416000Y217050D02*
X418500D01*
X418000Y216550D01*
G01X416000D02*
Y217550D01*
G01X416500Y219233D02*
X416208Y219483D01*
X416042Y219817D01*
X416000Y220192D01*
X416042Y220525D01*
X416250Y220858D01*
X416500Y221067D01*
X416750Y221108D01*
X417042Y221025D01*
X417250Y220733D01*
X417333Y220442D01*
Y220067D01*
G01Y220442D02*
X417458Y220692D01*
X417667Y220900D01*
X417917Y220983D01*
X418167Y220900D01*
X418375Y220692D01*
X418500Y220317D01*
X418458Y219942D01*
X418292Y219567D01*
G01X418500Y223250D02*
X418417Y222917D01*
X418208Y222667D01*
X417958Y222500D01*
X417625Y222375D01*
X417250Y222333D01*
X416875Y222375D01*
X416542Y222500D01*
X416292Y222667D01*
X416083Y222917D01*
X416000Y223250D01*
X416083Y223583D01*
X416292Y223833D01*
X416542Y224000D01*
X416875Y224125D01*
X417250Y224167D01*
X417625Y224125D01*
X417958Y224000D01*
X418208Y223833D01*
X418417Y223583D01*
X418500Y223250D01*
G01X422483Y226000D02*
Y228500D01*
X421442D01*
X421108Y228375D01*
X420900Y228208D01*
X420817Y227875D01*
X420900Y227542D01*
X421150Y227333D01*
X421442Y227208D01*
X422483D01*
G01X421442D02*
X420817Y226000D01*
G01X419342Y228083D02*
X419092Y228333D01*
X418800Y228458D01*
X418467Y228500D01*
X418050Y228417D01*
X417758Y228208D01*
X417675Y227958D01*
X417717Y227708D01*
X417883Y227500D01*
X418717Y227083D01*
X419092Y226792D01*
X419342Y226375D01*
X419425Y226000D01*
X417675D01*
G01X415450D02*
X415158Y226042D01*
X414825Y226167D01*
X414617Y226375D01*
X414533Y226667D01*
X414617Y226958D01*
X414867Y227208D01*
X415242Y227333D01*
X415658D01*
X415908Y227417D01*
X416117Y227625D01*
X416200Y227917D01*
X416075Y228208D01*
X415783Y228417D01*
X415450Y228500D01*
X415117Y228417D01*
X414825Y228208D01*
X414700Y227917D01*
X414783Y227625D01*
X414992Y227417D01*
X415242Y227333D01*
X415658D01*
X416033Y227208D01*
X416283Y226958D01*
X416367Y226667D01*
X416283Y226375D01*
X416075Y226167D01*
X415742Y226042D01*
X415450Y226000D01*
G01X413267Y226375D02*
X413017Y226167D01*
X412725Y226042D01*
X412350Y226000D01*
X411975Y226083D01*
X411683Y226250D01*
X411475Y226542D01*
X411433Y226875D01*
X411517Y227208D01*
X411725Y227417D01*
X412017Y227583D01*
X412308Y227625D01*
X412600Y227583D01*
X412975Y227417D01*
X412850Y228500D01*
X411725D01*
G01X417500Y252967D02*
X420000D01*
Y253967D01*
X419875Y254300D01*
X419583Y254550D01*
X419250Y254633D01*
X418917Y254550D01*
X418667Y254342D01*
X418542Y253967D01*
Y252967D01*
G01X419792Y257817D02*
X419917Y257567D01*
X420000Y257275D01*
Y256942D01*
X419875Y256567D01*
X419667Y256275D01*
X419417Y256067D01*
X419000Y255900D01*
X418625Y255858D01*
X418250Y255942D01*
X418000Y256067D01*
X417750Y256317D01*
X417583Y256608D01*
X417500Y256900D01*
Y257192D01*
X417583Y257483D01*
X417708Y257733D01*
X417875Y257942D01*
G01X417500Y260000D02*
X417542Y260292D01*
X417667Y260625D01*
X417875Y260833D01*
X418167Y260917D01*
X418458Y260833D01*
X418708Y260583D01*
X418833Y260208D01*
Y259792D01*
X418917Y259542D01*
X419125Y259333D01*
X419417Y259250D01*
X419708Y259375D01*
X419917Y259667D01*
X420000Y260000D01*
X419917Y260333D01*
X419708Y260625D01*
X419417Y260750D01*
X419125Y260667D01*
X418917Y260458D01*
X418833Y260208D01*
Y259792D01*
X418708Y259417D01*
X418458Y259167D01*
X418167Y259083D01*
X417875Y259167D01*
X417667Y259375D01*
X417542Y259708D01*
X417500Y260000D01*
G01X415333Y252700D02*
Y255200D01*
X414333D01*
X414000Y255075D01*
X413750Y254783D01*
X413667Y254450D01*
X413750Y254117D01*
X413958Y253867D01*
X414333Y253742D01*
X415333D01*
G01X412233Y252700D02*
Y255200D01*
X411192D01*
X410858Y255075D01*
X410650Y254908D01*
X410567Y254575D01*
X410650Y254242D01*
X410900Y254033D01*
X411192Y253908D01*
X412233D01*
G01X411192D02*
X410567Y252700D01*
G01X407800D02*
Y255200D01*
X409342Y253408D01*
X407258D01*
G01X414983Y258000D02*
Y260500D01*
X413983D01*
X413650Y260375D01*
X413400Y260083D01*
X413317Y259750D01*
X413400Y259417D01*
X413608Y259167D01*
X413983Y259042D01*
X414983D01*
G01X411883Y258000D02*
Y260500D01*
X410842D01*
X410508Y260375D01*
X410300Y260208D01*
X410217Y259875D01*
X410300Y259542D01*
X410550Y259333D01*
X410842Y259208D01*
X411883D01*
G01X410842D02*
X410217Y258000D01*
G01X407950D02*
Y260500D01*
X408450Y260000D01*
G01Y258000D02*
X407450D01*
G01X405767Y258375D02*
X405517Y258167D01*
X405225Y258042D01*
X404850Y258000D01*
X404475Y258083D01*
X404183Y258250D01*
X403975Y258542D01*
X403933Y258875D01*
X404017Y259208D01*
X404225Y259417D01*
X404517Y259583D01*
X404808Y259625D01*
X405100Y259583D01*
X405475Y259417D01*
X405350Y260500D01*
X404225D01*
G01X406500Y270067D02*
X409000D01*
Y271067D01*
X408875Y271400D01*
X408583Y271650D01*
X408250Y271733D01*
X407917Y271650D01*
X407667Y271442D01*
X407542Y271067D01*
Y270067D01*
G01X408792Y274917D02*
X408917Y274667D01*
X409000Y274375D01*
Y274042D01*
X408875Y273667D01*
X408667Y273375D01*
X408417Y273167D01*
X408000Y273000D01*
X407625Y272958D01*
X407250Y273042D01*
X407000Y273167D01*
X406750Y273417D01*
X406583Y273708D01*
X406500Y274000D01*
Y274292D01*
X406583Y274583D01*
X406708Y274833D01*
X406875Y275042D01*
G01X406500Y277600D02*
X409000D01*
X407208Y276058D01*
Y278142D01*
G01X423433Y263000D02*
Y265500D01*
X422433D01*
X422100Y265375D01*
X421850Y265083D01*
X421767Y264750D01*
X421850Y264417D01*
X422058Y264167D01*
X422433Y264042D01*
X423433D01*
G01X420333Y263000D02*
Y265500D01*
X419292D01*
X418958Y265375D01*
X418750Y265208D01*
X418667Y264875D01*
X418750Y264542D01*
X419000Y264333D01*
X419292Y264208D01*
X420333D01*
G01X419292D02*
X418667Y263000D01*
G01X417317Y263375D02*
X417067Y263167D01*
X416775Y263042D01*
X416400Y263000D01*
X416025Y263083D01*
X415733Y263250D01*
X415525Y263542D01*
X415483Y263875D01*
X415567Y264208D01*
X415775Y264417D01*
X416067Y264583D01*
X416358Y264625D01*
X416650Y264583D01*
X417025Y264417D01*
X416900Y265500D01*
X415775D01*
G01X441833Y283000D02*
X445167D01*
Y288000D01*
X441833D01*
G01X443167Y285583D02*
X445167D01*
G01X439650Y283000D02*
X436150Y288000D01*
G01X439650D02*
X436150Y283000D01*
G01X432300Y288000D02*
Y283000D01*
G01X434217Y288000D02*
X430383D01*
G01X429200Y281333D02*
X424200D01*
G01X420433Y285667D02*
X420100Y285917D01*
X419850Y286333D01*
X419683Y286917D01*
X419850Y287417D01*
X420183Y287750D01*
X420767Y288000D01*
X423017D01*
Y283000D01*
X420267D01*
X419683Y283333D01*
X419350Y283833D01*
X419183Y284417D01*
X419350Y285000D01*
X419850Y285500D01*
X420433Y285667D01*
X423017D01*
G01X417583Y283000D02*
X415500Y288000D01*
X413417Y283000D01*
G01X414167Y284750D02*
X416833D01*
G01X409900Y288000D02*
Y283000D01*
G01X411817Y288000D02*
X407983D01*
G01X428233Y18792D02*
X428483Y18917D01*
X428775Y19000D01*
X429108D01*
X429483Y18875D01*
X429775Y18667D01*
X429983Y18417D01*
X430150Y18000D01*
X430192Y17625D01*
X430108Y17250D01*
X429983Y17000D01*
X429733Y16750D01*
X429442Y16583D01*
X429150Y16500D01*
X428858D01*
X428567Y16583D01*
X428317Y16708D01*
X428108Y16875D01*
G01X426967Y17000D02*
X426717Y16708D01*
X426383Y16542D01*
X426008Y16500D01*
X425675Y16542D01*
X425342Y16750D01*
X425133Y17000D01*
X425092Y17250D01*
X425175Y17542D01*
X425467Y17750D01*
X425758Y17833D01*
X426133D01*
G01X425758D02*
X425508Y17958D01*
X425300Y18167D01*
X425217Y18417D01*
X425300Y18667D01*
X425508Y18875D01*
X425883Y19000D01*
X426258Y18958D01*
X426633Y18792D01*
G01X423867Y17000D02*
X423617Y16708D01*
X423283Y16542D01*
X422908Y16500D01*
X422575Y16542D01*
X422242Y16750D01*
X422033Y17000D01*
X421992Y17250D01*
X422075Y17542D01*
X422367Y17750D01*
X422658Y17833D01*
X423033D01*
G01X422658D02*
X422408Y17958D01*
X422200Y18167D01*
X422117Y18417D01*
X422200Y18667D01*
X422408Y18875D01*
X422783Y19000D01*
X423158Y18958D01*
X423533Y18792D01*
G01X419933Y16500D02*
X419850Y17042D01*
X419725Y17500D01*
X419558Y17917D01*
X419350Y18375D01*
X419017Y19000D01*
X420683D01*
G01X429983Y21000D02*
Y23500D01*
X428942D01*
X428608Y23375D01*
X428400Y23208D01*
X428317Y22875D01*
X428400Y22542D01*
X428650Y22333D01*
X428942Y22208D01*
X429983D01*
G01X428942D02*
X428317Y21000D01*
G01X425550D02*
Y23500D01*
X427092Y21708D01*
X425008D01*
G01X423742Y22042D02*
X423450Y22333D01*
X423200Y22500D01*
X422867Y22583D01*
X422575Y22500D01*
X422367Y22333D01*
X422200Y22083D01*
X422158Y21792D01*
X422200Y21542D01*
X422367Y21292D01*
X422617Y21083D01*
X422908Y21000D01*
X423242Y21083D01*
X423533Y21333D01*
X423700Y21708D01*
X423742Y22125D01*
X423658Y22667D01*
X423533Y22958D01*
X423325Y23250D01*
X423033Y23458D01*
X422742Y23500D01*
X422450Y23417D01*
X422242Y23208D01*
G01X419850Y21000D02*
X419558Y21042D01*
X419225Y21167D01*
X419017Y21375D01*
X418933Y21667D01*
X419017Y21958D01*
X419267Y22208D01*
X419642Y22333D01*
X420058D01*
X420308Y22417D01*
X420517Y22625D01*
X420600Y22917D01*
X420475Y23208D01*
X420183Y23417D01*
X419850Y23500D01*
X419517Y23417D01*
X419225Y23208D01*
X419100Y22917D01*
X419183Y22625D01*
X419392Y22417D01*
X419642Y22333D01*
X420058D01*
X420433Y22208D01*
X420683Y21958D01*
X420767Y21667D01*
X420683Y21375D01*
X420475Y21167D01*
X420142Y21042D01*
X419850Y21000D01*
G01X432000Y37017D02*
X434500D01*
Y38058D01*
X434375Y38392D01*
X434208Y38600D01*
X433875Y38683D01*
X433542Y38600D01*
X433333Y38350D01*
X433208Y38058D01*
Y37017D01*
G01Y38058D02*
X432000Y38683D01*
G01Y41450D02*
X434500D01*
X432708Y39908D01*
Y41992D01*
G01X433042Y43258D02*
X433333Y43550D01*
X433500Y43800D01*
X433583Y44133D01*
X433500Y44425D01*
X433333Y44633D01*
X433083Y44800D01*
X432792Y44842D01*
X432542Y44800D01*
X432292Y44633D01*
X432083Y44383D01*
X432000Y44092D01*
X432083Y43758D01*
X432333Y43467D01*
X432708Y43300D01*
X433125Y43258D01*
X433667Y43342D01*
X433958Y43467D01*
X434250Y43675D01*
X434458Y43967D01*
X434500Y44258D01*
X434417Y44550D01*
X434208Y44758D01*
G01X432000Y47067D02*
X432542Y47150D01*
X433000Y47275D01*
X433417Y47442D01*
X433875Y47650D01*
X434500Y47983D01*
Y46317D01*
G01X423500Y57017D02*
X426000D01*
Y58058D01*
X425875Y58392D01*
X425708Y58600D01*
X425375Y58683D01*
X425042Y58600D01*
X424833Y58350D01*
X424708Y58058D01*
Y57017D01*
G01Y58058D02*
X423500Y58683D01*
G01Y61450D02*
X426000D01*
X424208Y59908D01*
Y61992D01*
G01X424542Y63258D02*
X424833Y63550D01*
X425000Y63800D01*
X425083Y64133D01*
X425000Y64425D01*
X424833Y64633D01*
X424583Y64800D01*
X424292Y64842D01*
X424042Y64800D01*
X423792Y64633D01*
X423583Y64383D01*
X423500Y64092D01*
X423583Y63758D01*
X423833Y63467D01*
X424208Y63300D01*
X424625Y63258D01*
X425167Y63342D01*
X425458Y63467D01*
X425750Y63675D01*
X425958Y63967D01*
X426000Y64258D01*
X425917Y64550D01*
X425708Y64758D01*
G01X424542Y66358D02*
X424833Y66650D01*
X425000Y66900D01*
X425083Y67233D01*
X425000Y67525D01*
X424833Y67733D01*
X424583Y67900D01*
X424292Y67942D01*
X424042Y67900D01*
X423792Y67733D01*
X423583Y67483D01*
X423500Y67192D01*
X423583Y66858D01*
X423833Y66567D01*
X424208Y66400D01*
X424625Y66358D01*
X425167Y66442D01*
X425458Y66567D01*
X425750Y66775D01*
X425958Y67067D01*
X426000Y67358D01*
X425917Y67650D01*
X425708Y67858D01*
G01X434383Y80000D02*
Y77500D01*
X432717D01*
G01X430450D02*
X430158Y77542D01*
X429825Y77667D01*
X429617Y77875D01*
X429533Y78167D01*
X429617Y78458D01*
X429867Y78708D01*
X430242Y78833D01*
X430658D01*
X430908Y78917D01*
X431117Y79125D01*
X431200Y79417D01*
X431075Y79708D01*
X430783Y79917D01*
X430450Y80000D01*
X430117Y79917D01*
X429825Y79708D01*
X429700Y79417D01*
X429783Y79125D01*
X429992Y78917D01*
X430242Y78833D01*
X430658D01*
X431033Y78708D01*
X431283Y78458D01*
X431367Y78167D01*
X431283Y77875D01*
X431075Y77667D01*
X430742Y77542D01*
X430450Y77500D01*
G01X432792Y105767D02*
X432917Y105517D01*
X433000Y105225D01*
Y104892D01*
X432875Y104517D01*
X432667Y104225D01*
X432417Y104017D01*
X432000Y103850D01*
X431625Y103808D01*
X431250Y103892D01*
X431000Y104017D01*
X430750Y104267D01*
X430583Y104558D01*
X430500Y104850D01*
Y105142D01*
X430583Y105433D01*
X430708Y105683D01*
X430875Y105892D01*
G01X432583Y107158D02*
X432833Y107408D01*
X432958Y107700D01*
X433000Y108033D01*
X432917Y108450D01*
X432708Y108742D01*
X432458Y108825D01*
X432208Y108783D01*
X432000Y108617D01*
X431583Y107783D01*
X431292Y107408D01*
X430875Y107158D01*
X430500Y107075D01*
Y108825D01*
G01X431000Y110133D02*
X430708Y110383D01*
X430542Y110717D01*
X430500Y111092D01*
X430542Y111425D01*
X430750Y111758D01*
X431000Y111967D01*
X431250Y112008D01*
X431542Y111925D01*
X431750Y111633D01*
X431833Y111342D01*
Y110967D01*
G01Y111342D02*
X431958Y111592D01*
X432167Y111800D01*
X432417Y111883D01*
X432667Y111800D01*
X432875Y111592D01*
X433000Y111217D01*
X432958Y110842D01*
X432792Y110467D01*
G01X430500Y114067D02*
X431042Y114150D01*
X431500Y114275D01*
X431917Y114442D01*
X432375Y114650D01*
X433000Y114983D01*
Y113317D01*
G01X427292Y93267D02*
X427417Y93017D01*
X427500Y92725D01*
Y92392D01*
X427375Y92017D01*
X427167Y91725D01*
X426917Y91517D01*
X426500Y91350D01*
X426125Y91308D01*
X425750Y91392D01*
X425500Y91517D01*
X425250Y91767D01*
X425083Y92058D01*
X425000Y92350D01*
Y92642D01*
X425083Y92933D01*
X425208Y93183D01*
X425375Y93392D01*
G01X427083Y94658D02*
X427333Y94908D01*
X427458Y95200D01*
X427500Y95533D01*
X427417Y95950D01*
X427208Y96242D01*
X426958Y96325D01*
X426708Y96283D01*
X426500Y96117D01*
X426083Y95283D01*
X425792Y94908D01*
X425375Y94658D01*
X425000Y94575D01*
Y96325D01*
G01X425500Y97633D02*
X425208Y97883D01*
X425042Y98217D01*
X425000Y98592D01*
X425042Y98925D01*
X425250Y99258D01*
X425500Y99467D01*
X425750Y99508D01*
X426042Y99425D01*
X426250Y99133D01*
X426333Y98842D01*
Y98467D01*
G01Y98842D02*
X426458Y99092D01*
X426667Y99300D01*
X426917Y99383D01*
X427167Y99300D01*
X427375Y99092D01*
X427500Y98717D01*
X427458Y98342D01*
X427292Y97967D01*
G01X425000Y101650D02*
X425042Y101942D01*
X425167Y102275D01*
X425375Y102483D01*
X425667Y102567D01*
X425958Y102483D01*
X426208Y102233D01*
X426333Y101858D01*
Y101442D01*
X426417Y101192D01*
X426625Y100983D01*
X426917Y100900D01*
X427208Y101025D01*
X427417Y101317D01*
X427500Y101650D01*
X427417Y101983D01*
X427208Y102275D01*
X426917Y102400D01*
X426625Y102317D01*
X426417Y102108D01*
X426333Y101858D01*
Y101442D01*
X426208Y101067D01*
X425958Y100817D01*
X425667Y100733D01*
X425375Y100817D01*
X425167Y101025D01*
X425042Y101358D01*
X425000Y101650D01*
G01X423292Y93267D02*
X423417Y93017D01*
X423500Y92725D01*
Y92392D01*
X423375Y92017D01*
X423167Y91725D01*
X422917Y91517D01*
X422500Y91350D01*
X422125Y91308D01*
X421750Y91392D01*
X421500Y91517D01*
X421250Y91767D01*
X421083Y92058D01*
X421000Y92350D01*
Y92642D01*
X421083Y92933D01*
X421208Y93183D01*
X421375Y93392D01*
G01X423083Y94658D02*
X423333Y94908D01*
X423458Y95200D01*
X423500Y95533D01*
X423417Y95950D01*
X423208Y96242D01*
X422958Y96325D01*
X422708Y96283D01*
X422500Y96117D01*
X422083Y95283D01*
X421792Y94908D01*
X421375Y94658D01*
X421000Y94575D01*
Y96325D01*
G01X421500Y97633D02*
X421208Y97883D01*
X421042Y98217D01*
X421000Y98592D01*
X421042Y98925D01*
X421250Y99258D01*
X421500Y99467D01*
X421750Y99508D01*
X422042Y99425D01*
X422250Y99133D01*
X422333Y98842D01*
Y98467D01*
G01Y98842D02*
X422458Y99092D01*
X422667Y99300D01*
X422917Y99383D01*
X423167Y99300D01*
X423375Y99092D01*
X423500Y98717D01*
X423458Y98342D01*
X423292Y97967D01*
G01X421292Y100942D02*
X421083Y101233D01*
X421000Y101567D01*
X421083Y101900D01*
X421333Y102192D01*
X421708Y102400D01*
X422083Y102483D01*
X422542D01*
X422917Y102400D01*
X423250Y102192D01*
X423417Y101942D01*
X423500Y101650D01*
X423417Y101317D01*
X423250Y101067D01*
X423000Y100900D01*
X422667Y100817D01*
X422375Y100900D01*
X422083Y101108D01*
X421917Y101358D01*
X421875Y101650D01*
X421958Y101983D01*
X422167Y102233D01*
X422542Y102483D01*
G01X443983Y130500D02*
Y133000D01*
X442942D01*
X442608Y132875D01*
X442400Y132708D01*
X442317Y132375D01*
X442400Y132042D01*
X442650Y131833D01*
X442942Y131708D01*
X443983D01*
G01X442942D02*
X442317Y130500D01*
G01X440967Y131000D02*
X440717Y130708D01*
X440383Y130542D01*
X440008Y130500D01*
X439675Y130542D01*
X439342Y130750D01*
X439133Y131000D01*
X439092Y131250D01*
X439175Y131542D01*
X439467Y131750D01*
X439758Y131833D01*
X440133D01*
G01X439758D02*
X439508Y131958D01*
X439300Y132167D01*
X439217Y132417D01*
X439300Y132667D01*
X439508Y132875D01*
X439883Y133000D01*
X440258Y132958D01*
X440633Y132792D01*
G01X437867Y130875D02*
X437617Y130667D01*
X437325Y130542D01*
X436950Y130500D01*
X436575Y130583D01*
X436283Y130750D01*
X436075Y131042D01*
X436033Y131375D01*
X436117Y131708D01*
X436325Y131917D01*
X436617Y132083D01*
X436908Y132125D01*
X437200Y132083D01*
X437575Y131917D01*
X437450Y133000D01*
X436325D01*
G01X434767Y131000D02*
X434517Y130708D01*
X434183Y130542D01*
X433808Y130500D01*
X433475Y130542D01*
X433142Y130750D01*
X432933Y131000D01*
X432892Y131250D01*
X432975Y131542D01*
X433267Y131750D01*
X433558Y131833D01*
X433933D01*
G01X433558D02*
X433308Y131958D01*
X433100Y132167D01*
X433017Y132417D01*
X433100Y132667D01*
X433308Y132875D01*
X433683Y133000D01*
X434058Y132958D01*
X434433Y132792D01*
G01X431292Y145267D02*
X431417Y145017D01*
X431500Y144725D01*
Y144392D01*
X431375Y144017D01*
X431167Y143725D01*
X430917Y143517D01*
X430500Y143350D01*
X430125Y143308D01*
X429750Y143392D01*
X429500Y143517D01*
X429250Y143767D01*
X429083Y144058D01*
X429000Y144350D01*
Y144642D01*
X429083Y144933D01*
X429208Y145183D01*
X429375Y145392D01*
G01X429000Y147450D02*
X431500D01*
X431000Y146950D01*
G01X429000D02*
Y147950D01*
G01X429292Y149842D02*
X429083Y150133D01*
X429000Y150467D01*
X429083Y150800D01*
X429333Y151092D01*
X429708Y151300D01*
X430083Y151383D01*
X430542D01*
X430917Y151300D01*
X431250Y151092D01*
X431417Y150842D01*
X431500Y150550D01*
X431417Y150217D01*
X431250Y149967D01*
X431000Y149800D01*
X430667Y149717D01*
X430375Y149800D01*
X430083Y150008D01*
X429917Y150258D01*
X429875Y150550D01*
X429958Y150883D01*
X430167Y151133D01*
X430542Y151383D01*
G01X429000Y154150D02*
X431500D01*
X429708Y152608D01*
Y154692D01*
G01X436233Y141292D02*
X436483Y141417D01*
X436775Y141500D01*
X437108D01*
X437483Y141375D01*
X437775Y141167D01*
X437983Y140917D01*
X438150Y140500D01*
X438192Y140125D01*
X438108Y139750D01*
X437983Y139500D01*
X437733Y139250D01*
X437442Y139083D01*
X437150Y139000D01*
X436858D01*
X436567Y139083D01*
X436317Y139208D01*
X436108Y139375D01*
G01X434050Y139000D02*
Y141500D01*
X434550Y141000D01*
G01Y139000D02*
X433550D01*
G01X431658Y139292D02*
X431367Y139083D01*
X431033Y139000D01*
X430700Y139083D01*
X430408Y139333D01*
X430200Y139708D01*
X430117Y140083D01*
Y140542D01*
X430200Y140917D01*
X430408Y141250D01*
X430658Y141417D01*
X430950Y141500D01*
X431283Y141417D01*
X431533Y141250D01*
X431700Y141000D01*
X431783Y140667D01*
X431700Y140375D01*
X431492Y140083D01*
X431242Y139917D01*
X430950Y139875D01*
X430617Y139958D01*
X430367Y140167D01*
X430117Y140542D01*
G01X428767Y139375D02*
X428517Y139167D01*
X428225Y139042D01*
X427850Y139000D01*
X427475Y139083D01*
X427183Y139250D01*
X426975Y139542D01*
X426933Y139875D01*
X427017Y140208D01*
X427225Y140417D01*
X427517Y140583D01*
X427808Y140625D01*
X428100Y140583D01*
X428475Y140417D01*
X428350Y141500D01*
X427225D01*
G01X429292Y159267D02*
X429417Y159017D01*
X429500Y158725D01*
Y158392D01*
X429375Y158017D01*
X429167Y157725D01*
X428917Y157517D01*
X428500Y157350D01*
X428125Y157308D01*
X427750Y157392D01*
X427500Y157517D01*
X427250Y157767D01*
X427083Y158058D01*
X427000Y158350D01*
Y158642D01*
X427083Y158933D01*
X427208Y159183D01*
X427375Y159392D01*
G01X427000Y161450D02*
X429500D01*
X429000Y160950D01*
G01X427000D02*
Y161950D01*
G01Y164467D02*
X427542Y164550D01*
X428000Y164675D01*
X428417Y164842D01*
X428875Y165050D01*
X429500Y165383D01*
Y163717D01*
G01X427375Y166733D02*
X427167Y166983D01*
X427042Y167275D01*
X427000Y167650D01*
X427083Y168025D01*
X427250Y168317D01*
X427542Y168525D01*
X427875Y168567D01*
X428208Y168483D01*
X428417Y168275D01*
X428583Y167983D01*
X428625Y167692D01*
X428583Y167400D01*
X428417Y167025D01*
X429500Y167150D01*
Y168275D01*
G01X426292Y179267D02*
X426417Y179017D01*
X426500Y178725D01*
Y178392D01*
X426375Y178017D01*
X426167Y177725D01*
X425917Y177517D01*
X425500Y177350D01*
X425125Y177308D01*
X424750Y177392D01*
X424500Y177517D01*
X424250Y177767D01*
X424083Y178058D01*
X424000Y178350D01*
Y178642D01*
X424083Y178933D01*
X424208Y179183D01*
X424375Y179392D01*
G01X424000Y181450D02*
X426500D01*
X426000Y180950D01*
G01X424000D02*
Y181950D01*
G01Y185050D02*
X426500D01*
X424708Y183508D01*
Y185592D01*
G01X424000Y187650D02*
X424042Y187942D01*
X424167Y188275D01*
X424375Y188483D01*
X424667Y188567D01*
X424958Y188483D01*
X425208Y188233D01*
X425333Y187858D01*
Y187442D01*
X425417Y187192D01*
X425625Y186983D01*
X425917Y186900D01*
X426208Y187025D01*
X426417Y187317D01*
X426500Y187650D01*
X426417Y187983D01*
X426208Y188275D01*
X425917Y188400D01*
X425625Y188317D01*
X425417Y188108D01*
X425333Y187858D01*
Y187442D01*
X425208Y187067D01*
X424958Y186817D01*
X424667Y186733D01*
X424375Y186817D01*
X424167Y187025D01*
X424042Y187358D01*
X424000Y187650D01*
G01X434292Y174267D02*
X434417Y174017D01*
X434500Y173725D01*
Y173392D01*
X434375Y173017D01*
X434167Y172725D01*
X433917Y172517D01*
X433500Y172350D01*
X433125Y172308D01*
X432750Y172392D01*
X432500Y172517D01*
X432250Y172767D01*
X432083Y173058D01*
X432000Y173350D01*
Y173642D01*
X432083Y173933D01*
X432208Y174183D01*
X432375Y174392D01*
G01X432000Y176450D02*
X434500D01*
X434000Y175950D01*
G01X432000D02*
Y176950D01*
G01X432292Y178842D02*
X432083Y179133D01*
X432000Y179467D01*
X432083Y179800D01*
X432333Y180092D01*
X432708Y180300D01*
X433083Y180383D01*
X433542D01*
X433917Y180300D01*
X434250Y180092D01*
X434417Y179842D01*
X434500Y179550D01*
X434417Y179217D01*
X434250Y178967D01*
X434000Y178800D01*
X433667Y178717D01*
X433375Y178800D01*
X433083Y179008D01*
X432917Y179258D01*
X432875Y179550D01*
X432958Y179883D01*
X433167Y180133D01*
X433542Y180383D01*
G01X432500Y181733D02*
X432208Y181983D01*
X432042Y182317D01*
X432000Y182692D01*
X432042Y183025D01*
X432250Y183358D01*
X432500Y183567D01*
X432750Y183608D01*
X433042Y183525D01*
X433250Y183233D01*
X433333Y182942D01*
Y182567D01*
G01Y182942D02*
X433458Y183192D01*
X433667Y183400D01*
X433917Y183483D01*
X434167Y183400D01*
X434375Y183192D01*
X434500Y182817D01*
X434458Y182442D01*
X434292Y182067D01*
G01X442733Y194292D02*
X442983Y194417D01*
X443275Y194500D01*
X443608D01*
X443983Y194375D01*
X444275Y194167D01*
X444483Y193917D01*
X444650Y193500D01*
X444692Y193125D01*
X444608Y192750D01*
X444483Y192500D01*
X444233Y192250D01*
X443942Y192083D01*
X443650Y192000D01*
X443358D01*
X443067Y192083D01*
X442817Y192208D01*
X442608Y192375D01*
G01X440550Y192000D02*
Y194500D01*
X441050Y194000D01*
G01Y192000D02*
X440050D01*
G01X436950D02*
Y194500D01*
X438492Y192708D01*
X436408D01*
G01X435142Y194083D02*
X434892Y194333D01*
X434600Y194458D01*
X434267Y194500D01*
X433850Y194417D01*
X433558Y194208D01*
X433475Y193958D01*
X433517Y193708D01*
X433683Y193500D01*
X434517Y193083D01*
X434892Y192792D01*
X435142Y192375D01*
X435225Y192000D01*
X433475D01*
G01X424792Y193767D02*
X424917Y193517D01*
X425000Y193225D01*
Y192892D01*
X424875Y192517D01*
X424667Y192225D01*
X424417Y192017D01*
X424000Y191850D01*
X423625Y191808D01*
X423250Y191892D01*
X423000Y192017D01*
X422750Y192267D01*
X422583Y192558D01*
X422500Y192850D01*
Y193142D01*
X422583Y193433D01*
X422708Y193683D01*
X422875Y193892D01*
G01X422500Y195950D02*
X425000D01*
X424500Y195450D01*
G01X422500D02*
Y196450D01*
G01X424583Y198258D02*
X424833Y198508D01*
X424958Y198800D01*
X425000Y199133D01*
X424917Y199550D01*
X424708Y199842D01*
X424458Y199925D01*
X424208Y199883D01*
X424000Y199717D01*
X423583Y198883D01*
X423292Y198508D01*
X422875Y198258D01*
X422500Y198175D01*
Y199925D01*
G01Y202067D02*
X423042Y202150D01*
X423500Y202275D01*
X423917Y202442D01*
X424375Y202650D01*
X425000Y202983D01*
Y201317D01*
G01X422792Y214867D02*
X422917Y214617D01*
X423000Y214325D01*
Y213992D01*
X422875Y213617D01*
X422667Y213325D01*
X422417Y213117D01*
X422000Y212950D01*
X421625Y212908D01*
X421250Y212992D01*
X421000Y213117D01*
X420750Y213367D01*
X420583Y213658D01*
X420500Y213950D01*
Y214242D01*
X420583Y214533D01*
X420708Y214783D01*
X420875Y214992D01*
G01X420500Y217050D02*
X423000D01*
X422500Y216550D01*
G01X420500D02*
Y217550D01*
G01X422583Y219358D02*
X422833Y219608D01*
X422958Y219900D01*
X423000Y220233D01*
X422917Y220650D01*
X422708Y220942D01*
X422458Y221025D01*
X422208Y220983D01*
X422000Y220817D01*
X421583Y219983D01*
X421292Y219608D01*
X420875Y219358D01*
X420500Y219275D01*
Y221025D01*
G01X420792Y222542D02*
X420583Y222833D01*
X420500Y223167D01*
X420583Y223500D01*
X420833Y223792D01*
X421208Y224000D01*
X421583Y224083D01*
X422042D01*
X422417Y224000D01*
X422750Y223792D01*
X422917Y223542D01*
X423000Y223250D01*
X422917Y222917D01*
X422750Y222667D01*
X422500Y222500D01*
X422167Y222417D01*
X421875Y222500D01*
X421583Y222708D01*
X421417Y222958D01*
X421375Y223250D01*
X421458Y223583D01*
X421667Y223833D01*
X422042Y224083D01*
G01X427792Y214767D02*
X427917Y214517D01*
X428000Y214225D01*
Y213892D01*
X427875Y213517D01*
X427667Y213225D01*
X427417Y213017D01*
X427000Y212850D01*
X426625Y212808D01*
X426250Y212892D01*
X426000Y213017D01*
X425750Y213267D01*
X425583Y213558D01*
X425500Y213850D01*
Y214142D01*
X425583Y214433D01*
X425708Y214683D01*
X425875Y214892D01*
G01X425500Y216950D02*
X428000D01*
X427500Y216450D01*
G01X425500D02*
Y217450D01*
G01X427583Y219258D02*
X427833Y219508D01*
X427958Y219800D01*
X428000Y220133D01*
X427917Y220550D01*
X427708Y220842D01*
X427458Y220925D01*
X427208Y220883D01*
X427000Y220717D01*
X426583Y219883D01*
X426292Y219508D01*
X425875Y219258D01*
X425500Y219175D01*
Y220925D01*
G01Y223150D02*
X425542Y223442D01*
X425667Y223775D01*
X425875Y223983D01*
X426167Y224067D01*
X426458Y223983D01*
X426708Y223733D01*
X426833Y223358D01*
Y222942D01*
X426917Y222692D01*
X427125Y222483D01*
X427417Y222400D01*
X427708Y222525D01*
X427917Y222817D01*
X428000Y223150D01*
X427917Y223483D01*
X427708Y223775D01*
X427417Y223900D01*
X427125Y223817D01*
X426917Y223608D01*
X426833Y223358D01*
Y222942D01*
X426708Y222567D01*
X426458Y222317D01*
X426167Y222233D01*
X425875Y222317D01*
X425667Y222525D01*
X425542Y222858D01*
X425500Y223150D01*
G01X431792Y214767D02*
X431917Y214517D01*
X432000Y214225D01*
Y213892D01*
X431875Y213517D01*
X431667Y213225D01*
X431417Y213017D01*
X431000Y212850D01*
X430625Y212808D01*
X430250Y212892D01*
X430000Y213017D01*
X429750Y213267D01*
X429583Y213558D01*
X429500Y213850D01*
Y214142D01*
X429583Y214433D01*
X429708Y214683D01*
X429875Y214892D01*
G01X429500Y216950D02*
X432000D01*
X431500Y216450D01*
G01X429500D02*
Y217450D01*
G01X431583Y219258D02*
X431833Y219508D01*
X431958Y219800D01*
X432000Y220133D01*
X431917Y220550D01*
X431708Y220842D01*
X431458Y220925D01*
X431208Y220883D01*
X431000Y220717D01*
X430583Y219883D01*
X430292Y219508D01*
X429875Y219258D01*
X429500Y219175D01*
Y220925D01*
G01X430000Y222233D02*
X429708Y222483D01*
X429542Y222817D01*
X429500Y223192D01*
X429542Y223525D01*
X429750Y223858D01*
X430000Y224067D01*
X430250Y224108D01*
X430542Y224025D01*
X430750Y223733D01*
X430833Y223442D01*
Y223067D01*
G01Y223442D02*
X430958Y223692D01*
X431167Y223900D01*
X431417Y223983D01*
X431667Y223900D01*
X431875Y223692D01*
X432000Y223317D01*
X431958Y222942D01*
X431792Y222567D01*
G01X433733Y228292D02*
X433983Y228417D01*
X434275Y228500D01*
X434608D01*
X434983Y228375D01*
X435275Y228167D01*
X435483Y227917D01*
X435650Y227500D01*
X435692Y227125D01*
X435608Y226750D01*
X435483Y226500D01*
X435233Y226250D01*
X434942Y226083D01*
X434650Y226000D01*
X434358D01*
X434067Y226083D01*
X433817Y226208D01*
X433608Y226375D01*
G01X431550Y226000D02*
Y228500D01*
X432050Y228000D01*
G01Y226000D02*
X431050D01*
G01X427950D02*
Y228500D01*
X429492Y226708D01*
X427408D01*
G01X425350Y226000D02*
Y228500D01*
X425850Y228000D01*
G01Y226000D02*
X424850D01*
G01X421500Y252967D02*
X424000D01*
Y253967D01*
X423875Y254300D01*
X423583Y254550D01*
X423250Y254633D01*
X422917Y254550D01*
X422667Y254342D01*
X422542Y253967D01*
Y252967D01*
G01X422750Y257150D02*
Y257983D01*
X422000D01*
X421750Y257733D01*
X421583Y257442D01*
X421500Y257025D01*
X421583Y256608D01*
X421750Y256317D01*
X422000Y256067D01*
X422292Y255900D01*
X422625Y255817D01*
X422917D01*
X423167Y255900D01*
X423458Y256067D01*
X423708Y256317D01*
X423875Y256567D01*
X424000Y256900D01*
Y257192D01*
X423917Y257525D01*
X423750Y257775D01*
G01X421500Y260000D02*
X424000D01*
X423500Y259500D01*
G01X421500D02*
Y260500D01*
G01X432183Y276292D02*
X432433Y276417D01*
X432725Y276500D01*
X433058D01*
X433433Y276375D01*
X433725Y276167D01*
X433933Y275917D01*
X434100Y275500D01*
X434142Y275125D01*
X434058Y274750D01*
X433933Y274500D01*
X433683Y274250D01*
X433392Y274083D01*
X433100Y274000D01*
X432808D01*
X432517Y274083D01*
X432267Y274208D01*
X432058Y274375D01*
G01X430958Y274000D02*
Y276500D01*
X429042Y274000D01*
Y276500D01*
G01X426983Y274000D02*
X426900Y274542D01*
X426775Y275000D01*
X426608Y275417D01*
X426400Y275875D01*
X426067Y276500D01*
X427733D01*
G01X445450Y27200D02*
Y29800D01*
G01X437550Y27200D02*
X445450D01*
G01X437550Y29800D02*
Y27200D01*
G01X445450Y29800D02*
X437550D01*
G01X458483Y35000D02*
Y37500D01*
X457442D01*
X457108Y37375D01*
X456900Y37208D01*
X456817Y36875D01*
X456900Y36542D01*
X457150Y36333D01*
X457442Y36208D01*
X458483D01*
G01X457442D02*
X456817Y35000D01*
G01X454050D02*
Y37500D01*
X455592Y35708D01*
X453508D01*
G01X451533Y35000D02*
X451450Y35542D01*
X451325Y36000D01*
X451158Y36417D01*
X450950Y36875D01*
X450617Y37500D01*
X452283D01*
G01X448350Y35000D02*
X448058Y35042D01*
X447725Y35167D01*
X447517Y35375D01*
X447433Y35667D01*
X447517Y35958D01*
X447767Y36208D01*
X448142Y36333D01*
X448558D01*
X448808Y36417D01*
X449017Y36625D01*
X449100Y36917D01*
X448975Y37208D01*
X448683Y37417D01*
X448350Y37500D01*
X448017Y37417D01*
X447725Y37208D01*
X447600Y36917D01*
X447683Y36625D01*
X447892Y36417D01*
X448142Y36333D01*
X448558D01*
X448933Y36208D01*
X449183Y35958D01*
X449267Y35667D01*
X449183Y35375D01*
X448975Y35167D01*
X448642Y35042D01*
X448350Y35000D01*
G01X435000Y91500D02*
Y102000D01*
X470500D01*
Y76500D01*
X436500D01*
G01X451533Y83000D02*
Y85500D01*
X450533D01*
X450200Y85375D01*
X449950Y85083D01*
X449867Y84750D01*
X449950Y84417D01*
X450158Y84167D01*
X450533Y84042D01*
X451533D01*
G01X446683Y85292D02*
X446933Y85417D01*
X447225Y85500D01*
X447558D01*
X447933Y85375D01*
X448225Y85167D01*
X448433Y84917D01*
X448600Y84500D01*
X448642Y84125D01*
X448558Y83750D01*
X448433Y83500D01*
X448183Y83250D01*
X447892Y83083D01*
X447600Y83000D01*
X447308D01*
X447017Y83083D01*
X446767Y83208D01*
X446558Y83375D01*
G01X444500Y83000D02*
Y85500D01*
X445000Y85000D01*
G01Y83000D02*
X444000D01*
G01X442108Y83292D02*
X441817Y83083D01*
X441483Y83000D01*
X441150Y83083D01*
X440858Y83333D01*
X440650Y83708D01*
X440567Y84083D01*
Y84542D01*
X440650Y84917D01*
X440858Y85250D01*
X441108Y85417D01*
X441400Y85500D01*
X441733Y85417D01*
X441983Y85250D01*
X442150Y85000D01*
X442233Y84667D01*
X442150Y84375D01*
X441942Y84083D01*
X441692Y83917D01*
X441400Y83875D01*
X441067Y83958D01*
X440817Y84167D01*
X440567Y84542D01*
G01X438383Y83000D02*
X438300Y83542D01*
X438175Y84000D01*
X438008Y84417D01*
X437800Y84875D01*
X437467Y85500D01*
X439133D01*
G01X451533Y87000D02*
Y89500D01*
X450533D01*
X450200Y89375D01*
X449950Y89083D01*
X449867Y88750D01*
X449950Y88417D01*
X450158Y88167D01*
X450533Y88042D01*
X451533D01*
G01X448433Y87000D02*
Y89500D01*
X447392D01*
X447058Y89375D01*
X446850Y89208D01*
X446767Y88875D01*
X446850Y88542D01*
X447100Y88333D01*
X447392Y88208D01*
X448433D01*
G01X447392D02*
X446767Y87000D01*
G01X445292Y89083D02*
X445042Y89333D01*
X444750Y89458D01*
X444417Y89500D01*
X444000Y89417D01*
X443708Y89208D01*
X443625Y88958D01*
X443667Y88708D01*
X443833Y88500D01*
X444667Y88083D01*
X445042Y87792D01*
X445292Y87375D01*
X445375Y87000D01*
X443625D01*
G01X442192Y89083D02*
X441942Y89333D01*
X441650Y89458D01*
X441317Y89500D01*
X440900Y89417D01*
X440608Y89208D01*
X440525Y88958D01*
X440567Y88708D01*
X440733Y88500D01*
X441567Y88083D01*
X441942Y87792D01*
X442192Y87375D01*
X442275Y87000D01*
X440525D01*
G01X439217Y87500D02*
X438967Y87208D01*
X438633Y87042D01*
X438258Y87000D01*
X437925Y87042D01*
X437592Y87250D01*
X437383Y87500D01*
X437342Y87750D01*
X437425Y88042D01*
X437717Y88250D01*
X438008Y88333D01*
X438383D01*
G01X438008D02*
X437758Y88458D01*
X437550Y88667D01*
X437467Y88917D01*
X437550Y89167D01*
X437758Y89375D01*
X438133Y89500D01*
X438508Y89458D01*
X438883Y89292D01*
G01X452033Y79000D02*
Y81500D01*
X451033D01*
X450700Y81375D01*
X450450Y81083D01*
X450367Y80750D01*
X450450Y80417D01*
X450658Y80167D01*
X451033Y80042D01*
X452033D01*
G01X448933Y79000D02*
Y81500D01*
X447892D01*
X447558Y81375D01*
X447350Y81208D01*
X447267Y80875D01*
X447350Y80542D01*
X447600Y80333D01*
X447892Y80208D01*
X448933D01*
G01X447892D02*
X447267Y79000D01*
G01X445792Y81083D02*
X445542Y81333D01*
X445250Y81458D01*
X444917Y81500D01*
X444500Y81417D01*
X444208Y81208D01*
X444125Y80958D01*
X444167Y80708D01*
X444333Y80500D01*
X445167Y80083D01*
X445542Y79792D01*
X445792Y79375D01*
X445875Y79000D01*
X444125D01*
G01X442692Y81083D02*
X442442Y81333D01*
X442150Y81458D01*
X441817Y81500D01*
X441400Y81417D01*
X441108Y81208D01*
X441025Y80958D01*
X441067Y80708D01*
X441233Y80500D01*
X442067Y80083D01*
X442442Y79792D01*
X442692Y79375D01*
X442775Y79000D01*
X441025D01*
G01X438300D02*
Y81500D01*
X439842Y79708D01*
X437758D01*
G01X444000Y98167D02*
X440000D01*
X444000Y93500D01*
X440000D01*
G01X450467Y118000D02*
Y125000D01*
X447000Y119167D01*
X443533Y125000D01*
Y118000D01*
G01X442000Y125000D02*
Y116500D01*
X445000D01*
G01X455733Y113792D02*
X455983Y113917D01*
X456275Y114000D01*
X456608D01*
X456983Y113875D01*
X457275Y113667D01*
X457483Y113417D01*
X457650Y113000D01*
X457692Y112625D01*
X457608Y112250D01*
X457483Y112000D01*
X457233Y111750D01*
X456942Y111583D01*
X456650Y111500D01*
X456358D01*
X456067Y111583D01*
X455817Y111708D01*
X455608Y111875D01*
G01X454342Y113583D02*
X454092Y113833D01*
X453800Y113958D01*
X453467Y114000D01*
X453050Y113917D01*
X452758Y113708D01*
X452675Y113458D01*
X452717Y113208D01*
X452883Y113000D01*
X453717Y112583D01*
X454092Y112292D01*
X454342Y111875D01*
X454425Y111500D01*
X452675D01*
G01X451242Y113583D02*
X450992Y113833D01*
X450700Y113958D01*
X450367Y114000D01*
X449950Y113917D01*
X449658Y113708D01*
X449575Y113458D01*
X449617Y113208D01*
X449783Y113000D01*
X450617Y112583D01*
X450992Y112292D01*
X451242Y111875D01*
X451325Y111500D01*
X449575D01*
G01X447350D02*
X447058Y111542D01*
X446725Y111667D01*
X446517Y111875D01*
X446433Y112167D01*
X446517Y112458D01*
X446767Y112708D01*
X447142Y112833D01*
X447558D01*
X447808Y112917D01*
X448017Y113125D01*
X448100Y113417D01*
X447975Y113708D01*
X447683Y113917D01*
X447350Y114000D01*
X447017Y113917D01*
X446725Y113708D01*
X446600Y113417D01*
X446683Y113125D01*
X446892Y112917D01*
X447142Y112833D01*
X447558D01*
X447933Y112708D01*
X448183Y112458D01*
X448267Y112167D01*
X448183Y111875D01*
X447975Y111667D01*
X447642Y111542D01*
X447350Y111500D01*
G01X447733Y108792D02*
X447983Y108917D01*
X448275Y109000D01*
X448608D01*
X448983Y108875D01*
X449275Y108667D01*
X449483Y108417D01*
X449650Y108000D01*
X449692Y107625D01*
X449608Y107250D01*
X449483Y107000D01*
X449233Y106750D01*
X448942Y106583D01*
X448650Y106500D01*
X448358D01*
X448067Y106583D01*
X447817Y106708D01*
X447608Y106875D01*
G01X446342Y108583D02*
X446092Y108833D01*
X445800Y108958D01*
X445467Y109000D01*
X445050Y108917D01*
X444758Y108708D01*
X444675Y108458D01*
X444717Y108208D01*
X444883Y108000D01*
X445717Y107583D01*
X446092Y107292D01*
X446342Y106875D01*
X446425Y106500D01*
X444675D01*
G01X443367Y107000D02*
X443117Y106708D01*
X442783Y106542D01*
X442408Y106500D01*
X442075Y106542D01*
X441742Y106750D01*
X441533Y107000D01*
X441492Y107250D01*
X441575Y107542D01*
X441867Y107750D01*
X442158Y107833D01*
X442533D01*
G01X442158D02*
X441908Y107958D01*
X441700Y108167D01*
X441617Y108417D01*
X441700Y108667D01*
X441908Y108875D01*
X442283Y109000D01*
X442658Y108958D01*
X443033Y108792D01*
G01X439350Y109000D02*
X439683Y108917D01*
X439933Y108708D01*
X440100Y108458D01*
X440225Y108125D01*
X440267Y107750D01*
X440225Y107375D01*
X440100Y107042D01*
X439933Y106792D01*
X439683Y106583D01*
X439350Y106500D01*
X439017Y106583D01*
X438767Y106792D01*
X438600Y107042D01*
X438475Y107375D01*
X438433Y107750D01*
X438475Y108125D01*
X438600Y108458D01*
X438767Y108708D01*
X439017Y108917D01*
X439350Y109000D01*
G01X435500Y117517D02*
X438000D01*
Y118558D01*
X437875Y118892D01*
X437708Y119100D01*
X437375Y119183D01*
X437042Y119100D01*
X436833Y118850D01*
X436708Y118558D01*
Y117517D01*
G01Y118558D02*
X435500Y119183D01*
G01X436000Y120533D02*
X435708Y120783D01*
X435542Y121117D01*
X435500Y121492D01*
X435542Y121825D01*
X435750Y122158D01*
X436000Y122367D01*
X436250Y122408D01*
X436542Y122325D01*
X436750Y122033D01*
X436833Y121742D01*
Y121367D01*
G01Y121742D02*
X436958Y121992D01*
X437167Y122200D01*
X437417Y122283D01*
X437667Y122200D01*
X437875Y121992D01*
X438000Y121617D01*
X437958Y121242D01*
X437792Y120867D01*
G01X436542Y123758D02*
X436833Y124050D01*
X437000Y124300D01*
X437083Y124633D01*
X437000Y124925D01*
X436833Y125133D01*
X436583Y125300D01*
X436292Y125342D01*
X436042Y125300D01*
X435792Y125133D01*
X435583Y124883D01*
X435500Y124592D01*
X435583Y124258D01*
X435833Y123967D01*
X436208Y123800D01*
X436625Y123758D01*
X437167Y123842D01*
X437458Y123967D01*
X437750Y124175D01*
X437958Y124467D01*
X438000Y124758D01*
X437917Y125050D01*
X437708Y125258D01*
G01X438000Y127650D02*
X437917Y127317D01*
X437708Y127067D01*
X437458Y126900D01*
X437125Y126775D01*
X436750Y126733D01*
X436375Y126775D01*
X436042Y126900D01*
X435792Y127067D01*
X435583Y127317D01*
X435500Y127650D01*
X435583Y127983D01*
X435792Y128233D01*
X436042Y128400D01*
X436375Y128525D01*
X436750Y128567D01*
X437125Y128525D01*
X437458Y128400D01*
X437708Y128233D01*
X437917Y127983D01*
X438000Y127650D01*
G01X478000Y168000D02*
Y131500D01*
X446500D01*
Y127000D01*
G01X450733Y201292D02*
X450983Y201417D01*
X451275Y201500D01*
X451608D01*
X451983Y201375D01*
X452275Y201167D01*
X452483Y200917D01*
X452650Y200500D01*
X452692Y200125D01*
X452608Y199750D01*
X452483Y199500D01*
X452233Y199250D01*
X451942Y199083D01*
X451650Y199000D01*
X451358D01*
X451067Y199083D01*
X450817Y199208D01*
X450608Y199375D01*
G01X448550Y199000D02*
Y201500D01*
X449050Y201000D01*
G01Y199000D02*
X448050D01*
G01X446367Y199500D02*
X446117Y199208D01*
X445783Y199042D01*
X445408Y199000D01*
X445075Y199042D01*
X444742Y199250D01*
X444533Y199500D01*
X444492Y199750D01*
X444575Y200042D01*
X444867Y200250D01*
X445158Y200333D01*
X445533D01*
G01X445158D02*
X444908Y200458D01*
X444700Y200667D01*
X444617Y200917D01*
X444700Y201167D01*
X444908Y201375D01*
X445283Y201500D01*
X445658Y201458D01*
X446033Y201292D01*
G01X443142Y201083D02*
X442892Y201333D01*
X442600Y201458D01*
X442267Y201500D01*
X441850Y201417D01*
X441558Y201208D01*
X441475Y200958D01*
X441517Y200708D01*
X441683Y200500D01*
X442517Y200083D01*
X442892Y199792D01*
X443142Y199375D01*
X443225Y199000D01*
X441475D01*
G01X451733Y206792D02*
X451983Y206917D01*
X452275Y207000D01*
X452608D01*
X452983Y206875D01*
X453275Y206667D01*
X453483Y206417D01*
X453650Y206000D01*
X453692Y205625D01*
X453608Y205250D01*
X453483Y205000D01*
X453233Y204750D01*
X452942Y204583D01*
X452650Y204500D01*
X452358D01*
X452067Y204583D01*
X451817Y204708D01*
X451608Y204875D01*
G01X449550Y204500D02*
Y207000D01*
X450050Y206500D01*
G01Y204500D02*
X449050D01*
G01X447242Y206583D02*
X446992Y206833D01*
X446700Y206958D01*
X446367Y207000D01*
X445950Y206917D01*
X445658Y206708D01*
X445575Y206458D01*
X445617Y206208D01*
X445783Y206000D01*
X446617Y205583D01*
X446992Y205292D01*
X447242Y204875D01*
X447325Y204500D01*
X445575D01*
G01X444142Y205542D02*
X443850Y205833D01*
X443600Y206000D01*
X443267Y206083D01*
X442975Y206000D01*
X442767Y205833D01*
X442600Y205583D01*
X442558Y205292D01*
X442600Y205042D01*
X442767Y204792D01*
X443017Y204583D01*
X443308Y204500D01*
X443642Y204583D01*
X443933Y204833D01*
X444100Y205208D01*
X444142Y205625D01*
X444058Y206167D01*
X443933Y206458D01*
X443725Y206750D01*
X443433Y206958D01*
X443142Y207000D01*
X442850Y206917D01*
X442642Y206708D01*
G01X454983Y254500D02*
Y257000D01*
X453942D01*
X453608Y256875D01*
X453400Y256708D01*
X453317Y256375D01*
X453400Y256042D01*
X453650Y255833D01*
X453942Y255708D01*
X454983D01*
G01X453942D02*
X453317Y254500D01*
G01X450550D02*
Y257000D01*
X452092Y255208D01*
X450008D01*
G01X447950Y257000D02*
X448283Y256917D01*
X448533Y256708D01*
X448700Y256458D01*
X448825Y256125D01*
X448867Y255750D01*
X448825Y255375D01*
X448700Y255042D01*
X448533Y254792D01*
X448283Y254583D01*
X447950Y254500D01*
X447617Y254583D01*
X447367Y254792D01*
X447200Y255042D01*
X447075Y255375D01*
X447033Y255750D01*
X447075Y256125D01*
X447200Y256458D01*
X447367Y256708D01*
X447617Y256917D01*
X447950Y257000D01*
G01X445642Y256583D02*
X445392Y256833D01*
X445100Y256958D01*
X444767Y257000D01*
X444350Y256917D01*
X444058Y256708D01*
X443975Y256458D01*
X444017Y256208D01*
X444183Y256000D01*
X445017Y255583D01*
X445392Y255292D01*
X445642Y254875D01*
X445725Y254500D01*
X443975D01*
G01X450733Y276292D02*
X450983Y276417D01*
X451275Y276500D01*
X451608D01*
X451983Y276375D01*
X452275Y276167D01*
X452483Y275917D01*
X452650Y275500D01*
X452692Y275125D01*
X452608Y274750D01*
X452483Y274500D01*
X452233Y274250D01*
X451942Y274083D01*
X451650Y274000D01*
X451358D01*
X451067Y274083D01*
X450817Y274208D01*
X450608Y274375D01*
G01X449467Y274500D02*
X449217Y274208D01*
X448883Y274042D01*
X448508Y274000D01*
X448175Y274042D01*
X447842Y274250D01*
X447633Y274500D01*
X447592Y274750D01*
X447675Y275042D01*
X447967Y275250D01*
X448258Y275333D01*
X448633D01*
G01X448258D02*
X448008Y275458D01*
X447800Y275667D01*
X447717Y275917D01*
X447800Y276167D01*
X448008Y276375D01*
X448383Y276500D01*
X448758Y276458D01*
X449133Y276292D01*
G01X446242Y276083D02*
X445992Y276333D01*
X445700Y276458D01*
X445367Y276500D01*
X444950Y276417D01*
X444658Y276208D01*
X444575Y275958D01*
X444617Y275708D01*
X444783Y275500D01*
X445617Y275083D01*
X445992Y274792D01*
X446242Y274375D01*
X446325Y274000D01*
X444575D01*
G01X443142Y276083D02*
X442892Y276333D01*
X442600Y276458D01*
X442267Y276500D01*
X441850Y276417D01*
X441558Y276208D01*
X441475Y275958D01*
X441517Y275708D01*
X441683Y275500D01*
X442517Y275083D01*
X442892Y274792D01*
X443142Y274375D01*
X443225Y274000D01*
X441475D01*
G01X454150Y280500D02*
Y278000D01*
G01X455108Y280500D02*
X453192D01*
G01X451883Y278000D02*
Y280500D01*
X450883D01*
X450550Y280375D01*
X450300Y280083D01*
X450217Y279750D01*
X450300Y279417D01*
X450508Y279167D01*
X450883Y279042D01*
X451883D01*
G01X448867Y278375D02*
X448617Y278167D01*
X448325Y278042D01*
X447950Y278000D01*
X447575Y278083D01*
X447283Y278250D01*
X447075Y278542D01*
X447033Y278875D01*
X447117Y279208D01*
X447325Y279417D01*
X447617Y279583D01*
X447908Y279625D01*
X448200Y279583D01*
X448575Y279417D01*
X448450Y280500D01*
X447325D01*
G01X445767Y278500D02*
X445517Y278208D01*
X445183Y278042D01*
X444808Y278000D01*
X444475Y278042D01*
X444142Y278250D01*
X443933Y278500D01*
X443892Y278750D01*
X443975Y279042D01*
X444267Y279250D01*
X444558Y279333D01*
X444933D01*
G01X444558D02*
X444308Y279458D01*
X444100Y279667D01*
X444017Y279917D01*
X444100Y280167D01*
X444308Y280375D01*
X444683Y280500D01*
X445058Y280458D01*
X445433Y280292D01*
G01X468233Y10292D02*
X468483Y10417D01*
X468775Y10500D01*
X469108D01*
X469483Y10375D01*
X469775Y10167D01*
X469983Y9917D01*
X470150Y9500D01*
X470192Y9125D01*
X470108Y8750D01*
X469983Y8500D01*
X469733Y8250D01*
X469442Y8083D01*
X469150Y8000D01*
X468858D01*
X468567Y8083D01*
X468317Y8208D01*
X468108Y8375D01*
G01X466967Y8500D02*
X466717Y8208D01*
X466383Y8042D01*
X466008Y8000D01*
X465675Y8042D01*
X465342Y8250D01*
X465133Y8500D01*
X465092Y8750D01*
X465175Y9042D01*
X465467Y9250D01*
X465758Y9333D01*
X466133D01*
G01X465758D02*
X465508Y9458D01*
X465300Y9667D01*
X465217Y9917D01*
X465300Y10167D01*
X465508Y10375D01*
X465883Y10500D01*
X466258Y10458D01*
X466633Y10292D01*
G01X463867Y8500D02*
X463617Y8208D01*
X463283Y8042D01*
X462908Y8000D01*
X462575Y8042D01*
X462242Y8250D01*
X462033Y8500D01*
X461992Y8750D01*
X462075Y9042D01*
X462367Y9250D01*
X462658Y9333D01*
X463033D01*
G01X462658D02*
X462408Y9458D01*
X462200Y9667D01*
X462117Y9917D01*
X462200Y10167D01*
X462408Y10375D01*
X462783Y10500D01*
X463158Y10458D01*
X463533Y10292D01*
G01X460767Y8375D02*
X460517Y8167D01*
X460225Y8042D01*
X459850Y8000D01*
X459475Y8083D01*
X459183Y8250D01*
X458975Y8542D01*
X458933Y8875D01*
X459017Y9208D01*
X459225Y9417D01*
X459517Y9583D01*
X459808Y9625D01*
X460100Y9583D01*
X460475Y9417D01*
X460350Y10500D01*
X459225D01*
G01X470017Y6500D02*
Y4708D01*
X469850Y4333D01*
X469517Y4083D01*
X469100Y4000D01*
X468683Y4083D01*
X468350Y4333D01*
X468183Y4708D01*
Y6500D01*
G01X465500Y4000D02*
Y6500D01*
X467042Y4708D01*
X464958D01*
G01X462900Y4000D02*
Y6500D01*
X463400Y6000D01*
G01Y4000D02*
X462400D01*
G01X463900Y13550D02*
X466500D01*
G01X463900Y21450D02*
Y13550D01*
G01X466500Y21450D02*
X463900D01*
G01X458517Y33000D02*
Y31208D01*
X458350Y30833D01*
X458017Y30583D01*
X457600Y30500D01*
X457183Y30583D01*
X456850Y30833D01*
X456683Y31208D01*
Y33000D01*
G01X454000Y30500D02*
Y33000D01*
X455542Y31208D01*
X453458D01*
G01X451400Y33000D02*
X451733Y32917D01*
X451983Y32708D01*
X452150Y32458D01*
X452275Y32125D01*
X452317Y31750D01*
X452275Y31375D01*
X452150Y31042D01*
X451983Y30792D01*
X451733Y30583D01*
X451400Y30500D01*
X451067Y30583D01*
X450817Y30792D01*
X450650Y31042D01*
X450525Y31375D01*
X450483Y31750D01*
X450525Y32125D01*
X450650Y32458D01*
X450817Y32708D01*
X451067Y32917D01*
X451400Y33000D01*
G01X454000Y77967D02*
X456500D01*
Y78967D01*
X456375Y79300D01*
X456083Y79550D01*
X455750Y79633D01*
X455417Y79550D01*
X455167Y79342D01*
X455042Y78967D01*
Y77967D01*
G01X454000Y81067D02*
X456500D01*
Y82108D01*
X456375Y82442D01*
X456208Y82650D01*
X455875Y82733D01*
X455542Y82650D01*
X455333Y82400D01*
X455208Y82108D01*
Y81067D01*
G01Y82108D02*
X454000Y82733D01*
G01X456083Y84208D02*
X456333Y84458D01*
X456458Y84750D01*
X456500Y85083D01*
X456417Y85500D01*
X456208Y85792D01*
X455958Y85875D01*
X455708Y85833D01*
X455500Y85667D01*
X455083Y84833D01*
X454792Y84458D01*
X454375Y84208D01*
X454000Y84125D01*
Y85875D01*
G01X456083Y87308D02*
X456333Y87558D01*
X456458Y87850D01*
X456500Y88183D01*
X456417Y88600D01*
X456208Y88892D01*
X455958Y88975D01*
X455708Y88933D01*
X455500Y88767D01*
X455083Y87933D01*
X454792Y87558D01*
X454375Y87308D01*
X454000Y87225D01*
Y88975D01*
G01Y91200D02*
X456500D01*
X456000Y90700D01*
G01X454000D02*
Y91700D01*
G01X463383Y84500D02*
Y82000D01*
X461717D01*
G01X460158Y82292D02*
X459867Y82083D01*
X459533Y82000D01*
X459200Y82083D01*
X458908Y82333D01*
X458700Y82708D01*
X458617Y83083D01*
Y83542D01*
X458700Y83917D01*
X458908Y84250D01*
X459158Y84417D01*
X459450Y84500D01*
X459783Y84417D01*
X460033Y84250D01*
X460200Y84000D01*
X460283Y83667D01*
X460200Y83375D01*
X459992Y83083D01*
X459742Y82917D01*
X459450Y82875D01*
X459117Y82958D01*
X458867Y83167D01*
X458617Y83542D01*
G01X463383Y89000D02*
Y86500D01*
X461717D01*
G01X459533D02*
X459450Y87042D01*
X459325Y87500D01*
X459158Y87917D01*
X458950Y88375D01*
X458617Y89000D01*
X460283D01*
G01X466733Y95792D02*
X466983Y95917D01*
X467275Y96000D01*
X467608D01*
X467983Y95875D01*
X468275Y95667D01*
X468483Y95417D01*
X468650Y95000D01*
X468692Y94625D01*
X468608Y94250D01*
X468483Y94000D01*
X468233Y93750D01*
X467942Y93583D01*
X467650Y93500D01*
X467358D01*
X467067Y93583D01*
X466817Y93708D01*
X466608Y93875D01*
G01X465342Y95583D02*
X465092Y95833D01*
X464800Y95958D01*
X464467Y96000D01*
X464050Y95917D01*
X463758Y95708D01*
X463675Y95458D01*
X463717Y95208D01*
X463883Y95000D01*
X464717Y94583D01*
X465092Y94292D01*
X465342Y93875D01*
X465425Y93500D01*
X463675D01*
G01X462367Y93875D02*
X462117Y93667D01*
X461825Y93542D01*
X461450Y93500D01*
X461075Y93583D01*
X460783Y93750D01*
X460575Y94042D01*
X460533Y94375D01*
X460617Y94708D01*
X460825Y94917D01*
X461117Y95083D01*
X461408Y95125D01*
X461700Y95083D01*
X462075Y94917D01*
X461950Y96000D01*
X460825D01*
G01X459142Y95583D02*
X458892Y95833D01*
X458600Y95958D01*
X458267Y96000D01*
X457850Y95917D01*
X457558Y95708D01*
X457475Y95458D01*
X457517Y95208D01*
X457683Y95000D01*
X458517Y94583D01*
X458892Y94292D01*
X459142Y93875D01*
X459225Y93500D01*
X457475D01*
G01X508500Y120500D02*
X468500D01*
Y116000D01*
X460500D01*
G01X453500Y118617D02*
X456000D01*
Y119658D01*
X455875Y119992D01*
X455708Y120200D01*
X455375Y120283D01*
X455042Y120200D01*
X454833Y119950D01*
X454708Y119658D01*
Y118617D01*
G01Y119658D02*
X453500Y120283D01*
G01X454000Y121633D02*
X453708Y121883D01*
X453542Y122217D01*
X453500Y122592D01*
X453542Y122925D01*
X453750Y123258D01*
X454000Y123467D01*
X454250Y123508D01*
X454542Y123425D01*
X454750Y123133D01*
X454833Y122842D01*
Y122467D01*
G01Y122842D02*
X454958Y123092D01*
X455167Y123300D01*
X455417Y123383D01*
X455667Y123300D01*
X455875Y123092D01*
X456000Y122717D01*
X455958Y122342D01*
X455792Y121967D01*
G01X454000Y124733D02*
X453708Y124983D01*
X453542Y125317D01*
X453500Y125692D01*
X453542Y126025D01*
X453750Y126358D01*
X454000Y126567D01*
X454250Y126608D01*
X454542Y126525D01*
X454750Y126233D01*
X454833Y125942D01*
Y125567D01*
G01Y125942D02*
X454958Y126192D01*
X455167Y126400D01*
X455417Y126483D01*
X455667Y126400D01*
X455875Y126192D01*
X456000Y125817D01*
X455958Y125442D01*
X455792Y125067D01*
G01X453500Y128667D02*
X454042Y128750D01*
X454500Y128875D01*
X454917Y129042D01*
X455375Y129250D01*
X456000Y129583D01*
Y127917D01*
G01X458000Y118517D02*
X460500D01*
Y119558D01*
X460375Y119892D01*
X460208Y120100D01*
X459875Y120183D01*
X459542Y120100D01*
X459333Y119850D01*
X459208Y119558D01*
Y118517D01*
G01Y119558D02*
X458000Y120183D01*
G01X458375Y121533D02*
X458167Y121783D01*
X458042Y122075D01*
X458000Y122450D01*
X458083Y122825D01*
X458250Y123117D01*
X458542Y123325D01*
X458875Y123367D01*
X459208Y123283D01*
X459417Y123075D01*
X459583Y122783D01*
X459625Y122492D01*
X459583Y122200D01*
X459417Y121825D01*
X460500Y121950D01*
Y123075D01*
G01Y125550D02*
X460417Y125217D01*
X460208Y124967D01*
X459958Y124800D01*
X459625Y124675D01*
X459250Y124633D01*
X458875Y124675D01*
X458542Y124800D01*
X458292Y124967D01*
X458083Y125217D01*
X458000Y125550D01*
X458083Y125883D01*
X458292Y126133D01*
X458542Y126300D01*
X458875Y126425D01*
X459250Y126467D01*
X459625Y126425D01*
X459958Y126300D01*
X460208Y126133D01*
X460417Y125883D01*
X460500Y125550D01*
G01X460083Y127858D02*
X460333Y128108D01*
X460458Y128400D01*
X460500Y128733D01*
X460417Y129150D01*
X460208Y129442D01*
X459958Y129525D01*
X459708Y129483D01*
X459500Y129317D01*
X459083Y128483D01*
X458792Y128108D01*
X458375Y127858D01*
X458000Y127775D01*
Y129525D01*
G01X462500Y118517D02*
X465000D01*
Y119558D01*
X464875Y119892D01*
X464708Y120100D01*
X464375Y120183D01*
X464042Y120100D01*
X463833Y119850D01*
X463708Y119558D01*
Y118517D01*
G01Y119558D02*
X462500Y120183D01*
G01Y122950D02*
X465000D01*
X463208Y121408D01*
Y123492D01*
G01X462500Y125550D02*
X462542Y125842D01*
X462667Y126175D01*
X462875Y126383D01*
X463167Y126467D01*
X463458Y126383D01*
X463708Y126133D01*
X463833Y125758D01*
Y125342D01*
X463917Y125092D01*
X464125Y124883D01*
X464417Y124800D01*
X464708Y124925D01*
X464917Y125217D01*
X465000Y125550D01*
X464917Y125883D01*
X464708Y126175D01*
X464417Y126300D01*
X464125Y126217D01*
X463917Y126008D01*
X463833Y125758D01*
Y125342D01*
X463708Y124967D01*
X463458Y124717D01*
X463167Y124633D01*
X462875Y124717D01*
X462667Y124925D01*
X462542Y125258D01*
X462500Y125550D01*
G01X462875Y127733D02*
X462667Y127983D01*
X462542Y128275D01*
X462500Y128650D01*
X462583Y129025D01*
X462750Y129317D01*
X463042Y129525D01*
X463375Y129567D01*
X463708Y129483D01*
X463917Y129275D01*
X464083Y128983D01*
X464125Y128692D01*
X464083Y128400D01*
X463917Y128025D01*
X465000Y128150D01*
Y129275D01*
G01X470483Y173000D02*
Y175500D01*
X469483D01*
X469150Y175375D01*
X468900Y175083D01*
X468817Y174750D01*
X468900Y174417D01*
X469108Y174167D01*
X469483Y174042D01*
X470483D01*
G01X466550Y175500D02*
Y173000D01*
G01X467508Y175500D02*
X465592D01*
G01X462533Y175292D02*
X462783Y175417D01*
X463075Y175500D01*
X463408D01*
X463783Y175375D01*
X464075Y175167D01*
X464283Y174917D01*
X464450Y174500D01*
X464492Y174125D01*
X464408Y173750D01*
X464283Y173500D01*
X464033Y173250D01*
X463742Y173083D01*
X463450Y173000D01*
X463158D01*
X462867Y173083D01*
X462617Y173208D01*
X462408Y173375D01*
G01X459850Y173000D02*
Y175500D01*
X461392Y173708D01*
X459308D01*
G01X470483Y177300D02*
Y179800D01*
X469483D01*
X469150Y179675D01*
X468900Y179383D01*
X468817Y179050D01*
X468900Y178717D01*
X469108Y178467D01*
X469483Y178342D01*
X470483D01*
G01X466550Y179800D02*
Y177300D01*
G01X467508Y179800D02*
X465592D01*
G01X462533Y179592D02*
X462783Y179717D01*
X463075Y179800D01*
X463408D01*
X463783Y179675D01*
X464075Y179467D01*
X464283Y179217D01*
X464450Y178800D01*
X464492Y178425D01*
X464408Y178050D01*
X464283Y177800D01*
X464033Y177550D01*
X463742Y177383D01*
X463450Y177300D01*
X463158D01*
X462867Y177383D01*
X462617Y177508D01*
X462408Y177675D01*
G01X461267D02*
X461017Y177467D01*
X460725Y177342D01*
X460350Y177300D01*
X459975Y177383D01*
X459683Y177550D01*
X459475Y177842D01*
X459433Y178175D01*
X459517Y178508D01*
X459725Y178717D01*
X460017Y178883D01*
X460308Y178925D01*
X460600Y178883D01*
X460975Y178717D01*
X460850Y179800D01*
X459725D01*
G01X453692Y184267D02*
X453817Y184017D01*
X453900Y183725D01*
Y183392D01*
X453775Y183017D01*
X453567Y182725D01*
X453317Y182517D01*
X452900Y182350D01*
X452525Y182308D01*
X452150Y182392D01*
X451900Y182517D01*
X451650Y182767D01*
X451483Y183058D01*
X451400Y183350D01*
Y183642D01*
X451483Y183933D01*
X451608Y184183D01*
X451775Y184392D01*
G01X451400Y186450D02*
X453900D01*
X453400Y185950D01*
G01X451400D02*
Y186950D01*
G01Y189550D02*
X451442Y189842D01*
X451567Y190175D01*
X451775Y190383D01*
X452067Y190467D01*
X452358Y190383D01*
X452608Y190133D01*
X452733Y189758D01*
Y189342D01*
X452817Y189092D01*
X453025Y188883D01*
X453317Y188800D01*
X453608Y188925D01*
X453817Y189217D01*
X453900Y189550D01*
X453817Y189883D01*
X453608Y190175D01*
X453317Y190300D01*
X453025Y190217D01*
X452817Y190008D01*
X452733Y189758D01*
Y189342D01*
X452608Y188967D01*
X452358Y188717D01*
X452067Y188633D01*
X451775Y188717D01*
X451567Y188925D01*
X451442Y189258D01*
X451400Y189550D01*
G01Y192650D02*
X451442Y192942D01*
X451567Y193275D01*
X451775Y193483D01*
X452067Y193567D01*
X452358Y193483D01*
X452608Y193233D01*
X452733Y192858D01*
Y192442D01*
X452817Y192192D01*
X453025Y191983D01*
X453317Y191900D01*
X453608Y192025D01*
X453817Y192317D01*
X453900Y192650D01*
X453817Y192983D01*
X453608Y193275D01*
X453317Y193400D01*
X453025Y193317D01*
X452817Y193108D01*
X452733Y192858D01*
Y192442D01*
X452608Y192067D01*
X452358Y191817D01*
X452067Y191733D01*
X451775Y191817D01*
X451567Y192025D01*
X451442Y192358D01*
X451400Y192650D01*
G01X457792Y184267D02*
X457917Y184017D01*
X458000Y183725D01*
Y183392D01*
X457875Y183017D01*
X457667Y182725D01*
X457417Y182517D01*
X457000Y182350D01*
X456625Y182308D01*
X456250Y182392D01*
X456000Y182517D01*
X455750Y182767D01*
X455583Y183058D01*
X455500Y183350D01*
Y183642D01*
X455583Y183933D01*
X455708Y184183D01*
X455875Y184392D01*
G01X455500Y186450D02*
X458000D01*
X457500Y185950D01*
G01X455500D02*
Y186950D01*
G01Y189467D02*
X456042Y189550D01*
X456500Y189675D01*
X456917Y189842D01*
X457375Y190050D01*
X458000Y190383D01*
Y188717D01*
G01X455792Y191942D02*
X455583Y192233D01*
X455500Y192567D01*
X455583Y192900D01*
X455833Y193192D01*
X456208Y193400D01*
X456583Y193483D01*
X457042D01*
X457417Y193400D01*
X457750Y193192D01*
X457917Y192942D01*
X458000Y192650D01*
X457917Y192317D01*
X457750Y192067D01*
X457500Y191900D01*
X457167Y191817D01*
X456875Y191900D01*
X456583Y192108D01*
X456417Y192358D01*
X456375Y192650D01*
X456458Y192983D01*
X456667Y193233D01*
X457042Y193483D01*
G01X462500Y205383D02*
X465000D01*
Y206217D01*
X464875Y206550D01*
X464708Y206800D01*
X464458Y207008D01*
X464167Y207175D01*
X463750Y207217D01*
X463333Y207175D01*
X463042Y207008D01*
X462792Y206800D01*
X462625Y206550D01*
X462500Y206217D01*
Y205383D01*
G01X465000Y208900D02*
Y209900D01*
G01Y209400D02*
X462500D01*
G01Y208900D02*
Y209900D01*
G01Y211417D02*
X465000D01*
X462917Y212500D01*
X465000Y213583D01*
X462500D01*
G01Y214517D02*
X465000D01*
X462917Y215600D01*
X465000Y216683D01*
X462500D01*
G01Y218700D02*
X465000D01*
X464500Y218200D01*
G01X462500D02*
Y219200D01*
G01X461733Y230792D02*
X461983Y230917D01*
X462275Y231000D01*
X462608D01*
X462983Y230875D01*
X463275Y230667D01*
X463483Y230417D01*
X463650Y230000D01*
X463692Y229625D01*
X463608Y229250D01*
X463483Y229000D01*
X463233Y228750D01*
X462942Y228583D01*
X462650Y228500D01*
X462358D01*
X462067Y228583D01*
X461817Y228708D01*
X461608Y228875D01*
G01X459550Y228500D02*
Y231000D01*
X460050Y230500D01*
G01Y228500D02*
X459050D01*
G01X456450Y231000D02*
X456783Y230917D01*
X457033Y230708D01*
X457200Y230458D01*
X457325Y230125D01*
X457367Y229750D01*
X457325Y229375D01*
X457200Y229042D01*
X457033Y228792D01*
X456783Y228583D01*
X456450Y228500D01*
X456117Y228583D01*
X455867Y228792D01*
X455700Y229042D01*
X455575Y229375D01*
X455533Y229750D01*
X455575Y230125D01*
X455700Y230458D01*
X455867Y230708D01*
X456117Y230917D01*
X456450Y231000D01*
G01X452850Y228500D02*
Y231000D01*
X454392Y229208D01*
X452308D01*
G01X461733Y226292D02*
X461983Y226417D01*
X462275Y226500D01*
X462608D01*
X462983Y226375D01*
X463275Y226167D01*
X463483Y225917D01*
X463650Y225500D01*
X463692Y225125D01*
X463608Y224750D01*
X463483Y224500D01*
X463233Y224250D01*
X462942Y224083D01*
X462650Y224000D01*
X462358D01*
X462067Y224083D01*
X461817Y224208D01*
X461608Y224375D01*
G01X459550Y224000D02*
Y226500D01*
X460050Y226000D01*
G01Y224000D02*
X459050D01*
G01X456450D02*
Y226500D01*
X456950Y226000D01*
G01Y224000D02*
X455950D01*
G01X453350D02*
Y226500D01*
X453850Y226000D01*
G01Y224000D02*
X452850D01*
G01X461733Y234792D02*
X461983Y234917D01*
X462275Y235000D01*
X462608D01*
X462983Y234875D01*
X463275Y234667D01*
X463483Y234417D01*
X463650Y234000D01*
X463692Y233625D01*
X463608Y233250D01*
X463483Y233000D01*
X463233Y232750D01*
X462942Y232583D01*
X462650Y232500D01*
X462358D01*
X462067Y232583D01*
X461817Y232708D01*
X461608Y232875D01*
G01X459550Y232500D02*
Y235000D01*
X460050Y234500D01*
G01Y232500D02*
X459050D01*
G01X456450Y235000D02*
X456783Y234917D01*
X457033Y234708D01*
X457200Y234458D01*
X457325Y234125D01*
X457367Y233750D01*
X457325Y233375D01*
X457200Y233042D01*
X457033Y232792D01*
X456783Y232583D01*
X456450Y232500D01*
X456117Y232583D01*
X455867Y232792D01*
X455700Y233042D01*
X455575Y233375D01*
X455533Y233750D01*
X455575Y234125D01*
X455700Y234458D01*
X455867Y234708D01*
X456117Y234917D01*
X456450Y235000D01*
G01X454142Y234583D02*
X453892Y234833D01*
X453600Y234958D01*
X453267Y235000D01*
X452850Y234917D01*
X452558Y234708D01*
X452475Y234458D01*
X452517Y234208D01*
X452683Y234000D01*
X453517Y233583D01*
X453892Y233292D01*
X454142Y232875D01*
X454225Y232500D01*
X452475D01*
G01X462100Y237417D02*
X464600D01*
Y238458D01*
X464475Y238792D01*
X464308Y239000D01*
X463975Y239083D01*
X463642Y239000D01*
X463433Y238750D01*
X463308Y238458D01*
Y237417D01*
G01Y238458D02*
X462100Y239083D01*
G01Y241850D02*
X464600D01*
X462808Y240308D01*
Y242392D01*
G01X462392Y243742D02*
X462183Y244033D01*
X462100Y244367D01*
X462183Y244700D01*
X462433Y244992D01*
X462808Y245200D01*
X463183Y245283D01*
X463642D01*
X464017Y245200D01*
X464350Y244992D01*
X464517Y244742D01*
X464600Y244450D01*
X464517Y244117D01*
X464350Y243867D01*
X464100Y243700D01*
X463767Y243617D01*
X463475Y243700D01*
X463183Y243908D01*
X463017Y244158D01*
X462975Y244450D01*
X463058Y244783D01*
X463267Y245033D01*
X463642Y245283D01*
G01X462392Y246842D02*
X462183Y247133D01*
X462100Y247467D01*
X462183Y247800D01*
X462433Y248092D01*
X462808Y248300D01*
X463183Y248383D01*
X463642D01*
X464017Y248300D01*
X464350Y248092D01*
X464517Y247842D01*
X464600Y247550D01*
X464517Y247217D01*
X464350Y246967D01*
X464100Y246800D01*
X463767Y246717D01*
X463475Y246800D01*
X463183Y247008D01*
X463017Y247258D01*
X462975Y247550D01*
X463058Y247883D01*
X463267Y248133D01*
X463642Y248383D01*
G01X458100Y237417D02*
X460600D01*
Y238458D01*
X460475Y238792D01*
X460308Y239000D01*
X459975Y239083D01*
X459642Y239000D01*
X459433Y238750D01*
X459308Y238458D01*
Y237417D01*
G01Y238458D02*
X458100Y239083D01*
G01Y241850D02*
X460600D01*
X458808Y240308D01*
Y242392D01*
G01X458392Y243742D02*
X458183Y244033D01*
X458100Y244367D01*
X458183Y244700D01*
X458433Y244992D01*
X458808Y245200D01*
X459183Y245283D01*
X459642D01*
X460017Y245200D01*
X460350Y244992D01*
X460517Y244742D01*
X460600Y244450D01*
X460517Y244117D01*
X460350Y243867D01*
X460100Y243700D01*
X459767Y243617D01*
X459475Y243700D01*
X459183Y243908D01*
X459017Y244158D01*
X458975Y244450D01*
X459058Y244783D01*
X459267Y245033D01*
X459642Y245283D01*
G01X458100Y247550D02*
X458142Y247842D01*
X458267Y248175D01*
X458475Y248383D01*
X458767Y248467D01*
X459058Y248383D01*
X459308Y248133D01*
X459433Y247758D01*
Y247342D01*
X459517Y247092D01*
X459725Y246883D01*
X460017Y246800D01*
X460308Y246925D01*
X460517Y247217D01*
X460600Y247550D01*
X460517Y247883D01*
X460308Y248175D01*
X460017Y248300D01*
X459725Y248217D01*
X459517Y248008D01*
X459433Y247758D01*
Y247342D01*
X459308Y246967D01*
X459058Y246717D01*
X458767Y246633D01*
X458475Y246717D01*
X458267Y246925D01*
X458142Y247258D01*
X458100Y247550D01*
G01X462467Y273500D02*
Y276000D01*
X461633D01*
X461300Y275875D01*
X461050Y275708D01*
X460842Y275458D01*
X460675Y275167D01*
X460633Y274750D01*
X460675Y274333D01*
X460842Y274042D01*
X461050Y273792D01*
X461300Y273625D01*
X461633Y273500D01*
X462467D01*
G01X458450D02*
Y276000D01*
X458950Y275500D01*
G01Y273500D02*
X457950D01*
G01X467250Y265750D02*
Y262250D01*
X453750D01*
Y265750D01*
X467250D01*
G01X466500Y13550D02*
Y21450D01*
G01X772671Y2098D02*
Y21798D01*
X776571D01*
Y29698D01*
X778571D01*
Y59998D01*
X787221D01*
Y80098D01*
X782010D01*
Y116298D01*
X755321D01*
Y106898D01*
X753321D01*
Y80098D01*
X751171D01*
Y59998D01*
X753321D01*
Y43498D01*
X506521D01*
Y59998D01*
X508671D01*
Y80098D01*
X506521D01*
Y106898D01*
X504521D01*
Y116298D01*
X477832D01*
Y80098D01*
X472621D01*
Y59998D01*
X481271D01*
Y29698D01*
X483271D01*
Y21798D01*
X487171D01*
Y2098D01*
X772671D01*
G01X467792Y80767D02*
X467917Y80517D01*
X468000Y80225D01*
Y79892D01*
X467875Y79517D01*
X467667Y79225D01*
X467417Y79017D01*
X467000Y78850D01*
X466625Y78808D01*
X466250Y78892D01*
X466000Y79017D01*
X465750Y79267D01*
X465583Y79558D01*
X465500Y79850D01*
Y80142D01*
X465583Y80433D01*
X465708Y80683D01*
X465875Y80892D01*
G01X467583Y82158D02*
X467833Y82408D01*
X467958Y82700D01*
X468000Y83033D01*
X467917Y83450D01*
X467708Y83742D01*
X467458Y83825D01*
X467208Y83783D01*
X467000Y83617D01*
X466583Y82783D01*
X466292Y82408D01*
X465875Y82158D01*
X465500Y82075D01*
Y83825D01*
G01X465875Y85133D02*
X465667Y85383D01*
X465542Y85675D01*
X465500Y86050D01*
X465583Y86425D01*
X465750Y86717D01*
X466042Y86925D01*
X466375Y86967D01*
X466708Y86883D01*
X466917Y86675D01*
X467083Y86383D01*
X467125Y86092D01*
X467083Y85800D01*
X466917Y85425D01*
X468000Y85550D01*
Y86675D01*
G01X465500Y89150D02*
X465542Y89442D01*
X465667Y89775D01*
X465875Y89983D01*
X466167Y90067D01*
X466458Y89983D01*
X466708Y89733D01*
X466833Y89358D01*
Y88942D01*
X466917Y88692D01*
X467125Y88483D01*
X467417Y88400D01*
X467708Y88525D01*
X467917Y88817D01*
X468000Y89150D01*
X467917Y89483D01*
X467708Y89775D01*
X467417Y89900D01*
X467125Y89817D01*
X466917Y89608D01*
X466833Y89358D01*
Y88942D01*
X466708Y88567D01*
X466458Y88317D01*
X466167Y88233D01*
X465875Y88317D01*
X465667Y88525D01*
X465542Y88858D01*
X465500Y89150D01*
G01X476233Y124292D02*
X476483Y124417D01*
X476775Y124500D01*
X477108D01*
X477483Y124375D01*
X477775Y124167D01*
X477983Y123917D01*
X478150Y123500D01*
X478192Y123125D01*
X478108Y122750D01*
X477983Y122500D01*
X477733Y122250D01*
X477442Y122083D01*
X477150Y122000D01*
X476858D01*
X476567Y122083D01*
X476317Y122208D01*
X476108Y122375D01*
G01X474842Y124083D02*
X474592Y124333D01*
X474300Y124458D01*
X473967Y124500D01*
X473550Y124417D01*
X473258Y124208D01*
X473175Y123958D01*
X473217Y123708D01*
X473383Y123500D01*
X474217Y123083D01*
X474592Y122792D01*
X474842Y122375D01*
X474925Y122000D01*
X473175D01*
G01X470950D02*
Y124500D01*
X471450Y124000D01*
G01Y122000D02*
X470450D01*
G01X468642Y124083D02*
X468392Y124333D01*
X468100Y124458D01*
X467767Y124500D01*
X467350Y124417D01*
X467058Y124208D01*
X466975Y123958D01*
X467017Y123708D01*
X467183Y123500D01*
X468017Y123083D01*
X468392Y122792D01*
X468642Y122375D01*
X468725Y122000D01*
X466975D01*
G01X476233Y128792D02*
X476483Y128917D01*
X476775Y129000D01*
X477108D01*
X477483Y128875D01*
X477775Y128667D01*
X477983Y128417D01*
X478150Y128000D01*
X478192Y127625D01*
X478108Y127250D01*
X477983Y127000D01*
X477733Y126750D01*
X477442Y126583D01*
X477150Y126500D01*
X476858D01*
X476567Y126583D01*
X476317Y126708D01*
X476108Y126875D01*
G01X474842Y128583D02*
X474592Y128833D01*
X474300Y128958D01*
X473967Y129000D01*
X473550Y128917D01*
X473258Y128708D01*
X473175Y128458D01*
X473217Y128208D01*
X473383Y128000D01*
X474217Y127583D01*
X474592Y127292D01*
X474842Y126875D01*
X474925Y126500D01*
X473175D01*
G01X470950D02*
Y129000D01*
X471450Y128500D01*
G01Y126500D02*
X470450D01*
G01X467850D02*
Y129000D01*
X468350Y128500D01*
G01Y126500D02*
X467350D01*
G01X478000Y168000D02*
X508500D01*
Y120500D01*
G01X481266Y283298D02*
Y263598D01*
X477366D01*
Y255698D01*
X475366D01*
Y225398D01*
X466716D01*
Y205298D01*
X471927D01*
Y169098D01*
X498616D01*
Y178498D01*
X500616D01*
Y205298D01*
X502766D01*
Y225398D01*
X500616D01*
Y241898D01*
X747416D01*
Y225398D01*
X745266D01*
Y205298D01*
X747416D01*
Y178498D01*
X749416D01*
Y169098D01*
X776105D01*
Y205298D01*
X781316D01*
Y225398D01*
X772666D01*
Y255698D01*
X770666D01*
Y263598D01*
X766766D01*
Y283298D01*
X481266D01*
G01X477000Y275217D02*
X479500D01*
Y276258D01*
X479375Y276592D01*
X479208Y276800D01*
X478875Y276883D01*
X478542Y276800D01*
X478333Y276550D01*
X478208Y276258D01*
Y275217D01*
G01Y276258D02*
X477000Y276883D01*
G01X479083Y278358D02*
X479333Y278608D01*
X479458Y278900D01*
X479500Y279233D01*
X479417Y279650D01*
X479208Y279942D01*
X478958Y280025D01*
X478708Y279983D01*
X478500Y279817D01*
X478083Y278983D01*
X477792Y278608D01*
X477375Y278358D01*
X477000Y278275D01*
Y280025D01*
G01X477500Y281333D02*
X477208Y281583D01*
X477042Y281917D01*
X477000Y282292D01*
X477042Y282625D01*
X477250Y282958D01*
X477500Y283167D01*
X477750Y283208D01*
X478042Y283125D01*
X478250Y282833D01*
X478333Y282542D01*
Y282167D01*
G01Y282542D02*
X478458Y282792D01*
X478667Y283000D01*
X478917Y283083D01*
X479167Y283000D01*
X479375Y282792D01*
X479500Y282417D01*
X479458Y282042D01*
X479292Y281667D01*
G01X477000Y285350D02*
X477042Y285642D01*
X477167Y285975D01*
X477375Y286183D01*
X477667Y286267D01*
X477958Y286183D01*
X478208Y285933D01*
X478333Y285558D01*
Y285142D01*
X478417Y284892D01*
X478625Y284683D01*
X478917Y284600D01*
X479208Y284725D01*
X479417Y285017D01*
X479500Y285350D01*
X479417Y285683D01*
X479208Y285975D01*
X478917Y286100D01*
X478625Y286017D01*
X478417Y285808D01*
X478333Y285558D01*
Y285142D01*
X478208Y284767D01*
X477958Y284517D01*
X477667Y284433D01*
X477375Y284517D01*
X477167Y284725D01*
X477042Y285058D01*
X477000Y285350D01*
G01X472500Y275217D02*
X475000D01*
Y276258D01*
X474875Y276592D01*
X474708Y276800D01*
X474375Y276883D01*
X474042Y276800D01*
X473833Y276550D01*
X473708Y276258D01*
Y275217D01*
G01Y276258D02*
X472500Y276883D01*
G01X474583Y278358D02*
X474833Y278608D01*
X474958Y278900D01*
X475000Y279233D01*
X474917Y279650D01*
X474708Y279942D01*
X474458Y280025D01*
X474208Y279983D01*
X474000Y279817D01*
X473583Y278983D01*
X473292Y278608D01*
X472875Y278358D01*
X472500Y278275D01*
Y280025D01*
G01X473000Y281333D02*
X472708Y281583D01*
X472542Y281917D01*
X472500Y282292D01*
X472542Y282625D01*
X472750Y282958D01*
X473000Y283167D01*
X473250Y283208D01*
X473542Y283125D01*
X473750Y282833D01*
X473833Y282542D01*
Y282167D01*
G01Y282542D02*
X473958Y282792D01*
X474167Y283000D01*
X474417Y283083D01*
X474667Y283000D01*
X474875Y282792D01*
X475000Y282417D01*
X474958Y282042D01*
X474792Y281667D01*
G01X473542Y284558D02*
X473833Y284850D01*
X474000Y285100D01*
X474083Y285433D01*
X474000Y285725D01*
X473833Y285933D01*
X473583Y286100D01*
X473292Y286142D01*
X473042Y286100D01*
X472792Y285933D01*
X472583Y285683D01*
X472500Y285392D01*
X472583Y285058D01*
X472833Y284767D01*
X473208Y284600D01*
X473625Y284558D01*
X474167Y284642D01*
X474458Y284767D01*
X474750Y284975D01*
X474958Y285267D01*
X475000Y285558D01*
X474917Y285850D01*
X474708Y286058D01*
G01X504233Y137292D02*
X504483Y137417D01*
X504775Y137500D01*
X505108D01*
X505483Y137375D01*
X505775Y137167D01*
X505983Y136917D01*
X506150Y136500D01*
X506192Y136125D01*
X506108Y135750D01*
X505983Y135500D01*
X505733Y135250D01*
X505442Y135083D01*
X505150Y135000D01*
X504858D01*
X504567Y135083D01*
X504317Y135208D01*
X504108Y135375D01*
G01X502842Y137083D02*
X502592Y137333D01*
X502300Y137458D01*
X501967Y137500D01*
X501550Y137417D01*
X501258Y137208D01*
X501175Y136958D01*
X501217Y136708D01*
X501383Y136500D01*
X502217Y136083D01*
X502592Y135792D01*
X502842Y135375D01*
X502925Y135000D01*
X501175D01*
G01X498950Y137500D02*
X499283Y137417D01*
X499533Y137208D01*
X499700Y136958D01*
X499825Y136625D01*
X499867Y136250D01*
X499825Y135875D01*
X499700Y135542D01*
X499533Y135292D01*
X499283Y135083D01*
X498950Y135000D01*
X498617Y135083D01*
X498367Y135292D01*
X498200Y135542D01*
X498075Y135875D01*
X498033Y136250D01*
X498075Y136625D01*
X498200Y136958D01*
X498367Y137208D01*
X498617Y137417D01*
X498950Y137500D01*
G01X496642Y137083D02*
X496392Y137333D01*
X496100Y137458D01*
X495767Y137500D01*
X495350Y137417D01*
X495058Y137208D01*
X494975Y136958D01*
X495017Y136708D01*
X495183Y136500D01*
X496017Y136083D01*
X496392Y135792D01*
X496642Y135375D01*
X496725Y135000D01*
X494975D01*
G01X489683Y128992D02*
X489933Y129117D01*
X490225Y129200D01*
X490558D01*
X490933Y129075D01*
X491225Y128867D01*
X491433Y128617D01*
X491600Y128200D01*
X491642Y127825D01*
X491558Y127450D01*
X491433Y127200D01*
X491183Y126950D01*
X490892Y126783D01*
X490600Y126700D01*
X490308D01*
X490017Y126783D01*
X489767Y126908D01*
X489558Y127075D01*
G01X488292Y128783D02*
X488042Y129033D01*
X487750Y129158D01*
X487417Y129200D01*
X487000Y129117D01*
X486708Y128908D01*
X486625Y128658D01*
X486667Y128408D01*
X486833Y128200D01*
X487667Y127783D01*
X488042Y127492D01*
X488292Y127075D01*
X488375Y126700D01*
X486625D01*
G01X484400D02*
Y129200D01*
X484900Y128700D01*
G01Y126700D02*
X483900D01*
G01X482217Y127200D02*
X481967Y126908D01*
X481633Y126742D01*
X481258Y126700D01*
X480925Y126742D01*
X480592Y126950D01*
X480383Y127200D01*
X480342Y127450D01*
X480425Y127742D01*
X480717Y127950D01*
X481008Y128033D01*
X481383D01*
G01X481008D02*
X480758Y128158D01*
X480550Y128367D01*
X480467Y128617D01*
X480550Y128867D01*
X480758Y129075D01*
X481133Y129200D01*
X481508Y129158D01*
X481883Y128992D01*
G01X492233Y124292D02*
X492483Y124417D01*
X492775Y124500D01*
X493108D01*
X493483Y124375D01*
X493775Y124167D01*
X493983Y123917D01*
X494150Y123500D01*
X494192Y123125D01*
X494108Y122750D01*
X493983Y122500D01*
X493733Y122250D01*
X493442Y122083D01*
X493150Y122000D01*
X492858D01*
X492567Y122083D01*
X492317Y122208D01*
X492108Y122375D01*
G01X490842Y124083D02*
X490592Y124333D01*
X490300Y124458D01*
X489967Y124500D01*
X489550Y124417D01*
X489258Y124208D01*
X489175Y123958D01*
X489217Y123708D01*
X489383Y123500D01*
X490217Y123083D01*
X490592Y122792D01*
X490842Y122375D01*
X490925Y122000D01*
X489175D01*
G01X487742Y124083D02*
X487492Y124333D01*
X487200Y124458D01*
X486867Y124500D01*
X486450Y124417D01*
X486158Y124208D01*
X486075Y123958D01*
X486117Y123708D01*
X486283Y123500D01*
X487117Y123083D01*
X487492Y122792D01*
X487742Y122375D01*
X487825Y122000D01*
X486075D01*
G01X483850Y124500D02*
X484183Y124417D01*
X484433Y124208D01*
X484600Y123958D01*
X484725Y123625D01*
X484767Y123250D01*
X484725Y122875D01*
X484600Y122542D01*
X484433Y122292D01*
X484183Y122083D01*
X483850Y122000D01*
X483517Y122083D01*
X483267Y122292D01*
X483100Y122542D01*
X482975Y122875D01*
X482933Y123250D01*
X482975Y123625D01*
X483100Y123958D01*
X483267Y124208D01*
X483517Y124417D01*
X483850Y124500D01*
G01X498092Y124267D02*
X498217Y124017D01*
X498300Y123725D01*
Y123392D01*
X498175Y123017D01*
X497967Y122725D01*
X497717Y122517D01*
X497300Y122350D01*
X496925Y122308D01*
X496550Y122392D01*
X496300Y122517D01*
X496050Y122767D01*
X495883Y123058D01*
X495800Y123350D01*
Y123642D01*
X495883Y123933D01*
X496008Y124183D01*
X496175Y124392D01*
G01X497883Y125658D02*
X498133Y125908D01*
X498258Y126200D01*
X498300Y126533D01*
X498217Y126950D01*
X498008Y127242D01*
X497758Y127325D01*
X497508Y127283D01*
X497300Y127117D01*
X496883Y126283D01*
X496592Y125908D01*
X496175Y125658D01*
X495800Y125575D01*
Y127325D01*
G01Y129550D02*
X498300D01*
X497800Y129050D01*
G01X495800D02*
Y130050D01*
G01Y132567D02*
X496342Y132650D01*
X496800Y132775D01*
X497217Y132942D01*
X497675Y133150D01*
X498300Y133483D01*
Y131817D01*
G01X489733Y153792D02*
X489983Y153917D01*
X490275Y154000D01*
X490608D01*
X490983Y153875D01*
X491275Y153667D01*
X491483Y153417D01*
X491650Y153000D01*
X491692Y152625D01*
X491608Y152250D01*
X491483Y152000D01*
X491233Y151750D01*
X490942Y151583D01*
X490650Y151500D01*
X490358D01*
X490067Y151583D01*
X489817Y151708D01*
X489608Y151875D01*
G01X487550Y151500D02*
Y154000D01*
X488050Y153500D01*
G01Y151500D02*
X487050D01*
G01X484450D02*
X484158Y151542D01*
X483825Y151667D01*
X483617Y151875D01*
X483533Y152167D01*
X483617Y152458D01*
X483867Y152708D01*
X484242Y152833D01*
X484658D01*
X484908Y152917D01*
X485117Y153125D01*
X485200Y153417D01*
X485075Y153708D01*
X484783Y153917D01*
X484450Y154000D01*
X484117Y153917D01*
X483825Y153708D01*
X483700Y153417D01*
X483783Y153125D01*
X483992Y152917D01*
X484242Y152833D01*
X484658D01*
X485033Y152708D01*
X485283Y152458D01*
X485367Y152167D01*
X485283Y151875D01*
X485075Y151667D01*
X484742Y151542D01*
X484450Y151500D01*
G01X482142Y152542D02*
X481850Y152833D01*
X481600Y153000D01*
X481267Y153083D01*
X480975Y153000D01*
X480767Y152833D01*
X480600Y152583D01*
X480558Y152292D01*
X480600Y152042D01*
X480767Y151792D01*
X481017Y151583D01*
X481308Y151500D01*
X481642Y151583D01*
X481933Y151833D01*
X482100Y152208D01*
X482142Y152625D01*
X482058Y153167D01*
X481933Y153458D01*
X481725Y153750D01*
X481433Y153958D01*
X481142Y154000D01*
X480850Y153917D01*
X480642Y153708D01*
G01X504233Y153792D02*
X504483Y153917D01*
X504775Y154000D01*
X505108D01*
X505483Y153875D01*
X505775Y153667D01*
X505983Y153417D01*
X506150Y153000D01*
X506192Y152625D01*
X506108Y152250D01*
X505983Y152000D01*
X505733Y151750D01*
X505442Y151583D01*
X505150Y151500D01*
X504858D01*
X504567Y151583D01*
X504317Y151708D01*
X504108Y151875D01*
G01X502050Y151500D02*
Y154000D01*
X502550Y153500D01*
G01Y151500D02*
X501550D01*
G01X498950D02*
X498658Y151542D01*
X498325Y151667D01*
X498117Y151875D01*
X498033Y152167D01*
X498117Y152458D01*
X498367Y152708D01*
X498742Y152833D01*
X499158D01*
X499408Y152917D01*
X499617Y153125D01*
X499700Y153417D01*
X499575Y153708D01*
X499283Y153917D01*
X498950Y154000D01*
X498617Y153917D01*
X498325Y153708D01*
X498200Y153417D01*
X498283Y153125D01*
X498492Y152917D01*
X498742Y152833D01*
X499158D01*
X499533Y152708D01*
X499783Y152458D01*
X499867Y152167D01*
X499783Y151875D01*
X499575Y151667D01*
X499242Y151542D01*
X498950Y151500D01*
G01X496767Y151875D02*
X496517Y151667D01*
X496225Y151542D01*
X495850Y151500D01*
X495475Y151583D01*
X495183Y151750D01*
X494975Y152042D01*
X494933Y152375D01*
X495017Y152708D01*
X495225Y152917D01*
X495517Y153083D01*
X495808Y153125D01*
X496100Y153083D01*
X496475Y152917D01*
X496350Y154000D01*
X495225D01*
G01X490733Y148292D02*
X490983Y148417D01*
X491275Y148500D01*
X491608D01*
X491983Y148375D01*
X492275Y148167D01*
X492483Y147917D01*
X492650Y147500D01*
X492692Y147125D01*
X492608Y146750D01*
X492483Y146500D01*
X492233Y146250D01*
X491942Y146083D01*
X491650Y146000D01*
X491358D01*
X491067Y146083D01*
X490817Y146208D01*
X490608Y146375D01*
G01X488550Y146000D02*
Y148500D01*
X489050Y148000D01*
G01Y146000D02*
X488050D01*
G01X485450D02*
X485158Y146042D01*
X484825Y146167D01*
X484617Y146375D01*
X484533Y146667D01*
X484617Y146958D01*
X484867Y147208D01*
X485242Y147333D01*
X485658D01*
X485908Y147417D01*
X486117Y147625D01*
X486200Y147917D01*
X486075Y148208D01*
X485783Y148417D01*
X485450Y148500D01*
X485117Y148417D01*
X484825Y148208D01*
X484700Y147917D01*
X484783Y147625D01*
X484992Y147417D01*
X485242Y147333D01*
X485658D01*
X486033Y147208D01*
X486283Y146958D01*
X486367Y146667D01*
X486283Y146375D01*
X486075Y146167D01*
X485742Y146042D01*
X485450Y146000D01*
G01X482433D02*
X482350Y146542D01*
X482225Y147000D01*
X482058Y147417D01*
X481850Y147875D01*
X481517Y148500D01*
X483183D01*
G01X490733Y143292D02*
X490983Y143417D01*
X491275Y143500D01*
X491608D01*
X491983Y143375D01*
X492275Y143167D01*
X492483Y142917D01*
X492650Y142500D01*
X492692Y142125D01*
X492608Y141750D01*
X492483Y141500D01*
X492233Y141250D01*
X491942Y141083D01*
X491650Y141000D01*
X491358D01*
X491067Y141083D01*
X490817Y141208D01*
X490608Y141375D01*
G01X489342Y143083D02*
X489092Y143333D01*
X488800Y143458D01*
X488467Y143500D01*
X488050Y143417D01*
X487758Y143208D01*
X487675Y142958D01*
X487717Y142708D01*
X487883Y142500D01*
X488717Y142083D01*
X489092Y141792D01*
X489342Y141375D01*
X489425Y141000D01*
X487675D01*
G01X485450Y143500D02*
X485783Y143417D01*
X486033Y143208D01*
X486200Y142958D01*
X486325Y142625D01*
X486367Y142250D01*
X486325Y141875D01*
X486200Y141542D01*
X486033Y141292D01*
X485783Y141083D01*
X485450Y141000D01*
X485117Y141083D01*
X484867Y141292D01*
X484700Y141542D01*
X484575Y141875D01*
X484533Y142250D01*
X484575Y142625D01*
X484700Y142958D01*
X484867Y143208D01*
X485117Y143417D01*
X485450Y143500D01*
G01X483267Y141500D02*
X483017Y141208D01*
X482683Y141042D01*
X482308Y141000D01*
X481975Y141042D01*
X481642Y141250D01*
X481433Y141500D01*
X481392Y141750D01*
X481475Y142042D01*
X481767Y142250D01*
X482058Y142333D01*
X482433D01*
G01X482058D02*
X481808Y142458D01*
X481600Y142667D01*
X481517Y142917D01*
X481600Y143167D01*
X481808Y143375D01*
X482183Y143500D01*
X482558Y143458D01*
X482933Y143292D01*
G01X503733Y165792D02*
X503983Y165917D01*
X504275Y166000D01*
X504608D01*
X504983Y165875D01*
X505275Y165667D01*
X505483Y165417D01*
X505650Y165000D01*
X505692Y164625D01*
X505608Y164250D01*
X505483Y164000D01*
X505233Y163750D01*
X504942Y163583D01*
X504650Y163500D01*
X504358D01*
X504067Y163583D01*
X503817Y163708D01*
X503608Y163875D01*
G01X501550Y163500D02*
Y166000D01*
X502050Y165500D01*
G01Y163500D02*
X501050D01*
G01X499367Y163875D02*
X499117Y163667D01*
X498825Y163542D01*
X498450Y163500D01*
X498075Y163583D01*
X497783Y163750D01*
X497575Y164042D01*
X497533Y164375D01*
X497617Y164708D01*
X497825Y164917D01*
X498117Y165083D01*
X498408Y165125D01*
X498700Y165083D01*
X499075Y164917D01*
X498950Y166000D01*
X497825D01*
G01X496142Y164542D02*
X495850Y164833D01*
X495600Y165000D01*
X495267Y165083D01*
X494975Y165000D01*
X494767Y164833D01*
X494600Y164583D01*
X494558Y164292D01*
X494600Y164042D01*
X494767Y163792D01*
X495017Y163583D01*
X495308Y163500D01*
X495642Y163583D01*
X495933Y163833D01*
X496100Y164208D01*
X496142Y164625D01*
X496058Y165167D01*
X495933Y165458D01*
X495725Y165750D01*
X495433Y165958D01*
X495142Y166000D01*
X494850Y165917D01*
X494642Y165708D01*
G01X490233Y165792D02*
X490483Y165917D01*
X490775Y166000D01*
X491108D01*
X491483Y165875D01*
X491775Y165667D01*
X491983Y165417D01*
X492150Y165000D01*
X492192Y164625D01*
X492108Y164250D01*
X491983Y164000D01*
X491733Y163750D01*
X491442Y163583D01*
X491150Y163500D01*
X490858D01*
X490567Y163583D01*
X490317Y163708D01*
X490108Y163875D01*
G01X488050Y163500D02*
Y166000D01*
X488550Y165500D01*
G01Y163500D02*
X487550D01*
G01X485867Y163875D02*
X485617Y163667D01*
X485325Y163542D01*
X484950Y163500D01*
X484575Y163583D01*
X484283Y163750D01*
X484075Y164042D01*
X484033Y164375D01*
X484117Y164708D01*
X484325Y164917D01*
X484617Y165083D01*
X484908Y165125D01*
X485200Y165083D01*
X485575Y164917D01*
X485450Y166000D01*
X484325D01*
G01X481933Y163500D02*
X481850Y164042D01*
X481725Y164500D01*
X481558Y164917D01*
X481350Y165375D01*
X481017Y166000D01*
X482683D01*
G01X498233Y157992D02*
X498483Y158117D01*
X498775Y158200D01*
X499108D01*
X499483Y158075D01*
X499775Y157867D01*
X499983Y157617D01*
X500150Y157200D01*
X500192Y156825D01*
X500108Y156450D01*
X499983Y156200D01*
X499733Y155950D01*
X499442Y155783D01*
X499150Y155700D01*
X498858D01*
X498567Y155783D01*
X498317Y155908D01*
X498108Y156075D01*
G01X496050Y155700D02*
Y158200D01*
X496550Y157700D01*
G01Y155700D02*
X495550D01*
G01X492950D02*
X492658Y155742D01*
X492325Y155867D01*
X492117Y156075D01*
X492033Y156367D01*
X492117Y156658D01*
X492367Y156908D01*
X492742Y157033D01*
X493158D01*
X493408Y157117D01*
X493617Y157325D01*
X493700Y157617D01*
X493575Y157908D01*
X493283Y158117D01*
X492950Y158200D01*
X492617Y158117D01*
X492325Y157908D01*
X492200Y157617D01*
X492283Y157325D01*
X492492Y157117D01*
X492742Y157033D01*
X493158D01*
X493533Y156908D01*
X493783Y156658D01*
X493867Y156367D01*
X493783Y156075D01*
X493575Y155867D01*
X493242Y155742D01*
X492950Y155700D01*
G01X489850Y158200D02*
X490183Y158117D01*
X490433Y157908D01*
X490600Y157658D01*
X490725Y157325D01*
X490767Y156950D01*
X490725Y156575D01*
X490600Y156242D01*
X490433Y155992D01*
X490183Y155783D01*
X489850Y155700D01*
X489517Y155783D01*
X489267Y155992D01*
X489100Y156242D01*
X488975Y156575D01*
X488933Y156950D01*
X488975Y157325D01*
X489100Y157658D01*
X489267Y157908D01*
X489517Y158117D01*
X489850Y158200D01*
G01X498233Y161792D02*
X498483Y161917D01*
X498775Y162000D01*
X499108D01*
X499483Y161875D01*
X499775Y161667D01*
X499983Y161417D01*
X500150Y161000D01*
X500192Y160625D01*
X500108Y160250D01*
X499983Y160000D01*
X499733Y159750D01*
X499442Y159583D01*
X499150Y159500D01*
X498858D01*
X498567Y159583D01*
X498317Y159708D01*
X498108Y159875D01*
G01X496050Y159500D02*
Y162000D01*
X496550Y161500D01*
G01Y159500D02*
X495550D01*
G01X493742Y160542D02*
X493450Y160833D01*
X493200Y161000D01*
X492867Y161083D01*
X492575Y161000D01*
X492367Y160833D01*
X492200Y160583D01*
X492158Y160292D01*
X492200Y160042D01*
X492367Y159792D01*
X492617Y159583D01*
X492908Y159500D01*
X493242Y159583D01*
X493533Y159833D01*
X493700Y160208D01*
X493742Y160625D01*
X493658Y161167D01*
X493533Y161458D01*
X493325Y161750D01*
X493033Y161958D01*
X492742Y162000D01*
X492450Y161917D01*
X492242Y161708D01*
G01X490558Y159792D02*
X490267Y159583D01*
X489933Y159500D01*
X489600Y159583D01*
X489308Y159833D01*
X489100Y160208D01*
X489017Y160583D01*
Y161042D01*
X489100Y161417D01*
X489308Y161750D01*
X489558Y161917D01*
X489850Y162000D01*
X490183Y161917D01*
X490433Y161750D01*
X490600Y161500D01*
X490683Y161167D01*
X490600Y160875D01*
X490392Y160583D01*
X490142Y160417D01*
X489850Y160375D01*
X489517Y160458D01*
X489267Y160667D01*
X489017Y161042D01*
G01X486958Y285917D02*
X487208Y285667D01*
X487500Y285542D01*
X487833Y285500D01*
X488250Y285583D01*
X488542Y285792D01*
X488625Y286042D01*
X488583Y286292D01*
X488417Y286500D01*
X487583Y286917D01*
X487208Y287208D01*
X486958Y287625D01*
X486875Y288000D01*
X488625D01*
G01X490850Y285500D02*
X490517Y285583D01*
X490267Y285792D01*
X490100Y286042D01*
X489975Y286375D01*
X489933Y286750D01*
X489975Y287125D01*
X490100Y287458D01*
X490267Y287708D01*
X490517Y287917D01*
X490850Y288000D01*
X491183Y287917D01*
X491433Y287708D01*
X491600Y287458D01*
X491725Y287125D01*
X491767Y286750D01*
X491725Y286375D01*
X491600Y286042D01*
X491433Y285792D01*
X491183Y285583D01*
X490850Y285500D01*
G01X494450Y288000D02*
Y285500D01*
X492908Y287292D01*
X494992D01*
G01X508250Y53000D02*
Y55500D01*
X508750Y55000D01*
G01Y53000D02*
X507750D01*
G01X505671Y48048D02*
Y44048D01*
X507671Y46048D01*
X503671D01*
X505671Y44048D01*
G01X513292Y66774D02*
X513417Y66524D01*
X513500Y66232D01*
Y65899D01*
X513375Y65524D01*
X513167Y65232D01*
X512917Y65024D01*
X512500Y64857D01*
X512125Y64815D01*
X511750Y64899D01*
X511500Y65024D01*
X511250Y65274D01*
X511083Y65565D01*
X511000Y65857D01*
Y66149D01*
X511083Y66440D01*
X511208Y66690D01*
X511375Y66899D01*
G01X511500Y68040D02*
X511208Y68290D01*
X511042Y68624D01*
X511000Y68999D01*
X511042Y69332D01*
X511250Y69665D01*
X511500Y69874D01*
X511750Y69915D01*
X512042Y69832D01*
X512250Y69540D01*
X512333Y69249D01*
Y68874D01*
G01Y69249D02*
X512458Y69499D01*
X512667Y69707D01*
X512917Y69790D01*
X513167Y69707D01*
X513375Y69499D01*
X513500Y69124D01*
X513458Y68749D01*
X513292Y68374D01*
G01X511375Y71140D02*
X511167Y71390D01*
X511042Y71682D01*
X511000Y72057D01*
X511083Y72432D01*
X511250Y72724D01*
X511542Y72932D01*
X511875Y72974D01*
X512208Y72890D01*
X512417Y72682D01*
X512583Y72390D01*
X512625Y72099D01*
X512583Y71807D01*
X512417Y71432D01*
X513500Y71557D01*
Y72682D01*
G01X511375Y74240D02*
X511167Y74490D01*
X511042Y74782D01*
X511000Y75157D01*
X511083Y75532D01*
X511250Y75824D01*
X511542Y76032D01*
X511875Y76074D01*
X512208Y75990D01*
X512417Y75782D01*
X512583Y75490D01*
X512625Y75199D01*
X512583Y74907D01*
X512417Y74532D01*
X513500Y74657D01*
Y75782D01*
G01X507500Y104067D02*
X510000D01*
Y105108D01*
X509875Y105442D01*
X509708Y105650D01*
X509375Y105733D01*
X509042Y105650D01*
X508833Y105400D01*
X508708Y105108D01*
Y104067D01*
G01Y105108D02*
X507500Y105733D01*
G01X508000Y107083D02*
X507708Y107333D01*
X507542Y107667D01*
X507500Y108042D01*
X507542Y108375D01*
X507750Y108708D01*
X508000Y108917D01*
X508250Y108958D01*
X508542Y108875D01*
X508750Y108583D01*
X508833Y108292D01*
Y107917D01*
G01Y108292D02*
X508958Y108542D01*
X509167Y108750D01*
X509417Y108833D01*
X509667Y108750D01*
X509875Y108542D01*
X510000Y108167D01*
X509958Y107792D01*
X509792Y107417D01*
G01X509583Y110308D02*
X509833Y110558D01*
X509958Y110850D01*
X510000Y111183D01*
X509917Y111600D01*
X509708Y111892D01*
X509458Y111975D01*
X509208Y111933D01*
X509000Y111767D01*
X508583Y110933D01*
X508292Y110558D01*
X507875Y110308D01*
X507500Y110225D01*
Y111975D01*
G01X506292Y124267D02*
X506417Y124017D01*
X506500Y123725D01*
Y123392D01*
X506375Y123017D01*
X506167Y122725D01*
X505917Y122517D01*
X505500Y122350D01*
X505125Y122308D01*
X504750Y122392D01*
X504500Y122517D01*
X504250Y122767D01*
X504083Y123058D01*
X504000Y123350D01*
Y123642D01*
X504083Y123933D01*
X504208Y124183D01*
X504375Y124392D01*
G01X506083Y125658D02*
X506333Y125908D01*
X506458Y126200D01*
X506500Y126533D01*
X506417Y126950D01*
X506208Y127242D01*
X505958Y127325D01*
X505708Y127283D01*
X505500Y127117D01*
X505083Y126283D01*
X504792Y125908D01*
X504375Y125658D01*
X504000Y125575D01*
Y127325D01*
G01Y129550D02*
X506500D01*
X506000Y129050D01*
G01X504000D02*
Y130050D01*
G01X504375Y131733D02*
X504167Y131983D01*
X504042Y132275D01*
X504000Y132650D01*
X504083Y133025D01*
X504250Y133317D01*
X504542Y133525D01*
X504875Y133567D01*
X505208Y133483D01*
X505417Y133275D01*
X505583Y132983D01*
X505625Y132692D01*
X505583Y132400D01*
X505417Y132025D01*
X506500Y132150D01*
Y133275D01*
G01X502292Y124267D02*
X502417Y124017D01*
X502500Y123725D01*
Y123392D01*
X502375Y123017D01*
X502167Y122725D01*
X501917Y122517D01*
X501500Y122350D01*
X501125Y122308D01*
X500750Y122392D01*
X500500Y122517D01*
X500250Y122767D01*
X500083Y123058D01*
X500000Y123350D01*
Y123642D01*
X500083Y123933D01*
X500208Y124183D01*
X500375Y124392D01*
G01X502083Y125658D02*
X502333Y125908D01*
X502458Y126200D01*
X502500Y126533D01*
X502417Y126950D01*
X502208Y127242D01*
X501958Y127325D01*
X501708Y127283D01*
X501500Y127117D01*
X501083Y126283D01*
X500792Y125908D01*
X500375Y125658D01*
X500000Y125575D01*
Y127325D01*
G01Y129550D02*
X502500D01*
X502000Y129050D01*
G01X500000D02*
Y130050D01*
G01X501042Y131858D02*
X501333Y132150D01*
X501500Y132400D01*
X501583Y132733D01*
X501500Y133025D01*
X501333Y133233D01*
X501083Y133400D01*
X500792Y133442D01*
X500542Y133400D01*
X500292Y133233D01*
X500083Y132983D01*
X500000Y132692D01*
X500083Y132358D01*
X500333Y132067D01*
X500708Y131900D01*
X501125Y131858D01*
X501667Y131942D01*
X501958Y132067D01*
X502250Y132275D01*
X502458Y132567D01*
X502500Y132858D01*
X502417Y133150D01*
X502208Y133358D01*
G01X519733Y149292D02*
X519983Y149417D01*
X520275Y149500D01*
X520608D01*
X520983Y149375D01*
X521275Y149167D01*
X521483Y148917D01*
X521650Y148500D01*
X521692Y148125D01*
X521608Y147750D01*
X521483Y147500D01*
X521233Y147250D01*
X520942Y147083D01*
X520650Y147000D01*
X520358D01*
X520067Y147083D01*
X519817Y147208D01*
X519608Y147375D01*
G01X517550Y147000D02*
Y149500D01*
X518050Y149000D01*
G01Y147000D02*
X517050D01*
G01X515367Y147500D02*
X515117Y147208D01*
X514783Y147042D01*
X514408Y147000D01*
X514075Y147042D01*
X513742Y147250D01*
X513533Y147500D01*
X513492Y147750D01*
X513575Y148042D01*
X513867Y148250D01*
X514158Y148333D01*
X514533D01*
G01X514158D02*
X513908Y148458D01*
X513700Y148667D01*
X513617Y148917D01*
X513700Y149167D01*
X513908Y149375D01*
X514283Y149500D01*
X514658Y149458D01*
X515033Y149292D01*
G01X512142Y148042D02*
X511850Y148333D01*
X511600Y148500D01*
X511267Y148583D01*
X510975Y148500D01*
X510767Y148333D01*
X510600Y148083D01*
X510558Y147792D01*
X510600Y147542D01*
X510767Y147292D01*
X511017Y147083D01*
X511308Y147000D01*
X511642Y147083D01*
X511933Y147333D01*
X512100Y147708D01*
X512142Y148125D01*
X512058Y148667D01*
X511933Y148958D01*
X511725Y149250D01*
X511433Y149458D01*
X511142Y149500D01*
X510850Y149417D01*
X510642Y149208D01*
G01X519733Y153792D02*
X519983Y153917D01*
X520275Y154000D01*
X520608D01*
X520983Y153875D01*
X521275Y153667D01*
X521483Y153417D01*
X521650Y153000D01*
X521692Y152625D01*
X521608Y152250D01*
X521483Y152000D01*
X521233Y151750D01*
X520942Y151583D01*
X520650Y151500D01*
X520358D01*
X520067Y151583D01*
X519817Y151708D01*
X519608Y151875D01*
G01X517550Y151500D02*
Y154000D01*
X518050Y153500D01*
G01Y151500D02*
X517050D01*
G01X515367Y152000D02*
X515117Y151708D01*
X514783Y151542D01*
X514408Y151500D01*
X514075Y151542D01*
X513742Y151750D01*
X513533Y152000D01*
X513492Y152250D01*
X513575Y152542D01*
X513867Y152750D01*
X514158Y152833D01*
X514533D01*
G01X514158D02*
X513908Y152958D01*
X513700Y153167D01*
X513617Y153417D01*
X513700Y153667D01*
X513908Y153875D01*
X514283Y154000D01*
X514658Y153958D01*
X515033Y153792D01*
G01X512267Y151875D02*
X512017Y151667D01*
X511725Y151542D01*
X511350Y151500D01*
X510975Y151583D01*
X510683Y151750D01*
X510475Y152042D01*
X510433Y152375D01*
X510517Y152708D01*
X510725Y152917D01*
X511017Y153083D01*
X511308Y153125D01*
X511600Y153083D01*
X511975Y152917D01*
X511850Y154000D01*
X510725D01*
G01X504000Y139850D02*
X501500D01*
G01X504000Y138892D02*
Y140808D01*
G01X501500Y142117D02*
X504000D01*
Y143117D01*
X503875Y143450D01*
X503583Y143700D01*
X503250Y143783D01*
X502917Y143700D01*
X502667Y143492D01*
X502542Y143117D01*
Y142117D01*
G01X502000Y145133D02*
X501708Y145383D01*
X501542Y145717D01*
X501500Y146092D01*
X501542Y146425D01*
X501750Y146758D01*
X502000Y146967D01*
X502250Y147008D01*
X502542Y146925D01*
X502750Y146633D01*
X502833Y146342D01*
Y145967D01*
G01Y146342D02*
X502958Y146592D01*
X503167Y146800D01*
X503417Y146883D01*
X503667Y146800D01*
X503875Y146592D01*
X504000Y146217D01*
X503958Y145842D01*
X503792Y145467D01*
G01X503583Y148358D02*
X503833Y148608D01*
X503958Y148900D01*
X504000Y149233D01*
X503917Y149650D01*
X503708Y149942D01*
X503458Y150025D01*
X503208Y149983D01*
X503000Y149817D01*
X502583Y148983D01*
X502292Y148608D01*
X501875Y148358D01*
X501500Y148275D01*
Y150025D01*
G01X497500Y139017D02*
X500000D01*
Y140058D01*
X499875Y140392D01*
X499708Y140600D01*
X499375Y140683D01*
X499042Y140600D01*
X498833Y140350D01*
X498708Y140058D01*
Y139017D01*
G01Y140058D02*
X497500Y140683D01*
G01X498000Y142033D02*
X497708Y142283D01*
X497542Y142617D01*
X497500Y142992D01*
X497542Y143325D01*
X497750Y143658D01*
X498000Y143867D01*
X498250Y143908D01*
X498542Y143825D01*
X498750Y143533D01*
X498833Y143242D01*
Y142867D01*
G01Y143242D02*
X498958Y143492D01*
X499167Y143700D01*
X499417Y143783D01*
X499667Y143700D01*
X499875Y143492D01*
X500000Y143117D01*
X499958Y142742D01*
X499792Y142367D01*
G01X498000Y145133D02*
X497708Y145383D01*
X497542Y145717D01*
X497500Y146092D01*
X497542Y146425D01*
X497750Y146758D01*
X498000Y146967D01*
X498250Y147008D01*
X498542Y146925D01*
X498750Y146633D01*
X498833Y146342D01*
Y145967D01*
G01Y146342D02*
X498958Y146592D01*
X499167Y146800D01*
X499417Y146883D01*
X499667Y146800D01*
X499875Y146592D01*
X500000Y146217D01*
X499958Y145842D01*
X499792Y145467D01*
G01X498000Y148233D02*
X497708Y148483D01*
X497542Y148817D01*
X497500Y149192D01*
X497542Y149525D01*
X497750Y149858D01*
X498000Y150067D01*
X498250Y150108D01*
X498542Y150025D01*
X498750Y149733D01*
X498833Y149442D01*
Y149067D01*
G01Y149442D02*
X498958Y149692D01*
X499167Y149900D01*
X499417Y149983D01*
X499667Y149900D01*
X499875Y149692D01*
X500000Y149317D01*
X499958Y148942D01*
X499792Y148567D01*
G01X504500Y229517D02*
X507000D01*
Y230558D01*
X506875Y230892D01*
X506708Y231100D01*
X506375Y231183D01*
X506042Y231100D01*
X505833Y230850D01*
X505708Y230558D01*
Y229517D01*
G01Y230558D02*
X504500Y231183D01*
G01X506583Y232658D02*
X506833Y232908D01*
X506958Y233200D01*
X507000Y233533D01*
X506917Y233950D01*
X506708Y234242D01*
X506458Y234325D01*
X506208Y234283D01*
X506000Y234117D01*
X505583Y233283D01*
X505292Y232908D01*
X504875Y232658D01*
X504500Y232575D01*
Y234325D01*
G01X506583Y235758D02*
X506833Y236008D01*
X506958Y236300D01*
X507000Y236633D01*
X506917Y237050D01*
X506708Y237342D01*
X506458Y237425D01*
X506208Y237383D01*
X506000Y237217D01*
X505583Y236383D01*
X505292Y236008D01*
X504875Y235758D01*
X504500Y235675D01*
Y237425D01*
G01Y239650D02*
X504542Y239942D01*
X504667Y240275D01*
X504875Y240483D01*
X505167Y240567D01*
X505458Y240483D01*
X505708Y240233D01*
X505833Y239858D01*
Y239442D01*
X505917Y239192D01*
X506125Y238983D01*
X506417Y238900D01*
X506708Y239025D01*
X506917Y239317D01*
X507000Y239650D01*
X506917Y239983D01*
X506708Y240275D01*
X506417Y240400D01*
X506125Y240317D01*
X505917Y240108D01*
X505833Y239858D01*
Y239442D01*
X505708Y239067D01*
X505458Y238817D01*
X505167Y238733D01*
X504875Y238817D01*
X504667Y239025D01*
X504542Y239358D01*
X504500Y239650D01*
G01X499336Y287888D02*
Y283888D01*
X497336Y285888D01*
X501336D01*
X499336Y283888D01*
G01X526733Y52299D02*
X526983Y52424D01*
X527275Y52507D01*
X527608D01*
X527983Y52382D01*
X528275Y52174D01*
X528483Y51924D01*
X528650Y51507D01*
X528692Y51132D01*
X528608Y50757D01*
X528483Y50507D01*
X528233Y50257D01*
X527942Y50090D01*
X527650Y50007D01*
X527358D01*
X527067Y50090D01*
X526817Y50215D01*
X526608Y50382D01*
G01X525342Y52090D02*
X525092Y52340D01*
X524800Y52465D01*
X524467Y52507D01*
X524050Y52424D01*
X523758Y52215D01*
X523675Y51965D01*
X523717Y51715D01*
X523883Y51507D01*
X524717Y51090D01*
X525092Y50799D01*
X525342Y50382D01*
X525425Y50007D01*
X523675D01*
G01X522158Y50299D02*
X521867Y50090D01*
X521533Y50007D01*
X521200Y50090D01*
X520908Y50340D01*
X520700Y50715D01*
X520617Y51090D01*
Y51549D01*
X520700Y51924D01*
X520908Y52257D01*
X521158Y52424D01*
X521450Y52507D01*
X521783Y52424D01*
X522033Y52257D01*
X522200Y52007D01*
X522283Y51674D01*
X522200Y51382D01*
X521992Y51090D01*
X521742Y50924D01*
X521450Y50882D01*
X521117Y50965D01*
X520867Y51174D01*
X520617Y51549D01*
G01X517850Y50007D02*
Y52507D01*
X519392Y50715D01*
X517308D01*
G01X526733Y47799D02*
X526983Y47924D01*
X527275Y48007D01*
X527608D01*
X527983Y47882D01*
X528275Y47674D01*
X528483Y47424D01*
X528650Y47007D01*
X528692Y46632D01*
X528608Y46257D01*
X528483Y46007D01*
X528233Y45757D01*
X527942Y45590D01*
X527650Y45507D01*
X527358D01*
X527067Y45590D01*
X526817Y45715D01*
X526608Y45882D01*
G01X525467Y46007D02*
X525217Y45715D01*
X524883Y45549D01*
X524508Y45507D01*
X524175Y45549D01*
X523842Y45757D01*
X523633Y46007D01*
X523592Y46257D01*
X523675Y46549D01*
X523967Y46757D01*
X524258Y46840D01*
X524633D01*
G01X524258D02*
X524008Y46965D01*
X523800Y47174D01*
X523717Y47424D01*
X523800Y47674D01*
X524008Y47882D01*
X524383Y48007D01*
X524758Y47965D01*
X525133Y47799D01*
G01X522367Y45882D02*
X522117Y45674D01*
X521825Y45549D01*
X521450Y45507D01*
X521075Y45590D01*
X520783Y45757D01*
X520575Y46049D01*
X520533Y46382D01*
X520617Y46715D01*
X520825Y46924D01*
X521117Y47090D01*
X521408Y47132D01*
X521700Y47090D01*
X522075Y46924D01*
X521950Y48007D01*
X520825D01*
G01X517850Y45507D02*
Y48007D01*
X519392Y46215D01*
X517308D01*
G01X518292Y64774D02*
X518417Y64524D01*
X518500Y64232D01*
Y63899D01*
X518375Y63524D01*
X518167Y63232D01*
X517917Y63024D01*
X517500Y62857D01*
X517125Y62815D01*
X516750Y62899D01*
X516500Y63024D01*
X516250Y63274D01*
X516083Y63565D01*
X516000Y63857D01*
Y64149D01*
X516083Y64440D01*
X516208Y64690D01*
X516375Y64899D01*
G01X518083Y66165D02*
X518333Y66415D01*
X518458Y66707D01*
X518500Y67040D01*
X518417Y67457D01*
X518208Y67749D01*
X517958Y67832D01*
X517708Y67790D01*
X517500Y67624D01*
X517083Y66790D01*
X516792Y66415D01*
X516375Y66165D01*
X516000Y66082D01*
Y67832D01*
G01X516292Y69349D02*
X516083Y69640D01*
X516000Y69974D01*
X516083Y70307D01*
X516333Y70599D01*
X516708Y70807D01*
X517083Y70890D01*
X517542D01*
X517917Y70807D01*
X518250Y70599D01*
X518417Y70349D01*
X518500Y70057D01*
X518417Y69724D01*
X518250Y69474D01*
X518000Y69307D01*
X517667Y69224D01*
X517375Y69307D01*
X517083Y69515D01*
X516917Y69765D01*
X516875Y70057D01*
X516958Y70390D01*
X517167Y70640D01*
X517542Y70890D01*
G01X517042Y72365D02*
X517333Y72657D01*
X517500Y72907D01*
X517583Y73240D01*
X517500Y73532D01*
X517333Y73740D01*
X517083Y73907D01*
X516792Y73949D01*
X516542Y73907D01*
X516292Y73740D01*
X516083Y73490D01*
X516000Y73199D01*
X516083Y72865D01*
X516333Y72574D01*
X516708Y72407D01*
X517125Y72365D01*
X517667Y72449D01*
X517958Y72574D01*
X518250Y72782D01*
X518458Y73074D01*
X518500Y73365D01*
X518417Y73657D01*
X518208Y73865D01*
G01X521000Y99950D02*
X521042Y99617D01*
X521208Y99325D01*
X521458Y99075D01*
X521750Y98908D01*
X522083Y98825D01*
X522417D01*
X522750Y98908D01*
X523042Y99075D01*
X523292Y99325D01*
X523458Y99617D01*
X523500Y99950D01*
X523458Y100283D01*
X523292Y100575D01*
X523042Y100825D01*
X522750Y100992D01*
X522417Y101075D01*
X522083D01*
X521750Y100992D01*
X521458Y100825D01*
X521208Y100575D01*
X521042Y100283D01*
X521000Y99950D01*
G01X521667Y100283D02*
X521000Y100783D01*
G01X523083Y102258D02*
X523333Y102508D01*
X523458Y102800D01*
X523500Y103133D01*
X523417Y103550D01*
X523208Y103842D01*
X522958Y103925D01*
X522708Y103883D01*
X522500Y103717D01*
X522083Y102883D01*
X521792Y102508D01*
X521375Y102258D01*
X521000Y102175D01*
Y103925D01*
G01X520233Y134792D02*
X520483Y134917D01*
X520775Y135000D01*
X521108D01*
X521483Y134875D01*
X521775Y134667D01*
X521983Y134417D01*
X522150Y134000D01*
X522192Y133625D01*
X522108Y133250D01*
X521983Y133000D01*
X521733Y132750D01*
X521442Y132583D01*
X521150Y132500D01*
X520858D01*
X520567Y132583D01*
X520317Y132708D01*
X520108Y132875D01*
G01X518050Y132500D02*
Y135000D01*
X518550Y134500D01*
G01Y132500D02*
X517550D01*
G01X515867Y133000D02*
X515617Y132708D01*
X515283Y132542D01*
X514908Y132500D01*
X514575Y132542D01*
X514242Y132750D01*
X514033Y133000D01*
X513992Y133250D01*
X514075Y133542D01*
X514367Y133750D01*
X514658Y133833D01*
X515033D01*
G01X514658D02*
X514408Y133958D01*
X514200Y134167D01*
X514117Y134417D01*
X514200Y134667D01*
X514408Y134875D01*
X514783Y135000D01*
X515158Y134958D01*
X515533Y134792D01*
G01X512558Y132792D02*
X512267Y132583D01*
X511933Y132500D01*
X511600Y132583D01*
X511308Y132833D01*
X511100Y133208D01*
X511017Y133583D01*
Y134042D01*
X511100Y134417D01*
X511308Y134750D01*
X511558Y134917D01*
X511850Y135000D01*
X512183Y134917D01*
X512433Y134750D01*
X512600Y134500D01*
X512683Y134167D01*
X512600Y133875D01*
X512392Y133583D01*
X512142Y133417D01*
X511850Y133375D01*
X511517Y133458D01*
X511267Y133667D01*
X511017Y134042D01*
G01X534233Y130792D02*
X534483Y130917D01*
X534775Y131000D01*
X535108D01*
X535483Y130875D01*
X535775Y130667D01*
X535983Y130417D01*
X536150Y130000D01*
X536192Y129625D01*
X536108Y129250D01*
X535983Y129000D01*
X535733Y128750D01*
X535442Y128583D01*
X535150Y128500D01*
X534858D01*
X534567Y128583D01*
X534317Y128708D01*
X534108Y128875D01*
G01X532050Y128500D02*
Y131000D01*
X532550Y130500D01*
G01Y128500D02*
X531550D01*
G01X529867Y129000D02*
X529617Y128708D01*
X529283Y128542D01*
X528908Y128500D01*
X528575Y128542D01*
X528242Y128750D01*
X528033Y129000D01*
X527992Y129250D01*
X528075Y129542D01*
X528367Y129750D01*
X528658Y129833D01*
X529033D01*
G01X528658D02*
X528408Y129958D01*
X528200Y130167D01*
X528117Y130417D01*
X528200Y130667D01*
X528408Y130875D01*
X528783Y131000D01*
X529158Y130958D01*
X529533Y130792D01*
G01X525850Y128500D02*
X525558Y128542D01*
X525225Y128667D01*
X525017Y128875D01*
X524933Y129167D01*
X525017Y129458D01*
X525267Y129708D01*
X525642Y129833D01*
X526058D01*
X526308Y129917D01*
X526517Y130125D01*
X526600Y130417D01*
X526475Y130708D01*
X526183Y130917D01*
X525850Y131000D01*
X525517Y130917D01*
X525225Y130708D01*
X525100Y130417D01*
X525183Y130125D01*
X525392Y129917D01*
X525642Y129833D01*
X526058D01*
X526433Y129708D01*
X526683Y129458D01*
X526767Y129167D01*
X526683Y128875D01*
X526475Y128667D01*
X526142Y128542D01*
X525850Y128500D01*
G01X520233Y130792D02*
X520483Y130917D01*
X520775Y131000D01*
X521108D01*
X521483Y130875D01*
X521775Y130667D01*
X521983Y130417D01*
X522150Y130000D01*
X522192Y129625D01*
X522108Y129250D01*
X521983Y129000D01*
X521733Y128750D01*
X521442Y128583D01*
X521150Y128500D01*
X520858D01*
X520567Y128583D01*
X520317Y128708D01*
X520108Y128875D01*
G01X518050Y128500D02*
Y131000D01*
X518550Y130500D01*
G01Y128500D02*
X517550D01*
G01X514450D02*
Y131000D01*
X515992Y129208D01*
X513908D01*
G01X511850Y131000D02*
X512183Y130917D01*
X512433Y130708D01*
X512600Y130458D01*
X512725Y130125D01*
X512767Y129750D01*
X512725Y129375D01*
X512600Y129042D01*
X512433Y128792D01*
X512183Y128583D01*
X511850Y128500D01*
X511517Y128583D01*
X511267Y128792D01*
X511100Y129042D01*
X510975Y129375D01*
X510933Y129750D01*
X510975Y130125D01*
X511100Y130458D01*
X511267Y130708D01*
X511517Y130917D01*
X511850Y131000D01*
G01X534233Y134792D02*
X534483Y134917D01*
X534775Y135000D01*
X535108D01*
X535483Y134875D01*
X535775Y134667D01*
X535983Y134417D01*
X536150Y134000D01*
X536192Y133625D01*
X536108Y133250D01*
X535983Y133000D01*
X535733Y132750D01*
X535442Y132583D01*
X535150Y132500D01*
X534858D01*
X534567Y132583D01*
X534317Y132708D01*
X534108Y132875D01*
G01X532050Y132500D02*
Y135000D01*
X532550Y134500D01*
G01Y132500D02*
X531550D01*
G01X529867Y133000D02*
X529617Y132708D01*
X529283Y132542D01*
X528908Y132500D01*
X528575Y132542D01*
X528242Y132750D01*
X528033Y133000D01*
X527992Y133250D01*
X528075Y133542D01*
X528367Y133750D01*
X528658Y133833D01*
X529033D01*
G01X528658D02*
X528408Y133958D01*
X528200Y134167D01*
X528117Y134417D01*
X528200Y134667D01*
X528408Y134875D01*
X528783Y135000D01*
X529158Y134958D01*
X529533Y134792D01*
G01X525933Y132500D02*
X525850Y133042D01*
X525725Y133500D01*
X525558Y133917D01*
X525350Y134375D01*
X525017Y135000D01*
X526683D01*
G01X522733Y180792D02*
X522983Y180917D01*
X523275Y181000D01*
X523608D01*
X523983Y180875D01*
X524275Y180667D01*
X524483Y180417D01*
X524650Y180000D01*
X524692Y179625D01*
X524608Y179250D01*
X524483Y179000D01*
X524233Y178750D01*
X523942Y178583D01*
X523650Y178500D01*
X523358D01*
X523067Y178583D01*
X522817Y178708D01*
X522608Y178875D01*
G01X520550Y178500D02*
Y181000D01*
X521050Y180500D01*
G01Y178500D02*
X520050D01*
G01X516950D02*
Y181000D01*
X518492Y179208D01*
X516408D01*
G01X513850Y178500D02*
Y181000D01*
X515392Y179208D01*
X513308D01*
G01X522733Y176292D02*
X522983Y176417D01*
X523275Y176500D01*
X523608D01*
X523983Y176375D01*
X524275Y176167D01*
X524483Y175917D01*
X524650Y175500D01*
X524692Y175125D01*
X524608Y174750D01*
X524483Y174500D01*
X524233Y174250D01*
X523942Y174083D01*
X523650Y174000D01*
X523358D01*
X523067Y174083D01*
X522817Y174208D01*
X522608Y174375D01*
G01X520550Y174000D02*
Y176500D01*
X521050Y176000D01*
G01Y174000D02*
X520050D01*
G01X516950D02*
Y176500D01*
X518492Y174708D01*
X516408D01*
G01X515058Y174292D02*
X514767Y174083D01*
X514433Y174000D01*
X514100Y174083D01*
X513808Y174333D01*
X513600Y174708D01*
X513517Y175083D01*
Y175542D01*
X513600Y175917D01*
X513808Y176250D01*
X514058Y176417D01*
X514350Y176500D01*
X514683Y176417D01*
X514933Y176250D01*
X515100Y176000D01*
X515183Y175667D01*
X515100Y175375D01*
X514892Y175083D01*
X514642Y174917D01*
X514350Y174875D01*
X514017Y174958D01*
X513767Y175167D01*
X513517Y175542D01*
G01X523983Y190500D02*
Y193000D01*
X522942D01*
X522608Y192875D01*
X522400Y192708D01*
X522317Y192375D01*
X522400Y192042D01*
X522650Y191833D01*
X522942Y191708D01*
X523983D01*
G01X522942D02*
X522317Y190500D01*
G01X520967Y191000D02*
X520717Y190708D01*
X520383Y190542D01*
X520008Y190500D01*
X519675Y190542D01*
X519342Y190750D01*
X519133Y191000D01*
X519092Y191250D01*
X519175Y191542D01*
X519467Y191750D01*
X519758Y191833D01*
X520133D01*
G01X519758D02*
X519508Y191958D01*
X519300Y192167D01*
X519217Y192417D01*
X519300Y192667D01*
X519508Y192875D01*
X519883Y193000D01*
X520258Y192958D01*
X520633Y192792D01*
G01X517658Y190792D02*
X517367Y190583D01*
X517033Y190500D01*
X516700Y190583D01*
X516408Y190833D01*
X516200Y191208D01*
X516117Y191583D01*
Y192042D01*
X516200Y192417D01*
X516408Y192750D01*
X516658Y192917D01*
X516950Y193000D01*
X517283Y192917D01*
X517533Y192750D01*
X517700Y192500D01*
X517783Y192167D01*
X517700Y191875D01*
X517492Y191583D01*
X517242Y191417D01*
X516950Y191375D01*
X516617Y191458D01*
X516367Y191667D01*
X516117Y192042D01*
G01X513933Y190500D02*
X513850Y191042D01*
X513725Y191500D01*
X513558Y191917D01*
X513350Y192375D01*
X513017Y193000D01*
X514683D01*
G01X523983Y186000D02*
Y188500D01*
X522942D01*
X522608Y188375D01*
X522400Y188208D01*
X522317Y187875D01*
X522400Y187542D01*
X522650Y187333D01*
X522942Y187208D01*
X523983D01*
G01X522942D02*
X522317Y186000D01*
G01X520967Y186500D02*
X520717Y186208D01*
X520383Y186042D01*
X520008Y186000D01*
X519675Y186042D01*
X519342Y186250D01*
X519133Y186500D01*
X519092Y186750D01*
X519175Y187042D01*
X519467Y187250D01*
X519758Y187333D01*
X520133D01*
G01X519758D02*
X519508Y187458D01*
X519300Y187667D01*
X519217Y187917D01*
X519300Y188167D01*
X519508Y188375D01*
X519883Y188500D01*
X520258Y188458D01*
X520633Y188292D01*
G01X517658Y186292D02*
X517367Y186083D01*
X517033Y186000D01*
X516700Y186083D01*
X516408Y186333D01*
X516200Y186708D01*
X516117Y187083D01*
Y187542D01*
X516200Y187917D01*
X516408Y188250D01*
X516658Y188417D01*
X516950Y188500D01*
X517283Y188417D01*
X517533Y188250D01*
X517700Y188000D01*
X517783Y187667D01*
X517700Y187375D01*
X517492Y187083D01*
X517242Y186917D01*
X516950Y186875D01*
X516617Y186958D01*
X516367Y187167D01*
X516117Y187542D01*
G01X514558Y186292D02*
X514267Y186083D01*
X513933Y186000D01*
X513600Y186083D01*
X513308Y186333D01*
X513100Y186708D01*
X513017Y187083D01*
Y187542D01*
X513100Y187917D01*
X513308Y188250D01*
X513558Y188417D01*
X513850Y188500D01*
X514183Y188417D01*
X514433Y188250D01*
X514600Y188000D01*
X514683Y187667D01*
X514600Y187375D01*
X514392Y187083D01*
X514142Y186917D01*
X513850Y186875D01*
X513517Y186958D01*
X513267Y187167D01*
X513017Y187542D01*
G01X528792Y214267D02*
X528917Y214017D01*
X529000Y213725D01*
Y213392D01*
X528875Y213017D01*
X528667Y212725D01*
X528417Y212517D01*
X528000Y212350D01*
X527625Y212308D01*
X527250Y212392D01*
X527000Y212517D01*
X526750Y212767D01*
X526583Y213058D01*
X526500Y213350D01*
Y213642D01*
X526583Y213933D01*
X526708Y214183D01*
X526875Y214392D01*
G01X526500Y216450D02*
X529000D01*
X528500Y215950D01*
G01X526500D02*
Y216950D01*
G01Y219550D02*
X529000D01*
X528500Y219050D01*
G01X526500D02*
Y220050D01*
G01X528583Y221858D02*
X528833Y222108D01*
X528958Y222400D01*
X529000Y222733D01*
X528917Y223150D01*
X528708Y223442D01*
X528458Y223525D01*
X528208Y223483D01*
X528000Y223317D01*
X527583Y222483D01*
X527292Y222108D01*
X526875Y221858D01*
X526500Y221775D01*
Y223525D01*
G01X513500Y229017D02*
X516000D01*
Y230058D01*
X515875Y230392D01*
X515708Y230600D01*
X515375Y230683D01*
X515042Y230600D01*
X514833Y230350D01*
X514708Y230058D01*
Y229017D01*
G01Y230058D02*
X513500Y230683D01*
G01X515583Y232158D02*
X515833Y232408D01*
X515958Y232700D01*
X516000Y233033D01*
X515917Y233450D01*
X515708Y233742D01*
X515458Y233825D01*
X515208Y233783D01*
X515000Y233617D01*
X514583Y232783D01*
X514292Y232408D01*
X513875Y232158D01*
X513500Y232075D01*
Y233825D01*
G01X515583Y235258D02*
X515833Y235508D01*
X515958Y235800D01*
X516000Y236133D01*
X515917Y236550D01*
X515708Y236842D01*
X515458Y236925D01*
X515208Y236883D01*
X515000Y236717D01*
X514583Y235883D01*
X514292Y235508D01*
X513875Y235258D01*
X513500Y235175D01*
Y236925D01*
G01Y239067D02*
X514042Y239150D01*
X514500Y239275D01*
X514917Y239442D01*
X515375Y239650D01*
X516000Y239983D01*
Y238317D01*
G01X545983Y56500D02*
Y59000D01*
X544942D01*
X544608Y58875D01*
X544400Y58708D01*
X544317Y58375D01*
X544400Y58042D01*
X544650Y57833D01*
X544942Y57708D01*
X545983D01*
G01X544942D02*
X544317Y56500D01*
G01X542967Y57000D02*
X542717Y56708D01*
X542383Y56542D01*
X542008Y56500D01*
X541675Y56542D01*
X541342Y56750D01*
X541133Y57000D01*
X541092Y57250D01*
X541175Y57542D01*
X541467Y57750D01*
X541758Y57833D01*
X542133D01*
G01X541758D02*
X541508Y57958D01*
X541300Y58167D01*
X541217Y58417D01*
X541300Y58667D01*
X541508Y58875D01*
X541883Y59000D01*
X542258Y58958D01*
X542633Y58792D01*
G01X539742Y58583D02*
X539492Y58833D01*
X539200Y58958D01*
X538867Y59000D01*
X538450Y58917D01*
X538158Y58708D01*
X538075Y58458D01*
X538117Y58208D01*
X538283Y58000D01*
X539117Y57583D01*
X539492Y57292D01*
X539742Y56875D01*
X539825Y56500D01*
X538075D01*
G01X535850Y59000D02*
X536183Y58917D01*
X536433Y58708D01*
X536600Y58458D01*
X536725Y58125D01*
X536767Y57750D01*
X536725Y57375D01*
X536600Y57042D01*
X536433Y56792D01*
X536183Y56583D01*
X535850Y56500D01*
X535517Y56583D01*
X535267Y56792D01*
X535100Y57042D01*
X534975Y57375D01*
X534933Y57750D01*
X534975Y58125D01*
X535100Y58458D01*
X535267Y58708D01*
X535517Y58917D01*
X535850Y59000D01*
G01X539000Y89500D02*
X526000D01*
Y74000D01*
X533500D01*
Y49500D01*
G01X544233Y54792D02*
X544483Y54917D01*
X544775Y55000D01*
X545108D01*
X545483Y54875D01*
X545775Y54667D01*
X545983Y54417D01*
X546150Y54000D01*
X546192Y53625D01*
X546108Y53250D01*
X545983Y53000D01*
X545733Y52750D01*
X545442Y52583D01*
X545150Y52500D01*
X544858D01*
X544567Y52583D01*
X544317Y52708D01*
X544108Y52875D01*
G01X542050Y52500D02*
Y55000D01*
X542550Y54500D01*
G01Y52500D02*
X541550D01*
G01X539658Y52792D02*
X539367Y52583D01*
X539033Y52500D01*
X538700Y52583D01*
X538408Y52833D01*
X538200Y53208D01*
X538117Y53583D01*
Y54042D01*
X538200Y54417D01*
X538408Y54750D01*
X538658Y54917D01*
X538950Y55000D01*
X539283Y54917D01*
X539533Y54750D01*
X539700Y54500D01*
X539783Y54167D01*
X539700Y53875D01*
X539492Y53583D01*
X539242Y53417D01*
X538950Y53375D01*
X538617Y53458D01*
X538367Y53667D01*
X538117Y54042D01*
G01X535850Y55000D02*
X536183Y54917D01*
X536433Y54708D01*
X536600Y54458D01*
X536725Y54125D01*
X536767Y53750D01*
X536725Y53375D01*
X536600Y53042D01*
X536433Y52792D01*
X536183Y52583D01*
X535850Y52500D01*
X535517Y52583D01*
X535267Y52792D01*
X535100Y53042D01*
X534975Y53375D01*
X534933Y53750D01*
X534975Y54125D01*
X535100Y54458D01*
X535267Y54708D01*
X535517Y54917D01*
X535850Y55000D01*
G01X544233Y50792D02*
X544483Y50917D01*
X544775Y51000D01*
X545108D01*
X545483Y50875D01*
X545775Y50667D01*
X545983Y50417D01*
X546150Y50000D01*
X546192Y49625D01*
X546108Y49250D01*
X545983Y49000D01*
X545733Y48750D01*
X545442Y48583D01*
X545150Y48500D01*
X544858D01*
X544567Y48583D01*
X544317Y48708D01*
X544108Y48875D01*
G01X542050Y48500D02*
Y51000D01*
X542550Y50500D01*
G01Y48500D02*
X541550D01*
G01X539742Y50583D02*
X539492Y50833D01*
X539200Y50958D01*
X538867Y51000D01*
X538450Y50917D01*
X538158Y50708D01*
X538075Y50458D01*
X538117Y50208D01*
X538283Y50000D01*
X539117Y49583D01*
X539492Y49292D01*
X539742Y48875D01*
X539825Y48500D01*
X538075D01*
G01X535850D02*
Y51000D01*
X536350Y50500D01*
G01Y48500D02*
X535350D01*
G01X544233Y62792D02*
X544483Y62917D01*
X544775Y63000D01*
X545108D01*
X545483Y62875D01*
X545775Y62667D01*
X545983Y62417D01*
X546150Y62000D01*
X546192Y61625D01*
X546108Y61250D01*
X545983Y61000D01*
X545733Y60750D01*
X545442Y60583D01*
X545150Y60500D01*
X544858D01*
X544567Y60583D01*
X544317Y60708D01*
X544108Y60875D01*
G01X542050Y60500D02*
Y63000D01*
X542550Y62500D01*
G01Y60500D02*
X541550D01*
G01X539033D02*
X538950Y61042D01*
X538825Y61500D01*
X538658Y61917D01*
X538450Y62375D01*
X538117Y63000D01*
X539783D01*
G01X536642Y61542D02*
X536350Y61833D01*
X536100Y62000D01*
X535767Y62083D01*
X535475Y62000D01*
X535267Y61833D01*
X535100Y61583D01*
X535058Y61292D01*
X535100Y61042D01*
X535267Y60792D01*
X535517Y60583D01*
X535808Y60500D01*
X536142Y60583D01*
X536433Y60833D01*
X536600Y61208D01*
X536642Y61625D01*
X536558Y62167D01*
X536433Y62458D01*
X536225Y62750D01*
X535933Y62958D01*
X535642Y63000D01*
X535350Y62917D01*
X535142Y62708D01*
G01X542792Y67767D02*
X542917Y67517D01*
X543000Y67225D01*
Y66892D01*
X542875Y66517D01*
X542667Y66225D01*
X542417Y66017D01*
X542000Y65850D01*
X541625Y65808D01*
X541250Y65892D01*
X541000Y66017D01*
X540750Y66267D01*
X540583Y66558D01*
X540500Y66850D01*
Y67142D01*
X540583Y67433D01*
X540708Y67683D01*
X540875Y67892D01*
G01X540500Y69950D02*
X543000D01*
X542500Y69450D01*
G01X540500D02*
Y70450D01*
G01X540875Y72133D02*
X540667Y72383D01*
X540542Y72675D01*
X540500Y73050D01*
X540583Y73425D01*
X540750Y73717D01*
X541042Y73925D01*
X541375Y73967D01*
X541708Y73883D01*
X541917Y73675D01*
X542083Y73383D01*
X542125Y73092D01*
X542083Y72800D01*
X541917Y72425D01*
X543000Y72550D01*
Y73675D01*
G01X542583Y75358D02*
X542833Y75608D01*
X542958Y75900D01*
X543000Y76233D01*
X542917Y76650D01*
X542708Y76942D01*
X542458Y77025D01*
X542208Y76983D01*
X542000Y76817D01*
X541583Y75983D01*
X541292Y75608D01*
X540875Y75358D01*
X540500Y75275D01*
Y77025D01*
G01X536000Y73567D02*
X538500D01*
Y74608D01*
X538375Y74942D01*
X538208Y75150D01*
X537875Y75233D01*
X537542Y75150D01*
X537333Y74900D01*
X537208Y74608D01*
Y73567D01*
G01Y74608D02*
X536000Y75233D01*
G01Y78000D02*
X538500D01*
X536708Y76458D01*
Y78542D01*
G01X536000Y80517D02*
X536542Y80600D01*
X537000Y80725D01*
X537417Y80892D01*
X537875Y81100D01*
X538500Y81433D01*
Y79767D01*
G01X534292Y78267D02*
X534417Y78017D01*
X534500Y77725D01*
Y77392D01*
X534375Y77017D01*
X534167Y76725D01*
X533917Y76517D01*
X533500Y76350D01*
X533125Y76308D01*
X532750Y76392D01*
X532500Y76517D01*
X532250Y76767D01*
X532083Y77058D01*
X532000Y77350D01*
Y77642D01*
X532083Y77933D01*
X532208Y78183D01*
X532375Y78392D01*
G01X532000Y80450D02*
X534500D01*
X534000Y79950D01*
G01X532000D02*
Y80950D01*
G01X533042Y82758D02*
X533333Y83050D01*
X533500Y83300D01*
X533583Y83633D01*
X533500Y83925D01*
X533333Y84133D01*
X533083Y84300D01*
X532792Y84342D01*
X532542Y84300D01*
X532292Y84133D01*
X532083Y83883D01*
X532000Y83592D01*
X532083Y83258D01*
X532333Y82967D01*
X532708Y82800D01*
X533125Y82758D01*
X533667Y82842D01*
X533958Y82967D01*
X534250Y83175D01*
X534458Y83467D01*
X534500Y83758D01*
X534417Y84050D01*
X534208Y84258D01*
G01X534500Y86650D02*
X534417Y86317D01*
X534208Y86067D01*
X533958Y85900D01*
X533625Y85775D01*
X533250Y85733D01*
X532875Y85775D01*
X532542Y85900D01*
X532292Y86067D01*
X532083Y86317D01*
X532000Y86650D01*
X532083Y86983D01*
X532292Y87233D01*
X532542Y87400D01*
X532875Y87525D01*
X533250Y87567D01*
X533625Y87525D01*
X533958Y87400D01*
X534208Y87233D01*
X534417Y86983D01*
X534500Y86650D01*
G01X543292Y81267D02*
X543417Y81017D01*
X543500Y80725D01*
Y80392D01*
X543375Y80017D01*
X543167Y79725D01*
X542917Y79517D01*
X542500Y79350D01*
X542125Y79308D01*
X541750Y79392D01*
X541500Y79517D01*
X541250Y79767D01*
X541083Y80058D01*
X541000Y80350D01*
Y80642D01*
X541083Y80933D01*
X541208Y81183D01*
X541375Y81392D01*
G01X541000Y83450D02*
X543500D01*
X543000Y82950D01*
G01X541000D02*
Y83950D01*
G01X541375Y85633D02*
X541167Y85883D01*
X541042Y86175D01*
X541000Y86550D01*
X541083Y86925D01*
X541250Y87217D01*
X541542Y87425D01*
X541875Y87467D01*
X542208Y87383D01*
X542417Y87175D01*
X542583Y86883D01*
X542625Y86592D01*
X542583Y86300D01*
X542417Y85925D01*
X543500Y86050D01*
Y87175D01*
G01X541000Y90150D02*
X543500D01*
X541708Y88608D01*
Y90692D01*
G01X528000Y76517D02*
X530500D01*
Y77558D01*
X530375Y77892D01*
X530208Y78100D01*
X529875Y78183D01*
X529542Y78100D01*
X529333Y77850D01*
X529208Y77558D01*
Y76517D01*
G01Y77558D02*
X528000Y78183D01*
G01X530083Y79658D02*
X530333Y79908D01*
X530458Y80200D01*
X530500Y80533D01*
X530417Y80950D01*
X530208Y81242D01*
X529958Y81325D01*
X529708Y81283D01*
X529500Y81117D01*
X529083Y80283D01*
X528792Y79908D01*
X528375Y79658D01*
X528000Y79575D01*
Y81325D01*
G01X528292Y82842D02*
X528083Y83133D01*
X528000Y83467D01*
X528083Y83800D01*
X528333Y84092D01*
X528708Y84300D01*
X529083Y84383D01*
X529542D01*
X529917Y84300D01*
X530250Y84092D01*
X530417Y83842D01*
X530500Y83550D01*
X530417Y83217D01*
X530250Y82967D01*
X530000Y82800D01*
X529667Y82717D01*
X529375Y82800D01*
X529083Y83008D01*
X528917Y83258D01*
X528875Y83550D01*
X528958Y83883D01*
X529167Y84133D01*
X529542Y84383D01*
G01X528292Y85942D02*
X528083Y86233D01*
X528000Y86567D01*
X528083Y86900D01*
X528333Y87192D01*
X528708Y87400D01*
X529083Y87483D01*
X529542D01*
X529917Y87400D01*
X530250Y87192D01*
X530417Y86942D01*
X530500Y86650D01*
X530417Y86317D01*
X530250Y86067D01*
X530000Y85900D01*
X529667Y85817D01*
X529375Y85900D01*
X529083Y86108D01*
X528917Y86358D01*
X528875Y86650D01*
X528958Y86983D01*
X529167Y87233D01*
X529542Y87483D01*
G01X546633Y105292D02*
X546883Y105417D01*
X547175Y105500D01*
X547508D01*
X547883Y105375D01*
X548175Y105167D01*
X548383Y104917D01*
X548550Y104500D01*
X548592Y104125D01*
X548508Y103750D01*
X548383Y103500D01*
X548133Y103250D01*
X547842Y103083D01*
X547550Y103000D01*
X547258D01*
X546967Y103083D01*
X546717Y103208D01*
X546508Y103375D01*
G01X544450Y103000D02*
Y105500D01*
X544950Y105000D01*
G01Y103000D02*
X543950D01*
G01X542142Y104042D02*
X541850Y104333D01*
X541600Y104500D01*
X541267Y104583D01*
X540975Y104500D01*
X540767Y104333D01*
X540600Y104083D01*
X540558Y103792D01*
X540600Y103542D01*
X540767Y103292D01*
X541017Y103083D01*
X541308Y103000D01*
X541642Y103083D01*
X541933Y103333D01*
X542100Y103708D01*
X542142Y104125D01*
X542058Y104667D01*
X541933Y104958D01*
X541725Y105250D01*
X541433Y105458D01*
X541142Y105500D01*
X540850Y105417D01*
X540642Y105208D01*
G01X539167Y103375D02*
X538917Y103167D01*
X538625Y103042D01*
X538250Y103000D01*
X537875Y103083D01*
X537583Y103250D01*
X537375Y103542D01*
X537333Y103875D01*
X537417Y104208D01*
X537625Y104417D01*
X537917Y104583D01*
X538208Y104625D01*
X538500Y104583D01*
X538875Y104417D01*
X538750Y105500D01*
X537625D01*
G01X546633Y101292D02*
X546883Y101417D01*
X547175Y101500D01*
X547508D01*
X547883Y101375D01*
X548175Y101167D01*
X548383Y100917D01*
X548550Y100500D01*
X548592Y100125D01*
X548508Y99750D01*
X548383Y99500D01*
X548133Y99250D01*
X547842Y99083D01*
X547550Y99000D01*
X547258D01*
X546967Y99083D01*
X546717Y99208D01*
X546508Y99375D01*
G01X544450Y99000D02*
Y101500D01*
X544950Y101000D01*
G01Y99000D02*
X543950D01*
G01X542142Y100042D02*
X541850Y100333D01*
X541600Y100500D01*
X541267Y100583D01*
X540975Y100500D01*
X540767Y100333D01*
X540600Y100083D01*
X540558Y99792D01*
X540600Y99542D01*
X540767Y99292D01*
X541017Y99083D01*
X541308Y99000D01*
X541642Y99083D01*
X541933Y99333D01*
X542100Y99708D01*
X542142Y100125D01*
X542058Y100667D01*
X541933Y100958D01*
X541725Y101250D01*
X541433Y101458D01*
X541142Y101500D01*
X540850Y101417D01*
X540642Y101208D01*
G01X539042Y101083D02*
X538792Y101333D01*
X538500Y101458D01*
X538167Y101500D01*
X537750Y101417D01*
X537458Y101208D01*
X537375Y100958D01*
X537417Y100708D01*
X537583Y100500D01*
X538417Y100083D01*
X538792Y99792D01*
X539042Y99375D01*
X539125Y99000D01*
X537375D01*
G01X537433Y93000D02*
Y95500D01*
X536392D01*
X536058Y95375D01*
X535850Y95208D01*
X535767Y94875D01*
X535850Y94542D01*
X536100Y94333D01*
X536392Y94208D01*
X537433D01*
G01X536392D02*
X535767Y93000D01*
G01X533000D02*
Y95500D01*
X534542Y93708D01*
X532458D01*
G01X530400Y93000D02*
X530108Y93042D01*
X529775Y93167D01*
X529567Y93375D01*
X529483Y93667D01*
X529567Y93958D01*
X529817Y94208D01*
X530192Y94333D01*
X530608D01*
X530858Y94417D01*
X531067Y94625D01*
X531150Y94917D01*
X531025Y95208D01*
X530733Y95417D01*
X530400Y95500D01*
X530067Y95417D01*
X529775Y95208D01*
X529650Y94917D01*
X529733Y94625D01*
X529942Y94417D01*
X530192Y94333D01*
X530608D01*
X530983Y94208D01*
X531233Y93958D01*
X531317Y93667D01*
X531233Y93375D01*
X531025Y93167D01*
X530692Y93042D01*
X530400Y93000D01*
G01X534933Y106000D02*
Y108500D01*
X533892D01*
X533558Y108375D01*
X533350Y108208D01*
X533267Y107875D01*
X533350Y107542D01*
X533600Y107333D01*
X533892Y107208D01*
X534933D01*
G01X533892D02*
X533267Y106000D01*
G01X531917Y106500D02*
X531667Y106208D01*
X531333Y106042D01*
X530958Y106000D01*
X530625Y106042D01*
X530292Y106250D01*
X530083Y106500D01*
X530042Y106750D01*
X530125Y107042D01*
X530417Y107250D01*
X530708Y107333D01*
X531083D01*
G01X530708D02*
X530458Y107458D01*
X530250Y107667D01*
X530167Y107917D01*
X530250Y108167D01*
X530458Y108375D01*
X530833Y108500D01*
X531208Y108458D01*
X531583Y108292D01*
G01X527400Y106000D02*
Y108500D01*
X528942Y106708D01*
X526858D01*
G01X534933Y110000D02*
Y112500D01*
X533892D01*
X533558Y112375D01*
X533350Y112208D01*
X533267Y111875D01*
X533350Y111542D01*
X533600Y111333D01*
X533892Y111208D01*
X534933D01*
G01X533892D02*
X533267Y110000D01*
G01X531917Y110500D02*
X531667Y110208D01*
X531333Y110042D01*
X530958Y110000D01*
X530625Y110042D01*
X530292Y110250D01*
X530083Y110500D01*
X530042Y110750D01*
X530125Y111042D01*
X530417Y111250D01*
X530708Y111333D01*
X531083D01*
G01X530708D02*
X530458Y111458D01*
X530250Y111667D01*
X530167Y111917D01*
X530250Y112167D01*
X530458Y112375D01*
X530833Y112500D01*
X531208Y112458D01*
X531583Y112292D01*
G01X528817Y110500D02*
X528567Y110208D01*
X528233Y110042D01*
X527858Y110000D01*
X527525Y110042D01*
X527192Y110250D01*
X526983Y110500D01*
X526942Y110750D01*
X527025Y111042D01*
X527317Y111250D01*
X527608Y111333D01*
X527983D01*
G01X527608D02*
X527358Y111458D01*
X527150Y111667D01*
X527067Y111917D01*
X527150Y112167D01*
X527358Y112375D01*
X527733Y112500D01*
X528108Y112458D01*
X528483Y112292D01*
G01X534500Y212517D02*
X537000D01*
Y213517D01*
X536875Y213850D01*
X536583Y214100D01*
X536250Y214183D01*
X535917Y214100D01*
X535667Y213892D01*
X535542Y213517D01*
Y212517D01*
G01X536792Y217367D02*
X536917Y217117D01*
X537000Y216825D01*
Y216492D01*
X536875Y216117D01*
X536667Y215825D01*
X536417Y215617D01*
X536000Y215450D01*
X535625Y215408D01*
X535250Y215492D01*
X535000Y215617D01*
X534750Y215867D01*
X534583Y216158D01*
X534500Y216450D01*
Y216742D01*
X534583Y217033D01*
X534708Y217283D01*
X534875Y217492D01*
G01X534500Y219550D02*
X537000D01*
X536500Y219050D01*
G01X534500D02*
Y220050D01*
G01Y223150D02*
X537000D01*
X535208Y221608D01*
Y223692D01*
G01X536583Y224958D02*
X536833Y225208D01*
X536958Y225500D01*
X537000Y225833D01*
X536917Y226250D01*
X536708Y226542D01*
X536458Y226625D01*
X536208Y226583D01*
X536000Y226417D01*
X535583Y225583D01*
X535292Y225208D01*
X534875Y224958D01*
X534500Y224875D01*
Y226625D01*
G01X530500Y212517D02*
X533000D01*
Y213517D01*
X532875Y213850D01*
X532583Y214100D01*
X532250Y214183D01*
X531917Y214100D01*
X531667Y213892D01*
X531542Y213517D01*
Y212517D01*
G01X532792Y217367D02*
X532917Y217117D01*
X533000Y216825D01*
Y216492D01*
X532875Y216117D01*
X532667Y215825D01*
X532417Y215617D01*
X532000Y215450D01*
X531625Y215408D01*
X531250Y215492D01*
X531000Y215617D01*
X530750Y215867D01*
X530583Y216158D01*
X530500Y216450D01*
Y216742D01*
X530583Y217033D01*
X530708Y217283D01*
X530875Y217492D01*
G01X530500Y219550D02*
X533000D01*
X532500Y219050D01*
G01X530500D02*
Y220050D01*
G01Y223150D02*
X533000D01*
X531208Y221608D01*
Y223692D01*
G01X531542Y224958D02*
X531833Y225250D01*
X532000Y225500D01*
X532083Y225833D01*
X532000Y226125D01*
X531833Y226333D01*
X531583Y226500D01*
X531292Y226542D01*
X531042Y226500D01*
X530792Y226333D01*
X530583Y226083D01*
X530500Y225792D01*
X530583Y225458D01*
X530833Y225167D01*
X531208Y225000D01*
X531625Y224958D01*
X532167Y225042D01*
X532458Y225167D01*
X532750Y225375D01*
X532958Y225667D01*
X533000Y225958D01*
X532917Y226250D01*
X532708Y226458D01*
G01X538500Y212517D02*
X541000D01*
Y213517D01*
X540875Y213850D01*
X540583Y214100D01*
X540250Y214183D01*
X539917Y214100D01*
X539667Y213892D01*
X539542Y213517D01*
Y212517D01*
G01X540792Y217367D02*
X540917Y217117D01*
X541000Y216825D01*
Y216492D01*
X540875Y216117D01*
X540667Y215825D01*
X540417Y215617D01*
X540000Y215450D01*
X539625Y215408D01*
X539250Y215492D01*
X539000Y215617D01*
X538750Y215867D01*
X538583Y216158D01*
X538500Y216450D01*
Y216742D01*
X538583Y217033D01*
X538708Y217283D01*
X538875Y217492D01*
G01X538500Y219550D02*
X541000D01*
X540500Y219050D01*
G01X538500D02*
Y220050D01*
G01Y223150D02*
X541000D01*
X539208Y221608D01*
Y223692D01*
G01X539000Y224833D02*
X538708Y225083D01*
X538542Y225417D01*
X538500Y225792D01*
X538542Y226125D01*
X538750Y226458D01*
X539000Y226667D01*
X539250Y226708D01*
X539542Y226625D01*
X539750Y226333D01*
X539833Y226042D01*
Y225667D01*
G01Y226042D02*
X539958Y226292D01*
X540167Y226500D01*
X540417Y226583D01*
X540667Y226500D01*
X540875Y226292D01*
X541000Y225917D01*
X540958Y225542D01*
X540792Y225167D01*
G01X528000Y229017D02*
X530500D01*
Y230058D01*
X530375Y230392D01*
X530208Y230600D01*
X529875Y230683D01*
X529542Y230600D01*
X529333Y230350D01*
X529208Y230058D01*
Y229017D01*
G01Y230058D02*
X528000Y230683D01*
G01X530083Y232158D02*
X530333Y232408D01*
X530458Y232700D01*
X530500Y233033D01*
X530417Y233450D01*
X530208Y233742D01*
X529958Y233825D01*
X529708Y233783D01*
X529500Y233617D01*
X529083Y232783D01*
X528792Y232408D01*
X528375Y232158D01*
X528000Y232075D01*
Y233825D01*
G01X528500Y235133D02*
X528208Y235383D01*
X528042Y235717D01*
X528000Y236092D01*
X528042Y236425D01*
X528250Y236758D01*
X528500Y236967D01*
X528750Y237008D01*
X529042Y236925D01*
X529250Y236633D01*
X529333Y236342D01*
Y235967D01*
G01Y236342D02*
X529458Y236592D01*
X529667Y236800D01*
X529917Y236883D01*
X530167Y236800D01*
X530375Y236592D01*
X530500Y236217D01*
X530458Y235842D01*
X530292Y235467D01*
G01X528000Y239150D02*
X530500D01*
X530000Y238650D01*
G01X528000D02*
Y239650D01*
G01X541500Y229017D02*
X544000D01*
Y230058D01*
X543875Y230392D01*
X543708Y230600D01*
X543375Y230683D01*
X543042Y230600D01*
X542833Y230350D01*
X542708Y230058D01*
Y229017D01*
G01Y230058D02*
X541500Y230683D01*
G01X543583Y232158D02*
X543833Y232408D01*
X543958Y232700D01*
X544000Y233033D01*
X543917Y233450D01*
X543708Y233742D01*
X543458Y233825D01*
X543208Y233783D01*
X543000Y233617D01*
X542583Y232783D01*
X542292Y232408D01*
X541875Y232158D01*
X541500Y232075D01*
Y233825D01*
G01X542000Y235133D02*
X541708Y235383D01*
X541542Y235717D01*
X541500Y236092D01*
X541542Y236425D01*
X541750Y236758D01*
X542000Y236967D01*
X542250Y237008D01*
X542542Y236925D01*
X542750Y236633D01*
X542833Y236342D01*
Y235967D01*
G01Y236342D02*
X542958Y236592D01*
X543167Y236800D01*
X543417Y236883D01*
X543667Y236800D01*
X543875Y236592D01*
X544000Y236217D01*
X543958Y235842D01*
X543792Y235467D01*
G01X543583Y238358D02*
X543833Y238608D01*
X543958Y238900D01*
X544000Y239233D01*
X543917Y239650D01*
X543708Y239942D01*
X543458Y240025D01*
X543208Y239983D01*
X543000Y239817D01*
X542583Y238983D01*
X542292Y238608D01*
X541875Y238358D01*
X541500Y238275D01*
Y240025D01*
G01X560233Y50792D02*
X560483Y50917D01*
X560775Y51000D01*
X561108D01*
X561483Y50875D01*
X561775Y50667D01*
X561983Y50417D01*
X562150Y50000D01*
X562192Y49625D01*
X562108Y49250D01*
X561983Y49000D01*
X561733Y48750D01*
X561442Y48583D01*
X561150Y48500D01*
X560858D01*
X560567Y48583D01*
X560317Y48708D01*
X560108Y48875D01*
G01X558842Y50583D02*
X558592Y50833D01*
X558300Y50958D01*
X557967Y51000D01*
X557550Y50917D01*
X557258Y50708D01*
X557175Y50458D01*
X557217Y50208D01*
X557383Y50000D01*
X558217Y49583D01*
X558592Y49292D01*
X558842Y48875D01*
X558925Y48500D01*
X557175D01*
G01X554950Y51000D02*
X555283Y50917D01*
X555533Y50708D01*
X555700Y50458D01*
X555825Y50125D01*
X555867Y49750D01*
X555825Y49375D01*
X555700Y49042D01*
X555533Y48792D01*
X555283Y48583D01*
X554950Y48500D01*
X554617Y48583D01*
X554367Y48792D01*
X554200Y49042D01*
X554075Y49375D01*
X554033Y49750D01*
X554075Y50125D01*
X554200Y50458D01*
X554367Y50708D01*
X554617Y50917D01*
X554950Y51000D01*
G01X551350Y48500D02*
Y51000D01*
X552892Y49208D01*
X550808D01*
G01X560233Y54792D02*
X560483Y54917D01*
X560775Y55000D01*
X561108D01*
X561483Y54875D01*
X561775Y54667D01*
X561983Y54417D01*
X562150Y54000D01*
X562192Y53625D01*
X562108Y53250D01*
X561983Y53000D01*
X561733Y52750D01*
X561442Y52583D01*
X561150Y52500D01*
X560858D01*
X560567Y52583D01*
X560317Y52708D01*
X560108Y52875D01*
G01X558050Y52500D02*
Y55000D01*
X558550Y54500D01*
G01Y52500D02*
X557550D01*
G01X555658Y52792D02*
X555367Y52583D01*
X555033Y52500D01*
X554700Y52583D01*
X554408Y52833D01*
X554200Y53208D01*
X554117Y53583D01*
Y54042D01*
X554200Y54417D01*
X554408Y54750D01*
X554658Y54917D01*
X554950Y55000D01*
X555283Y54917D01*
X555533Y54750D01*
X555700Y54500D01*
X555783Y54167D01*
X555700Y53875D01*
X555492Y53583D01*
X555242Y53417D01*
X554950Y53375D01*
X554617Y53458D01*
X554367Y53667D01*
X554117Y54042D01*
G01X551850Y52500D02*
X551558Y52542D01*
X551225Y52667D01*
X551017Y52875D01*
X550933Y53167D01*
X551017Y53458D01*
X551267Y53708D01*
X551642Y53833D01*
X552058D01*
X552308Y53917D01*
X552517Y54125D01*
X552600Y54417D01*
X552475Y54708D01*
X552183Y54917D01*
X551850Y55000D01*
X551517Y54917D01*
X551225Y54708D01*
X551100Y54417D01*
X551183Y54125D01*
X551392Y53917D01*
X551642Y53833D01*
X552058D01*
X552433Y53708D01*
X552683Y53458D01*
X552767Y53167D01*
X552683Y52875D01*
X552475Y52667D01*
X552142Y52542D01*
X551850Y52500D01*
G01X560233Y58792D02*
X560483Y58917D01*
X560775Y59000D01*
X561108D01*
X561483Y58875D01*
X561775Y58667D01*
X561983Y58417D01*
X562150Y58000D01*
X562192Y57625D01*
X562108Y57250D01*
X561983Y57000D01*
X561733Y56750D01*
X561442Y56583D01*
X561150Y56500D01*
X560858D01*
X560567Y56583D01*
X560317Y56708D01*
X560108Y56875D01*
G01X558050Y56500D02*
Y59000D01*
X558550Y58500D01*
G01Y56500D02*
X557550D01*
G01X554950D02*
X554658Y56542D01*
X554325Y56667D01*
X554117Y56875D01*
X554033Y57167D01*
X554117Y57458D01*
X554367Y57708D01*
X554742Y57833D01*
X555158D01*
X555408Y57917D01*
X555617Y58125D01*
X555700Y58417D01*
X555575Y58708D01*
X555283Y58917D01*
X554950Y59000D01*
X554617Y58917D01*
X554325Y58708D01*
X554200Y58417D01*
X554283Y58125D01*
X554492Y57917D01*
X554742Y57833D01*
X555158D01*
X555533Y57708D01*
X555783Y57458D01*
X555867Y57167D01*
X555783Y56875D01*
X555575Y56667D01*
X555242Y56542D01*
X554950Y56500D01*
G01X552767Y57000D02*
X552517Y56708D01*
X552183Y56542D01*
X551808Y56500D01*
X551475Y56542D01*
X551142Y56750D01*
X550933Y57000D01*
X550892Y57250D01*
X550975Y57542D01*
X551267Y57750D01*
X551558Y57833D01*
X551933D01*
G01X551558D02*
X551308Y57958D01*
X551100Y58167D01*
X551017Y58417D01*
X551100Y58667D01*
X551308Y58875D01*
X551683Y59000D01*
X552058Y58958D01*
X552433Y58792D01*
G01X557700Y67000D02*
X555033D01*
Y64900D01*
X555833Y64200D01*
X556767Y63733D01*
X558100Y63500D01*
X559433Y63733D01*
X560367Y64200D01*
X561167Y64900D01*
X561700Y65717D01*
X561967Y66650D01*
Y67467D01*
X561700Y68167D01*
X561167Y68983D01*
X560367Y69683D01*
X559567Y70150D01*
X558500Y70500D01*
X557567D01*
X556500Y70267D01*
X555700Y69800D01*
G01X547292Y67767D02*
X547417Y67517D01*
X547500Y67225D01*
Y66892D01*
X547375Y66517D01*
X547167Y66225D01*
X546917Y66017D01*
X546500Y65850D01*
X546125Y65808D01*
X545750Y65892D01*
X545500Y66017D01*
X545250Y66267D01*
X545083Y66558D01*
X545000Y66850D01*
Y67142D01*
X545083Y67433D01*
X545208Y67683D01*
X545375Y67892D01*
G01X545000Y69950D02*
X547500D01*
X547000Y69450D01*
G01X545000D02*
Y70450D01*
G01Y72967D02*
X545542Y73050D01*
X546000Y73175D01*
X546417Y73342D01*
X546875Y73550D01*
X547500Y73883D01*
Y72217D01*
G01X545000Y76150D02*
X545042Y76442D01*
X545167Y76775D01*
X545375Y76983D01*
X545667Y77067D01*
X545958Y76983D01*
X546208Y76733D01*
X546333Y76358D01*
Y75942D01*
X546417Y75692D01*
X546625Y75483D01*
X546917Y75400D01*
X547208Y75525D01*
X547417Y75817D01*
X547500Y76150D01*
X547417Y76483D01*
X547208Y76775D01*
X546917Y76900D01*
X546625Y76817D01*
X546417Y76608D01*
X546333Y76358D01*
Y75942D01*
X546208Y75567D01*
X545958Y75317D01*
X545667Y75233D01*
X545375Y75317D01*
X545167Y75525D01*
X545042Y75858D01*
X545000Y76150D01*
G01X551292Y68267D02*
X551417Y68017D01*
X551500Y67725D01*
Y67392D01*
X551375Y67017D01*
X551167Y66725D01*
X550917Y66517D01*
X550500Y66350D01*
X550125Y66308D01*
X549750Y66392D01*
X549500Y66517D01*
X549250Y66767D01*
X549083Y67058D01*
X549000Y67350D01*
Y67642D01*
X549083Y67933D01*
X549208Y68183D01*
X549375Y68392D01*
G01X549000Y70450D02*
X551500D01*
X551000Y69950D01*
G01X549000D02*
Y70950D01*
G01X550042Y72758D02*
X550333Y73050D01*
X550500Y73300D01*
X550583Y73633D01*
X550500Y73925D01*
X550333Y74133D01*
X550083Y74300D01*
X549792Y74342D01*
X549542Y74300D01*
X549292Y74133D01*
X549083Y73883D01*
X549000Y73592D01*
X549083Y73258D01*
X549333Y72967D01*
X549708Y72800D01*
X550125Y72758D01*
X550667Y72842D01*
X550958Y72967D01*
X551250Y73175D01*
X551458Y73467D01*
X551500Y73758D01*
X551417Y74050D01*
X551208Y74258D01*
G01X549000Y76567D02*
X549542Y76650D01*
X550000Y76775D01*
X550417Y76942D01*
X550875Y77150D01*
X551500Y77483D01*
Y75817D01*
G01X565150Y74500D02*
Y72000D01*
G01X566108Y74500D02*
X564192D01*
G01X562883Y72000D02*
Y74500D01*
X561883D01*
X561550Y74375D01*
X561300Y74083D01*
X561217Y73750D01*
X561300Y73417D01*
X561508Y73167D01*
X561883Y73042D01*
X562883D01*
G01X559867Y72500D02*
X559617Y72208D01*
X559283Y72042D01*
X558908Y72000D01*
X558575Y72042D01*
X558242Y72250D01*
X558033Y72500D01*
X557992Y72750D01*
X558075Y73042D01*
X558367Y73250D01*
X558658Y73333D01*
X559033D01*
G01X558658D02*
X558408Y73458D01*
X558200Y73667D01*
X558117Y73917D01*
X558200Y74167D01*
X558408Y74375D01*
X558783Y74500D01*
X559158Y74458D01*
X559533Y74292D01*
G01X555850Y72000D02*
Y74500D01*
X556350Y74000D01*
G01Y72000D02*
X555350D01*
G01X557650Y83000D02*
Y80500D01*
G01X558608Y83000D02*
X556692D01*
G01X555383Y80500D02*
Y83000D01*
X554383D01*
X554050Y82875D01*
X553800Y82583D01*
X553717Y82250D01*
X553800Y81917D01*
X554008Y81667D01*
X554383Y81542D01*
X555383D01*
G01X552242Y82583D02*
X551992Y82833D01*
X551700Y82958D01*
X551367Y83000D01*
X550950Y82917D01*
X550658Y82708D01*
X550575Y82458D01*
X550617Y82208D01*
X550783Y82000D01*
X551617Y81583D01*
X551992Y81292D01*
X552242Y80875D01*
X552325Y80500D01*
X550575D01*
G01X548350D02*
X548058Y80542D01*
X547725Y80667D01*
X547517Y80875D01*
X547433Y81167D01*
X547517Y81458D01*
X547767Y81708D01*
X548142Y81833D01*
X548558D01*
X548808Y81917D01*
X549017Y82125D01*
X549100Y82417D01*
X548975Y82708D01*
X548683Y82917D01*
X548350Y83000D01*
X548017Y82917D01*
X547725Y82708D01*
X547600Y82417D01*
X547683Y82125D01*
X547892Y81917D01*
X548142Y81833D01*
X548558D01*
X548933Y81708D01*
X549183Y81458D01*
X549267Y81167D01*
X549183Y80875D01*
X548975Y80667D01*
X548642Y80542D01*
X548350Y80500D01*
G01X558650Y89000D02*
Y86500D01*
G01X559608Y89000D02*
X557692D01*
G01X556383Y86500D02*
Y89000D01*
X555383D01*
X555050Y88875D01*
X554800Y88583D01*
X554717Y88250D01*
X554800Y87917D01*
X555008Y87667D01*
X555383Y87542D01*
X556383D01*
G01X553242Y88583D02*
X552992Y88833D01*
X552700Y88958D01*
X552367Y89000D01*
X551950Y88917D01*
X551658Y88708D01*
X551575Y88458D01*
X551617Y88208D01*
X551783Y88000D01*
X552617Y87583D01*
X552992Y87292D01*
X553242Y86875D01*
X553325Y86500D01*
X551575D01*
G01X550142Y88583D02*
X549892Y88833D01*
X549600Y88958D01*
X549267Y89000D01*
X548850Y88917D01*
X548558Y88708D01*
X548475Y88458D01*
X548517Y88208D01*
X548683Y88000D01*
X549517Y87583D01*
X549892Y87292D01*
X550142Y86875D01*
X550225Y86500D01*
X548475D01*
G01X563000Y92000D02*
X549000D01*
Y90500D01*
X545000D01*
G01X556385Y102400D02*
Y108280D01*
G01X552555Y103085D02*
X551820Y106320D01*
G01X552895Y101520D02*
X552555Y103085D01*
G01X553115Y101025D02*
X552895Y101520D01*
G01X553400Y100635D02*
X553115Y101025D01*
G01X553850Y100440D02*
X553400Y100635D01*
G01X554190D02*
X553850Y100440D01*
G01X553620Y106320D02*
X552555Y103085D01*
G01X546500Y123017D02*
X549000D01*
Y124058D01*
X548875Y124392D01*
X548708Y124600D01*
X548375Y124683D01*
X548042Y124600D01*
X547833Y124350D01*
X547708Y124058D01*
Y123017D01*
G01Y124058D02*
X546500Y124683D01*
G01Y127450D02*
X549000D01*
X547208Y125908D01*
Y127992D01*
G01X546500Y130050D02*
X546542Y130342D01*
X546667Y130675D01*
X546875Y130883D01*
X547167Y130967D01*
X547458Y130883D01*
X547708Y130633D01*
X547833Y130258D01*
Y129842D01*
X547917Y129592D01*
X548125Y129383D01*
X548417Y129300D01*
X548708Y129425D01*
X548917Y129717D01*
X549000Y130050D01*
X548917Y130383D01*
X548708Y130675D01*
X548417Y130800D01*
X548125Y130717D01*
X547917Y130508D01*
X547833Y130258D01*
Y129842D01*
X547708Y129467D01*
X547458Y129217D01*
X547167Y129133D01*
X546875Y129217D01*
X546667Y129425D01*
X546542Y129758D01*
X546500Y130050D01*
G01X548583Y132358D02*
X548833Y132608D01*
X548958Y132900D01*
X549000Y133233D01*
X548917Y133650D01*
X548708Y133942D01*
X548458Y134025D01*
X548208Y133983D01*
X548000Y133817D01*
X547583Y132983D01*
X547292Y132608D01*
X546875Y132358D01*
X546500Y132275D01*
Y134025D01*
G01X546292Y166267D02*
X546417Y166017D01*
X546500Y165725D01*
Y165392D01*
X546375Y165017D01*
X546167Y164725D01*
X545917Y164517D01*
X545500Y164350D01*
X545125Y164308D01*
X544750Y164392D01*
X544500Y164517D01*
X544250Y164767D01*
X544083Y165058D01*
X544000Y165350D01*
Y165642D01*
X544083Y165933D01*
X544208Y166183D01*
X544375Y166392D01*
G01X544000Y168450D02*
X546500D01*
X546000Y167950D01*
G01X544000D02*
Y168950D01*
G01X545042Y170758D02*
X545333Y171050D01*
X545500Y171300D01*
X545583Y171633D01*
X545500Y171925D01*
X545333Y172133D01*
X545083Y172300D01*
X544792Y172342D01*
X544542Y172300D01*
X544292Y172133D01*
X544083Y171883D01*
X544000Y171592D01*
X544083Y171258D01*
X544333Y170967D01*
X544708Y170800D01*
X545125Y170758D01*
X545667Y170842D01*
X545958Y170967D01*
X546250Y171175D01*
X546458Y171467D01*
X546500Y171758D01*
X546417Y172050D01*
X546208Y172258D01*
G01X544000Y175150D02*
X546500D01*
X544708Y173608D01*
Y175692D01*
G01X550292Y166267D02*
X550417Y166017D01*
X550500Y165725D01*
Y165392D01*
X550375Y165017D01*
X550167Y164725D01*
X549917Y164517D01*
X549500Y164350D01*
X549125Y164308D01*
X548750Y164392D01*
X548500Y164517D01*
X548250Y164767D01*
X548083Y165058D01*
X548000Y165350D01*
Y165642D01*
X548083Y165933D01*
X548208Y166183D01*
X548375Y166392D01*
G01X548000Y168450D02*
X550500D01*
X550000Y167950D01*
G01X548000D02*
Y168950D01*
G01Y171467D02*
X548542Y171550D01*
X549000Y171675D01*
X549417Y171842D01*
X549875Y172050D01*
X550500Y172383D01*
Y170717D01*
G01X550083Y173858D02*
X550333Y174108D01*
X550458Y174400D01*
X550500Y174733D01*
X550417Y175150D01*
X550208Y175442D01*
X549958Y175525D01*
X549708Y175483D01*
X549500Y175317D01*
X549083Y174483D01*
X548792Y174108D01*
X548375Y173858D01*
X548000Y173775D01*
Y175525D01*
G01X558292Y166267D02*
X558417Y166017D01*
X558500Y165725D01*
Y165392D01*
X558375Y165017D01*
X558167Y164725D01*
X557917Y164517D01*
X557500Y164350D01*
X557125Y164308D01*
X556750Y164392D01*
X556500Y164517D01*
X556250Y164767D01*
X556083Y165058D01*
X556000Y165350D01*
Y165642D01*
X556083Y165933D01*
X556208Y166183D01*
X556375Y166392D01*
G01X556000Y168450D02*
X558500D01*
X558000Y167950D01*
G01X556000D02*
Y168950D01*
G01X556292Y170842D02*
X556083Y171133D01*
X556000Y171467D01*
X556083Y171800D01*
X556333Y172092D01*
X556708Y172300D01*
X557083Y172383D01*
X557542D01*
X557917Y172300D01*
X558250Y172092D01*
X558417Y171842D01*
X558500Y171550D01*
X558417Y171217D01*
X558250Y170967D01*
X558000Y170800D01*
X557667Y170717D01*
X557375Y170800D01*
X557083Y171008D01*
X556917Y171258D01*
X556875Y171550D01*
X556958Y171883D01*
X557167Y172133D01*
X557542Y172383D01*
G01X558083Y173858D02*
X558333Y174108D01*
X558458Y174400D01*
X558500Y174733D01*
X558417Y175150D01*
X558208Y175442D01*
X557958Y175525D01*
X557708Y175483D01*
X557500Y175317D01*
X557083Y174483D01*
X556792Y174108D01*
X556375Y173858D01*
X556000Y173775D01*
Y175525D01*
G01X552000Y164517D02*
X554500D01*
Y165558D01*
X554375Y165892D01*
X554208Y166100D01*
X553875Y166183D01*
X553542Y166100D01*
X553333Y165850D01*
X553208Y165558D01*
Y164517D01*
G01Y165558D02*
X552000Y166183D01*
G01X552500Y167533D02*
X552208Y167783D01*
X552042Y168117D01*
X552000Y168492D01*
X552042Y168825D01*
X552250Y169158D01*
X552500Y169367D01*
X552750Y169408D01*
X553042Y169325D01*
X553250Y169033D01*
X553333Y168742D01*
Y168367D01*
G01Y168742D02*
X553458Y168992D01*
X553667Y169200D01*
X553917Y169283D01*
X554167Y169200D01*
X554375Y168992D01*
X554500Y168617D01*
X554458Y168242D01*
X554292Y167867D01*
G01X552500Y170633D02*
X552208Y170883D01*
X552042Y171217D01*
X552000Y171592D01*
X552042Y171925D01*
X552250Y172258D01*
X552500Y172467D01*
X552750Y172508D01*
X553042Y172425D01*
X553250Y172133D01*
X553333Y171842D01*
Y171467D01*
G01Y171842D02*
X553458Y172092D01*
X553667Y172300D01*
X553917Y172383D01*
X554167Y172300D01*
X554375Y172092D01*
X554500Y171717D01*
X554458Y171342D01*
X554292Y170967D01*
G01X552000Y174650D02*
X552042Y174942D01*
X552167Y175275D01*
X552375Y175483D01*
X552667Y175567D01*
X552958Y175483D01*
X553208Y175233D01*
X553333Y174858D01*
Y174442D01*
X553417Y174192D01*
X553625Y173983D01*
X553917Y173900D01*
X554208Y174025D01*
X554417Y174317D01*
X554500Y174650D01*
X554417Y174983D01*
X554208Y175275D01*
X553917Y175400D01*
X553625Y175317D01*
X553417Y175108D01*
X553333Y174858D01*
Y174442D01*
X553208Y174067D01*
X552958Y173817D01*
X552667Y173733D01*
X552375Y173817D01*
X552167Y174025D01*
X552042Y174358D01*
X552000Y174650D01*
G01X552983Y181500D02*
Y184000D01*
X551942D01*
X551608Y183875D01*
X551400Y183708D01*
X551317Y183375D01*
X551400Y183042D01*
X551650Y182833D01*
X551942Y182708D01*
X552983D01*
G01X551942D02*
X551317Y181500D01*
G01X549842Y183583D02*
X549592Y183833D01*
X549300Y183958D01*
X548967Y184000D01*
X548550Y183917D01*
X548258Y183708D01*
X548175Y183458D01*
X548217Y183208D01*
X548383Y183000D01*
X549217Y182583D01*
X549592Y182292D01*
X549842Y181875D01*
X549925Y181500D01*
X548175D01*
G01X546658Y181792D02*
X546367Y181583D01*
X546033Y181500D01*
X545700Y181583D01*
X545408Y181833D01*
X545200Y182208D01*
X545117Y182583D01*
Y183042D01*
X545200Y183417D01*
X545408Y183750D01*
X545658Y183917D01*
X545950Y184000D01*
X546283Y183917D01*
X546533Y183750D01*
X546700Y183500D01*
X546783Y183167D01*
X546700Y182875D01*
X546492Y182583D01*
X546242Y182417D01*
X545950Y182375D01*
X545617Y182458D01*
X545367Y182667D01*
X545117Y183042D01*
G01X542933Y181500D02*
X542850Y182042D01*
X542725Y182500D01*
X542558Y182917D01*
X542350Y183375D01*
X542017Y184000D01*
X543683D01*
G01X563933Y181500D02*
Y184000D01*
X562892D01*
X562558Y183875D01*
X562350Y183708D01*
X562267Y183375D01*
X562350Y183042D01*
X562600Y182833D01*
X562892Y182708D01*
X563933D01*
G01X562892D02*
X562267Y181500D01*
G01X560083D02*
X560000Y182042D01*
X559875Y182500D01*
X559708Y182917D01*
X559500Y183375D01*
X559167Y184000D01*
X560833D01*
G01X557692Y182542D02*
X557400Y182833D01*
X557150Y183000D01*
X556817Y183083D01*
X556525Y183000D01*
X556317Y182833D01*
X556150Y182583D01*
X556108Y182292D01*
X556150Y182042D01*
X556317Y181792D01*
X556567Y181583D01*
X556858Y181500D01*
X557192Y181583D01*
X557483Y181833D01*
X557650Y182208D01*
X557692Y182625D01*
X557608Y183167D01*
X557483Y183458D01*
X557275Y183750D01*
X556983Y183958D01*
X556692Y184000D01*
X556400Y183917D01*
X556192Y183708D01*
G01X567292Y52767D02*
X567417Y52517D01*
X567500Y52225D01*
Y51892D01*
X567375Y51517D01*
X567167Y51225D01*
X566917Y51017D01*
X566500Y50850D01*
X566125Y50808D01*
X565750Y50892D01*
X565500Y51017D01*
X565250Y51267D01*
X565083Y51558D01*
X565000Y51850D01*
Y52142D01*
X565083Y52433D01*
X565208Y52683D01*
X565375Y52892D01*
G01X565000Y54950D02*
X567500D01*
X567000Y54450D01*
G01X565000D02*
Y55450D01*
G01Y58050D02*
X565042Y58342D01*
X565167Y58675D01*
X565375Y58883D01*
X565667Y58967D01*
X565958Y58883D01*
X566208Y58633D01*
X566333Y58258D01*
Y57842D01*
X566417Y57592D01*
X566625Y57383D01*
X566917Y57300D01*
X567208Y57425D01*
X567417Y57717D01*
X567500Y58050D01*
X567417Y58383D01*
X567208Y58675D01*
X566917Y58800D01*
X566625Y58717D01*
X566417Y58508D01*
X566333Y58258D01*
Y57842D01*
X566208Y57467D01*
X565958Y57217D01*
X565667Y57133D01*
X565375Y57217D01*
X565167Y57425D01*
X565042Y57758D01*
X565000Y58050D01*
G01X567083Y60358D02*
X567333Y60608D01*
X567458Y60900D01*
X567500Y61233D01*
X567417Y61650D01*
X567208Y61942D01*
X566958Y62025D01*
X566708Y61983D01*
X566500Y61817D01*
X566083Y60983D01*
X565792Y60608D01*
X565375Y60358D01*
X565000Y60275D01*
Y62025D01*
G01X566500Y49000D02*
X578000D01*
Y88500D01*
X575500D01*
G01X574150Y67500D02*
Y65000D01*
G01X575108Y67500D02*
X573192D01*
G01X571883Y65000D02*
Y67500D01*
X570883D01*
X570550Y67375D01*
X570300Y67083D01*
X570217Y66750D01*
X570300Y66417D01*
X570508Y66167D01*
X570883Y66042D01*
X571883D01*
G01X568742Y67083D02*
X568492Y67333D01*
X568200Y67458D01*
X567867Y67500D01*
X567450Y67417D01*
X567158Y67208D01*
X567075Y66958D01*
X567117Y66708D01*
X567283Y66500D01*
X568117Y66083D01*
X568492Y65792D01*
X568742Y65375D01*
X568825Y65000D01*
X567075D01*
G01X565558Y65292D02*
X565267Y65083D01*
X564933Y65000D01*
X564600Y65083D01*
X564308Y65333D01*
X564100Y65708D01*
X564017Y66083D01*
Y66542D01*
X564100Y66917D01*
X564308Y67250D01*
X564558Y67417D01*
X564850Y67500D01*
X565183Y67417D01*
X565433Y67250D01*
X565600Y67000D01*
X565683Y66667D01*
X565600Y66375D01*
X565392Y66083D01*
X565142Y65917D01*
X564850Y65875D01*
X564517Y65958D01*
X564267Y66167D01*
X564017Y66542D01*
G01X570650Y83500D02*
Y81000D01*
G01X571608Y83500D02*
X569692D01*
G01X568383Y81000D02*
Y83500D01*
X567383D01*
X567050Y83375D01*
X566800Y83083D01*
X566717Y82750D01*
X566800Y82417D01*
X567008Y82167D01*
X567383Y82042D01*
X568383D01*
G01X565242Y83083D02*
X564992Y83333D01*
X564700Y83458D01*
X564367Y83500D01*
X563950Y83417D01*
X563658Y83208D01*
X563575Y82958D01*
X563617Y82708D01*
X563783Y82500D01*
X564617Y82083D01*
X564992Y81792D01*
X565242Y81375D01*
X565325Y81000D01*
X563575D01*
G01X562142Y82042D02*
X561850Y82333D01*
X561600Y82500D01*
X561267Y82583D01*
X560975Y82500D01*
X560767Y82333D01*
X560600Y82083D01*
X560558Y81792D01*
X560600Y81542D01*
X560767Y81292D01*
X561017Y81083D01*
X561308Y81000D01*
X561642Y81083D01*
X561933Y81333D01*
X562100Y81708D01*
X562142Y82125D01*
X562058Y82667D01*
X561933Y82958D01*
X561725Y83250D01*
X561433Y83458D01*
X561142Y83500D01*
X560850Y83417D01*
X560642Y83208D01*
G01X572150Y89500D02*
Y87000D01*
G01X573108Y89500D02*
X571192D01*
G01X569883Y87000D02*
Y89500D01*
X568883D01*
X568550Y89375D01*
X568300Y89083D01*
X568217Y88750D01*
X568300Y88417D01*
X568508Y88167D01*
X568883Y88042D01*
X569883D01*
G01X566742Y89083D02*
X566492Y89333D01*
X566200Y89458D01*
X565867Y89500D01*
X565450Y89417D01*
X565158Y89208D01*
X565075Y88958D01*
X565117Y88708D01*
X565283Y88500D01*
X566117Y88083D01*
X566492Y87792D01*
X566742Y87375D01*
X566825Y87000D01*
X565075D01*
G01X563767Y87500D02*
X563517Y87208D01*
X563183Y87042D01*
X562808Y87000D01*
X562475Y87042D01*
X562142Y87250D01*
X561933Y87500D01*
X561892Y87750D01*
X561975Y88042D01*
X562267Y88250D01*
X562558Y88333D01*
X562933D01*
G01X562558D02*
X562308Y88458D01*
X562100Y88667D01*
X562017Y88917D01*
X562100Y89167D01*
X562308Y89375D01*
X562683Y89500D01*
X563058Y89458D01*
X563433Y89292D01*
G01X574650Y79000D02*
Y76500D01*
G01X575608Y79000D02*
X573692D01*
G01X572383Y76500D02*
Y79000D01*
X571383D01*
X571050Y78875D01*
X570800Y78583D01*
X570717Y78250D01*
X570800Y77917D01*
X571008Y77667D01*
X571383Y77542D01*
X572383D01*
G01X569367Y77000D02*
X569117Y76708D01*
X568783Y76542D01*
X568408Y76500D01*
X568075Y76542D01*
X567742Y76750D01*
X567533Y77000D01*
X567492Y77250D01*
X567575Y77542D01*
X567867Y77750D01*
X568158Y77833D01*
X568533D01*
G01X568158D02*
X567908Y77958D01*
X567700Y78167D01*
X567617Y78417D01*
X567700Y78667D01*
X567908Y78875D01*
X568283Y79000D01*
X568658Y78958D01*
X569033Y78792D01*
G01X565350Y79000D02*
X565683Y78917D01*
X565933Y78708D01*
X566100Y78458D01*
X566225Y78125D01*
X566267Y77750D01*
X566225Y77375D01*
X566100Y77042D01*
X565933Y76792D01*
X565683Y76583D01*
X565350Y76500D01*
X565017Y76583D01*
X564767Y76792D01*
X564600Y77042D01*
X564475Y77375D01*
X564433Y77750D01*
X564475Y78125D01*
X564600Y78458D01*
X564767Y78708D01*
X565017Y78917D01*
X565350Y79000D01*
G01X568665Y104070D02*
Y108280D01*
G01X568895Y103185D02*
X568665Y104070D01*
G01X569345Y102600D02*
X568895Y103185D01*
G01X569910Y102400D02*
X569345Y102600D01*
G01X570475D02*
X569910Y102400D01*
G01X570925Y103185D02*
X570475Y102600D01*
G01X571150Y104070D02*
X570925Y103185D01*
G01X571150Y108280D02*
Y104070D01*
G01X562700Y102495D02*
X563145Y102400D01*
G01X562300Y102890D02*
X562700Y102495D01*
G01X561965Y103480D02*
X562300Y102890D01*
G01X561735Y104165D02*
X561965Y103480D01*
G01X561625Y104950D02*
X561735Y104165D01*
G01X561625Y105730D02*
Y104950D01*
G01X564670D02*
Y105730D01*
G01X564560Y104165D02*
X564670Y104950D01*
G01X564330Y103480D02*
X564560Y104165D01*
G01X563995Y102890D02*
X564330Y103480D01*
G01X563595Y102495D02*
X563995Y102890D01*
G01X563145Y102400D02*
X563595Y102495D01*
G01X560720Y102400D02*
Y106320D01*
G01X558810Y105140D02*
Y102400D01*
G01X558980Y105830D02*
X558810Y105140D01*
G01X560720Y105340D02*
X560500Y105830D01*
G01X569233Y98292D02*
X569483Y98417D01*
X569775Y98500D01*
X570108D01*
X570483Y98375D01*
X570775Y98167D01*
X570983Y97917D01*
X571150Y97500D01*
X571192Y97125D01*
X571108Y96750D01*
X570983Y96500D01*
X570733Y96250D01*
X570442Y96083D01*
X570150Y96000D01*
X569858D01*
X569567Y96083D01*
X569317Y96208D01*
X569108Y96375D01*
G01X567050Y96000D02*
Y98500D01*
X567550Y98000D01*
G01Y96000D02*
X566550D01*
G01X564658Y96292D02*
X564367Y96083D01*
X564033Y96000D01*
X563700Y96083D01*
X563408Y96333D01*
X563200Y96708D01*
X563117Y97083D01*
Y97542D01*
X563200Y97917D01*
X563408Y98250D01*
X563658Y98417D01*
X563950Y98500D01*
X564283Y98417D01*
X564533Y98250D01*
X564700Y98000D01*
X564783Y97667D01*
X564700Y97375D01*
X564492Y97083D01*
X564242Y96917D01*
X563950Y96875D01*
X563617Y96958D01*
X563367Y97167D01*
X563117Y97542D01*
G01X560933Y96000D02*
X560850Y96542D01*
X560725Y97000D01*
X560558Y97417D01*
X560350Y97875D01*
X560017Y98500D01*
X561683D01*
G01X561735Y106515D02*
X561625Y105730D01*
G01X561965Y107200D02*
X561735Y106515D01*
G01X562300Y107790D02*
X561965Y107200D01*
G01X562700Y108185D02*
X562300Y107790D01*
G01X563145Y108280D02*
X562700Y108185D01*
G01X563595D02*
X563145Y108280D01*
G01X563995Y107790D02*
X563595Y108185D01*
G01X564330Y107200D02*
X563995Y107790D01*
G01X564560Y106515D02*
X564330Y107200D01*
G01X564670Y105730D02*
X564560Y106515D01*
G01X559320Y106220D02*
X558980Y105830D01*
G01X559710Y106320D02*
X559320Y106220D01*
G01X560165D02*
X559710Y106320D01*
G01X560500Y105830D02*
X560165Y106220D01*
G01X572483Y164500D02*
Y167000D01*
X571442D01*
X571108Y166875D01*
X570900Y166708D01*
X570817Y166375D01*
X570900Y166042D01*
X571150Y165833D01*
X571442Y165708D01*
X572483D01*
G01X571442D02*
X570817Y164500D01*
G01X568050D02*
Y167000D01*
X569592Y165208D01*
X567508D01*
G01X566158Y164792D02*
X565867Y164583D01*
X565533Y164500D01*
X565200Y164583D01*
X564908Y164833D01*
X564700Y165208D01*
X564617Y165583D01*
Y166042D01*
X564700Y166417D01*
X564908Y166750D01*
X565158Y166917D01*
X565450Y167000D01*
X565783Y166917D01*
X566033Y166750D01*
X566200Y166500D01*
X566283Y166167D01*
X566200Y165875D01*
X565992Y165583D01*
X565742Y165417D01*
X565450Y165375D01*
X565117Y165458D01*
X564867Y165667D01*
X564617Y166042D01*
G01X563267Y165000D02*
X563017Y164708D01*
X562683Y164542D01*
X562308Y164500D01*
X561975Y164542D01*
X561642Y164750D01*
X561433Y165000D01*
X561392Y165250D01*
X561475Y165542D01*
X561767Y165750D01*
X562058Y165833D01*
X562433D01*
G01X562058D02*
X561808Y165958D01*
X561600Y166167D01*
X561517Y166417D01*
X561600Y166667D01*
X561808Y166875D01*
X562183Y167000D01*
X562558Y166958D01*
X562933Y166792D01*
G01X572483Y168500D02*
Y171000D01*
X571442D01*
X571108Y170875D01*
X570900Y170708D01*
X570817Y170375D01*
X570900Y170042D01*
X571150Y169833D01*
X571442Y169708D01*
X572483D01*
G01X571442D02*
X570817Y168500D01*
G01X569467Y169000D02*
X569217Y168708D01*
X568883Y168542D01*
X568508Y168500D01*
X568175Y168542D01*
X567842Y168750D01*
X567633Y169000D01*
X567592Y169250D01*
X567675Y169542D01*
X567967Y169750D01*
X568258Y169833D01*
X568633D01*
G01X568258D02*
X568008Y169958D01*
X567800Y170167D01*
X567717Y170417D01*
X567800Y170667D01*
X568008Y170875D01*
X568383Y171000D01*
X568758Y170958D01*
X569133Y170792D01*
G01X566367Y169000D02*
X566117Y168708D01*
X565783Y168542D01*
X565408Y168500D01*
X565075Y168542D01*
X564742Y168750D01*
X564533Y169000D01*
X564492Y169250D01*
X564575Y169542D01*
X564867Y169750D01*
X565158Y169833D01*
X565533D01*
G01X565158D02*
X564908Y169958D01*
X564700Y170167D01*
X564617Y170417D01*
X564700Y170667D01*
X564908Y170875D01*
X565283Y171000D01*
X565658Y170958D01*
X566033Y170792D01*
G01X563142Y169542D02*
X562850Y169833D01*
X562600Y170000D01*
X562267Y170083D01*
X561975Y170000D01*
X561767Y169833D01*
X561600Y169583D01*
X561558Y169292D01*
X561600Y169042D01*
X561767Y168792D01*
X562017Y168583D01*
X562308Y168500D01*
X562642Y168583D01*
X562933Y168833D01*
X563100Y169208D01*
X563142Y169625D01*
X563058Y170167D01*
X562933Y170458D01*
X562725Y170750D01*
X562433Y170958D01*
X562142Y171000D01*
X561850Y170917D01*
X561642Y170708D01*
G01X577483Y181500D02*
Y184000D01*
X576442D01*
X576108Y183875D01*
X575900Y183708D01*
X575817Y183375D01*
X575900Y183042D01*
X576150Y182833D01*
X576442Y182708D01*
X577483D01*
G01X576442D02*
X575817Y181500D01*
G01X573050D02*
Y184000D01*
X574592Y182208D01*
X572508D01*
G01X571158Y181792D02*
X570867Y181583D01*
X570533Y181500D01*
X570200Y181583D01*
X569908Y181833D01*
X569700Y182208D01*
X569617Y182583D01*
Y183042D01*
X569700Y183417D01*
X569908Y183750D01*
X570158Y183917D01*
X570450Y184000D01*
X570783Y183917D01*
X571033Y183750D01*
X571200Y183500D01*
X571283Y183167D01*
X571200Y182875D01*
X570992Y182583D01*
X570742Y182417D01*
X570450Y182375D01*
X570117Y182458D01*
X569867Y182667D01*
X569617Y183042D01*
G01X568142Y183583D02*
X567892Y183833D01*
X567600Y183958D01*
X567267Y184000D01*
X566850Y183917D01*
X566558Y183708D01*
X566475Y183458D01*
X566517Y183208D01*
X566683Y183000D01*
X567517Y182583D01*
X567892Y182292D01*
X568142Y181875D01*
X568225Y181500D01*
X566475D01*
G01X572292Y229767D02*
X572417Y229517D01*
X572500Y229225D01*
Y228892D01*
X572375Y228517D01*
X572167Y228225D01*
X571917Y228017D01*
X571500Y227850D01*
X571125Y227808D01*
X570750Y227892D01*
X570500Y228017D01*
X570250Y228267D01*
X570083Y228558D01*
X570000Y228850D01*
Y229142D01*
X570083Y229433D01*
X570208Y229683D01*
X570375Y229892D01*
G01X570500Y231033D02*
X570208Y231283D01*
X570042Y231617D01*
X570000Y231992D01*
X570042Y232325D01*
X570250Y232658D01*
X570500Y232867D01*
X570750Y232908D01*
X571042Y232825D01*
X571250Y232533D01*
X571333Y232242D01*
Y231867D01*
G01Y232242D02*
X571458Y232492D01*
X571667Y232700D01*
X571917Y232783D01*
X572167Y232700D01*
X572375Y232492D01*
X572500Y232117D01*
X572458Y231742D01*
X572292Y231367D01*
G01X570375Y234133D02*
X570167Y234383D01*
X570042Y234675D01*
X570000Y235050D01*
X570083Y235425D01*
X570250Y235717D01*
X570542Y235925D01*
X570875Y235967D01*
X571208Y235883D01*
X571417Y235675D01*
X571583Y235383D01*
X571625Y235092D01*
X571583Y234800D01*
X571417Y234425D01*
X572500Y234550D01*
Y235675D01*
G01X570292Y237442D02*
X570083Y237733D01*
X570000Y238067D01*
X570083Y238400D01*
X570333Y238692D01*
X570708Y238900D01*
X571083Y238983D01*
X571542D01*
X571917Y238900D01*
X572250Y238692D01*
X572417Y238442D01*
X572500Y238150D01*
X572417Y237817D01*
X572250Y237567D01*
X572000Y237400D01*
X571667Y237317D01*
X571375Y237400D01*
X571083Y237608D01*
X570917Y237858D01*
X570875Y238150D01*
X570958Y238483D01*
X571167Y238733D01*
X571542Y238983D01*
G01X700967Y75500D02*
Y82500D01*
X697500Y76667D01*
X694033Y82500D01*
Y75500D01*
G01X692233D02*
X688900Y82500D01*
X685567Y75500D01*
G01X686767Y77950D02*
X691033D01*
G01X683233Y75500D02*
Y82500D01*
X680567D01*
X679500Y82150D01*
X678700Y81683D01*
X678033Y80983D01*
X677500Y80167D01*
X677367Y79000D01*
X677500Y77833D01*
X678033Y77017D01*
X678700Y76316D01*
X679500Y75850D01*
X680567Y75500D01*
X683233D01*
G01X669033D02*
X674367D01*
Y82500D01*
X669033D01*
G01X671167Y79117D02*
X674367D01*
G01X656100Y82500D02*
X652900D01*
G01X654500D02*
Y75500D01*
G01X656100D02*
X652900D01*
G01X648967D02*
Y82500D01*
X642833Y75500D01*
Y82500D01*
G01X628700D02*
Y75500D01*
G01X631767Y82500D02*
X625633D01*
G01X623433Y75500D02*
X620100Y82500D01*
X616767Y75500D01*
G01X617967Y77950D02*
X622233D01*
G01X613100Y82500D02*
X609900D01*
G01X611500D02*
Y75500D01*
G01X613100D02*
X609900D01*
G01X606900Y82500D02*
X605033Y75500D01*
X602900Y82500D01*
X600767Y75500D01*
X598900Y82500D01*
G01X597633Y75500D02*
X594300Y82500D01*
X590967Y75500D01*
G01X592167Y77950D02*
X596433D01*
G01X588767Y75500D02*
Y82500D01*
X582633Y75500D01*
Y82500D01*
G01X581000Y90517D02*
X583500D01*
Y91558D01*
X583375Y91892D01*
X583208Y92100D01*
X582875Y92183D01*
X582542Y92100D01*
X582333Y91850D01*
X582208Y91558D01*
Y90517D01*
G01Y91558D02*
X581000Y92183D01*
G01Y94450D02*
X583500D01*
X583000Y93950D01*
G01X581000D02*
Y94950D01*
G01X583500Y97550D02*
X583417Y97217D01*
X583208Y96967D01*
X582958Y96800D01*
X582625Y96675D01*
X582250Y96633D01*
X581875Y96675D01*
X581542Y96800D01*
X581292Y96967D01*
X581083Y97217D01*
X581000Y97550D01*
X581083Y97883D01*
X581292Y98133D01*
X581542Y98300D01*
X581875Y98425D01*
X582250Y98467D01*
X582625Y98425D01*
X582958Y98300D01*
X583208Y98133D01*
X583417Y97883D01*
X583500Y97550D01*
G01X581000Y101150D02*
X583500D01*
X581708Y99608D01*
Y101692D01*
G01X574415Y102400D02*
Y108280D01*
G01X572165Y102400D02*
X574415D01*
G01X573065Y105435D02*
X574415D01*
G01Y108280D02*
X572165D01*
G01X587792Y144267D02*
X587917Y144017D01*
X588000Y143725D01*
Y143392D01*
X587875Y143017D01*
X587667Y142725D01*
X587417Y142517D01*
X587000Y142350D01*
X586625Y142308D01*
X586250Y142392D01*
X586000Y142517D01*
X585750Y142767D01*
X585583Y143058D01*
X585500Y143350D01*
Y143642D01*
X585583Y143933D01*
X585708Y144183D01*
X585875Y144392D01*
G01X587583Y145658D02*
X587833Y145908D01*
X587958Y146200D01*
X588000Y146533D01*
X587917Y146950D01*
X587708Y147242D01*
X587458Y147325D01*
X587208Y147283D01*
X587000Y147117D01*
X586583Y146283D01*
X586292Y145908D01*
X585875Y145658D01*
X585500Y145575D01*
Y147325D01*
G01X586000Y148633D02*
X585708Y148883D01*
X585542Y149217D01*
X585500Y149592D01*
X585542Y149925D01*
X585750Y150258D01*
X586000Y150467D01*
X586250Y150508D01*
X586542Y150425D01*
X586750Y150133D01*
X586833Y149842D01*
Y149467D01*
G01Y149842D02*
X586958Y150092D01*
X587167Y150300D01*
X587417Y150383D01*
X587667Y150300D01*
X587875Y150092D01*
X588000Y149717D01*
X587958Y149342D01*
X587792Y148967D01*
G01X586000Y151733D02*
X585708Y151983D01*
X585542Y152317D01*
X585500Y152692D01*
X585542Y153025D01*
X585750Y153358D01*
X586000Y153567D01*
X586250Y153608D01*
X586542Y153525D01*
X586750Y153233D01*
X586833Y152942D01*
Y152567D01*
G01Y152942D02*
X586958Y153192D01*
X587167Y153400D01*
X587417Y153483D01*
X587667Y153400D01*
X587875Y153192D01*
X588000Y152817D01*
X587958Y152442D01*
X587792Y152067D01*
G01X575500Y162067D02*
X578000D01*
Y163108D01*
X577875Y163442D01*
X577708Y163650D01*
X577375Y163733D01*
X577042Y163650D01*
X576833Y163400D01*
X576708Y163108D01*
Y162067D01*
G01Y163108D02*
X575500Y163733D01*
G01Y165917D02*
X576042Y166000D01*
X576500Y166125D01*
X576917Y166292D01*
X577375Y166500D01*
X578000Y166833D01*
Y165167D01*
G01X575500Y169017D02*
X576042Y169100D01*
X576500Y169225D01*
X576917Y169392D01*
X577375Y169600D01*
X578000Y169933D01*
Y168267D01*
G01X580000Y160517D02*
X582500D01*
Y161558D01*
X582375Y161892D01*
X582208Y162100D01*
X581875Y162183D01*
X581542Y162100D01*
X581333Y161850D01*
X581208Y161558D01*
Y160517D01*
G01Y161558D02*
X580000Y162183D01*
G01Y164450D02*
X582500D01*
X582000Y163950D01*
G01X580000D02*
Y164950D01*
G01X580500Y166633D02*
X580208Y166883D01*
X580042Y167217D01*
X580000Y167592D01*
X580042Y167925D01*
X580250Y168258D01*
X580500Y168467D01*
X580750Y168508D01*
X581042Y168425D01*
X581250Y168133D01*
X581333Y167842D01*
Y167467D01*
G01Y167842D02*
X581458Y168092D01*
X581667Y168300D01*
X581917Y168383D01*
X582167Y168300D01*
X582375Y168092D01*
X582500Y167717D01*
X582458Y167342D01*
X582292Y166967D01*
G01X582500Y170650D02*
X582417Y170317D01*
X582208Y170067D01*
X581958Y169900D01*
X581625Y169775D01*
X581250Y169733D01*
X580875Y169775D01*
X580542Y169900D01*
X580292Y170067D01*
X580083Y170317D01*
X580000Y170650D01*
X580083Y170983D01*
X580292Y171233D01*
X580542Y171400D01*
X580875Y171525D01*
X581250Y171567D01*
X581625Y171525D01*
X581958Y171400D01*
X582208Y171233D01*
X582417Y170983D01*
X582500Y170650D01*
G01X590233Y184292D02*
X590483Y184417D01*
X590775Y184500D01*
X591108D01*
X591483Y184375D01*
X591775Y184167D01*
X591983Y183917D01*
X592150Y183500D01*
X592192Y183125D01*
X592108Y182750D01*
X591983Y182500D01*
X591733Y182250D01*
X591442Y182083D01*
X591150Y182000D01*
X590858D01*
X590567Y182083D01*
X590317Y182208D01*
X590108Y182375D01*
G01X588842Y184083D02*
X588592Y184333D01*
X588300Y184458D01*
X587967Y184500D01*
X587550Y184417D01*
X587258Y184208D01*
X587175Y183958D01*
X587217Y183708D01*
X587383Y183500D01*
X588217Y183083D01*
X588592Y182792D01*
X588842Y182375D01*
X588925Y182000D01*
X587175D01*
G01X585742Y184083D02*
X585492Y184333D01*
X585200Y184458D01*
X584867Y184500D01*
X584450Y184417D01*
X584158Y184208D01*
X584075Y183958D01*
X584117Y183708D01*
X584283Y183500D01*
X585117Y183083D01*
X585492Y182792D01*
X585742Y182375D01*
X585825Y182000D01*
X584075D01*
G01X582767Y182500D02*
X582517Y182208D01*
X582183Y182042D01*
X581808Y182000D01*
X581475Y182042D01*
X581142Y182250D01*
X580933Y182500D01*
X580892Y182750D01*
X580975Y183042D01*
X581267Y183250D01*
X581558Y183333D01*
X581933D01*
G01X581558D02*
X581308Y183458D01*
X581100Y183667D01*
X581017Y183917D01*
X581100Y184167D01*
X581308Y184375D01*
X581683Y184500D01*
X582058Y184458D01*
X582433Y184292D01*
G01X580933Y189500D02*
Y192000D01*
X579892D01*
X579558Y191875D01*
X579350Y191708D01*
X579267Y191375D01*
X579350Y191042D01*
X579600Y190833D01*
X579892Y190708D01*
X580933D01*
G01X579892D02*
X579267Y189500D01*
G01X577000D02*
X576708Y189542D01*
X576375Y189667D01*
X576167Y189875D01*
X576083Y190167D01*
X576167Y190458D01*
X576417Y190708D01*
X576792Y190833D01*
X577208D01*
X577458Y190917D01*
X577667Y191125D01*
X577750Y191417D01*
X577625Y191708D01*
X577333Y191917D01*
X577000Y192000D01*
X576667Y191917D01*
X576375Y191708D01*
X576250Y191417D01*
X576333Y191125D01*
X576542Y190917D01*
X576792Y190833D01*
X577208D01*
X577583Y190708D01*
X577833Y190458D01*
X577917Y190167D01*
X577833Y189875D01*
X577625Y189667D01*
X577292Y189542D01*
X577000Y189500D01*
G01X573900Y192000D02*
X574233Y191917D01*
X574483Y191708D01*
X574650Y191458D01*
X574775Y191125D01*
X574817Y190750D01*
X574775Y190375D01*
X574650Y190042D01*
X574483Y189792D01*
X574233Y189583D01*
X573900Y189500D01*
X573567Y189583D01*
X573317Y189792D01*
X573150Y190042D01*
X573025Y190375D01*
X572983Y190750D01*
X573025Y191125D01*
X573150Y191458D01*
X573317Y191708D01*
X573567Y191917D01*
X573900Y192000D01*
G01X576292Y229767D02*
X576417Y229517D01*
X576500Y229225D01*
Y228892D01*
X576375Y228517D01*
X576167Y228225D01*
X575917Y228017D01*
X575500Y227850D01*
X575125Y227808D01*
X574750Y227892D01*
X574500Y228017D01*
X574250Y228267D01*
X574083Y228558D01*
X574000Y228850D01*
Y229142D01*
X574083Y229433D01*
X574208Y229683D01*
X574375Y229892D01*
G01X574500Y231033D02*
X574208Y231283D01*
X574042Y231617D01*
X574000Y231992D01*
X574042Y232325D01*
X574250Y232658D01*
X574500Y232867D01*
X574750Y232908D01*
X575042Y232825D01*
X575250Y232533D01*
X575333Y232242D01*
Y231867D01*
G01Y232242D02*
X575458Y232492D01*
X575667Y232700D01*
X575917Y232783D01*
X576167Y232700D01*
X576375Y232492D01*
X576500Y232117D01*
X576458Y231742D01*
X576292Y231367D01*
G01X575042Y234258D02*
X575333Y234550D01*
X575500Y234800D01*
X575583Y235133D01*
X575500Y235425D01*
X575333Y235633D01*
X575083Y235800D01*
X574792Y235842D01*
X574542Y235800D01*
X574292Y235633D01*
X574083Y235383D01*
X574000Y235092D01*
X574083Y234758D01*
X574333Y234467D01*
X574708Y234300D01*
X575125Y234258D01*
X575667Y234342D01*
X575958Y234467D01*
X576250Y234675D01*
X576458Y234967D01*
X576500Y235258D01*
X576417Y235550D01*
X576208Y235758D01*
G01X576500Y238150D02*
X576417Y237817D01*
X576208Y237567D01*
X575958Y237400D01*
X575625Y237275D01*
X575250Y237233D01*
X574875Y237275D01*
X574542Y237400D01*
X574292Y237567D01*
X574083Y237817D01*
X574000Y238150D01*
X574083Y238483D01*
X574292Y238733D01*
X574542Y238900D01*
X574875Y239025D01*
X575250Y239067D01*
X575625Y239025D01*
X575958Y238900D01*
X576208Y238733D01*
X576417Y238483D01*
X576500Y238150D01*
G01X602292Y48774D02*
X602417Y48524D01*
X602500Y48232D01*
Y47899D01*
X602375Y47524D01*
X602167Y47232D01*
X601917Y47024D01*
X601500Y46857D01*
X601125Y46815D01*
X600750Y46899D01*
X600500Y47024D01*
X600250Y47274D01*
X600083Y47565D01*
X600000Y47857D01*
Y48149D01*
X600083Y48440D01*
X600208Y48690D01*
X600375Y48899D01*
G01X600500Y50040D02*
X600208Y50290D01*
X600042Y50624D01*
X600000Y50999D01*
X600042Y51332D01*
X600250Y51665D01*
X600500Y51874D01*
X600750Y51915D01*
X601042Y51832D01*
X601250Y51540D01*
X601333Y51249D01*
Y50874D01*
G01Y51249D02*
X601458Y51499D01*
X601667Y51707D01*
X601917Y51790D01*
X602167Y51707D01*
X602375Y51499D01*
X602500Y51124D01*
X602458Y50749D01*
X602292Y50374D01*
G01X601042Y53265D02*
X601333Y53557D01*
X601500Y53807D01*
X601583Y54140D01*
X601500Y54432D01*
X601333Y54640D01*
X601083Y54807D01*
X600792Y54849D01*
X600542Y54807D01*
X600292Y54640D01*
X600083Y54390D01*
X600000Y54099D01*
X600083Y53765D01*
X600333Y53474D01*
X600708Y53307D01*
X601125Y53265D01*
X601667Y53349D01*
X601958Y53474D01*
X602250Y53682D01*
X602458Y53974D01*
X602500Y54265D01*
X602417Y54557D01*
X602208Y54765D01*
G01X600000Y57657D02*
X602500D01*
X600708Y56115D01*
Y58199D01*
G01X597292Y48774D02*
X597417Y48524D01*
X597500Y48232D01*
Y47899D01*
X597375Y47524D01*
X597167Y47232D01*
X596917Y47024D01*
X596500Y46857D01*
X596125Y46815D01*
X595750Y46899D01*
X595500Y47024D01*
X595250Y47274D01*
X595083Y47565D01*
X595000Y47857D01*
Y48149D01*
X595083Y48440D01*
X595208Y48690D01*
X595375Y48899D01*
G01X595500Y50040D02*
X595208Y50290D01*
X595042Y50624D01*
X595000Y50999D01*
X595042Y51332D01*
X595250Y51665D01*
X595500Y51874D01*
X595750Y51915D01*
X596042Y51832D01*
X596250Y51540D01*
X596333Y51249D01*
Y50874D01*
G01Y51249D02*
X596458Y51499D01*
X596667Y51707D01*
X596917Y51790D01*
X597167Y51707D01*
X597375Y51499D01*
X597500Y51124D01*
X597458Y50749D01*
X597292Y50374D01*
G01X596042Y53265D02*
X596333Y53557D01*
X596500Y53807D01*
X596583Y54140D01*
X596500Y54432D01*
X596333Y54640D01*
X596083Y54807D01*
X595792Y54849D01*
X595542Y54807D01*
X595292Y54640D01*
X595083Y54390D01*
X595000Y54099D01*
X595083Y53765D01*
X595333Y53474D01*
X595708Y53307D01*
X596125Y53265D01*
X596667Y53349D01*
X596958Y53474D01*
X597250Y53682D01*
X597458Y53974D01*
X597500Y54265D01*
X597417Y54557D01*
X597208Y54765D01*
G01X595500Y56240D02*
X595208Y56490D01*
X595042Y56824D01*
X595000Y57199D01*
X595042Y57532D01*
X595250Y57865D01*
X595500Y58074D01*
X595750Y58115D01*
X596042Y58032D01*
X596250Y57740D01*
X596333Y57449D01*
Y57074D01*
G01Y57449D02*
X596458Y57699D01*
X596667Y57907D01*
X596917Y57990D01*
X597167Y57907D01*
X597375Y57699D01*
X597500Y57324D01*
X597458Y56949D01*
X597292Y56574D01*
G01X694400Y88000D02*
Y95000D01*
X699333Y89983D01*
X692667D01*
G01X687400Y88000D02*
X686467Y88117D01*
X685400Y88467D01*
X684733Y89050D01*
X684467Y89867D01*
X684733Y90683D01*
X685533Y91383D01*
X686733Y91733D01*
X688067D01*
X688867Y91967D01*
X689533Y92550D01*
X689800Y93367D01*
X689400Y94183D01*
X688467Y94767D01*
X687400Y95000D01*
X686333Y94767D01*
X685400Y94183D01*
X685000Y93367D01*
X685267Y92550D01*
X685933Y91967D01*
X686733Y91733D01*
X688067D01*
X689267Y91383D01*
X690067Y90683D01*
X690333Y89867D01*
X690067Y89050D01*
X689400Y88467D01*
X688333Y88117D01*
X687400Y88000D01*
G01X678800Y87767D02*
X679067Y87883D01*
Y88117D01*
X678800Y88233D01*
X678533Y88117D01*
Y87883D01*
X678800Y87767D01*
G01X669133Y91733D02*
X668600Y92083D01*
X668200Y92667D01*
X667933Y93483D01*
X668200Y94183D01*
X668733Y94650D01*
X669667Y95000D01*
X673267D01*
Y88000D01*
X668867D01*
X667933Y88467D01*
X667400Y89167D01*
X667133Y89983D01*
X667400Y90800D01*
X668200Y91500D01*
X669133Y91733D01*
X673267D01*
G01X661600Y95000D02*
X662667Y94767D01*
X663467Y94183D01*
X664000Y93483D01*
X664400Y92550D01*
X664533Y91500D01*
X664400Y90450D01*
X664000Y89517D01*
X663467Y88816D01*
X662667Y88233D01*
X661600Y88000D01*
X660533Y88233D01*
X659733Y88816D01*
X659200Y89517D01*
X658800Y90450D01*
X658667Y91500D01*
X658800Y92550D01*
X659200Y93483D01*
X659733Y94183D01*
X660533Y94767D01*
X661600Y95000D01*
G01X653267Y88000D02*
X653000Y89517D01*
X652600Y90800D01*
X652067Y91967D01*
X651400Y93250D01*
X650333Y95000D01*
X655667D01*
G01X646933Y93833D02*
X646133Y94533D01*
X645200Y94883D01*
X644133Y95000D01*
X642800Y94767D01*
X641867Y94183D01*
X641600Y93483D01*
X641733Y92783D01*
X642267Y92200D01*
X644933Y91033D01*
X646133Y90217D01*
X646933Y89050D01*
X647200Y88000D01*
X641600D01*
G01X638333Y90916D02*
X637400Y91733D01*
X636600Y92200D01*
X635533Y92433D01*
X634600Y92200D01*
X633933Y91733D01*
X633400Y91033D01*
X633267Y90217D01*
X633400Y89517D01*
X633933Y88816D01*
X634733Y88233D01*
X635667Y88000D01*
X636733Y88233D01*
X637667Y88933D01*
X638200Y89983D01*
X638333Y91150D01*
X638067Y92667D01*
X637667Y93483D01*
X637000Y94300D01*
X636067Y94883D01*
X635133Y95000D01*
X634200Y94767D01*
X633533Y94183D01*
G01X627200Y87767D02*
X627467Y87883D01*
Y88117D01*
X627200Y88233D01*
X626933Y88117D01*
Y87883D01*
X627200Y87767D01*
G01X618600Y95000D02*
X619667Y94767D01*
X620467Y94183D01*
X621000Y93483D01*
X621400Y92550D01*
X621533Y91500D01*
X621400Y90450D01*
X621000Y89517D01*
X620467Y88816D01*
X619667Y88233D01*
X618600Y88000D01*
X617533Y88233D01*
X616733Y88816D01*
X616200Y89517D01*
X615800Y90450D01*
X615667Y91500D01*
X615800Y92550D01*
X616200Y93483D01*
X616733Y94183D01*
X617533Y94767D01*
X618600Y95000D01*
G01X610000Y88000D02*
Y95000D01*
X611600Y93600D01*
G01Y88000D02*
X608400D01*
G01X600333Y91733D02*
X599800Y92083D01*
X599400Y92667D01*
X599133Y93483D01*
X599400Y94183D01*
X599933Y94650D01*
X600867Y95000D01*
X604467D01*
Y88000D01*
X600067D01*
X599133Y88467D01*
X598600Y89167D01*
X598333Y89983D01*
X598600Y90800D01*
X599400Y91500D01*
X600333Y91733D01*
X604467D01*
G01X655500Y106500D02*
Y113500D01*
X657100Y112100D01*
G01Y106500D02*
X653900D01*
G01X649833Y107900D02*
X649033Y107083D01*
X647967Y106617D01*
X646767Y106500D01*
X645700Y106617D01*
X644633Y107200D01*
X643967Y107900D01*
X643833Y108600D01*
X644100Y109416D01*
X645033Y110000D01*
X645967Y110233D01*
X647167D01*
G01X645967D02*
X645167Y110583D01*
X644500Y111167D01*
X644233Y111867D01*
X644500Y112567D01*
X645167Y113150D01*
X646367Y113500D01*
X647567Y113383D01*
X648767Y112917D01*
G01X638300Y106500D02*
Y113500D01*
X639900Y112100D01*
G01Y106500D02*
X636700D01*
G01X632633Y107900D02*
X631833Y107083D01*
X630767Y106617D01*
X629567Y106500D01*
X628500Y106617D01*
X627433Y107200D01*
X626767Y107900D01*
X626633Y108600D01*
X626900Y109416D01*
X627833Y110000D01*
X628767Y110233D01*
X629967D01*
G01X628767D02*
X627967Y110583D01*
X627300Y111167D01*
X627033Y111867D01*
X627300Y112567D01*
X627967Y113150D01*
X629167Y113500D01*
X630367Y113383D01*
X631567Y112917D01*
G01X621100Y113500D02*
X622167Y113267D01*
X622967Y112683D01*
X623500Y111983D01*
X623900Y111050D01*
X624033Y110000D01*
X623900Y108950D01*
X623500Y108017D01*
X622967Y107316D01*
X622167Y106733D01*
X621100Y106500D01*
X620033Y106733D01*
X619233Y107316D01*
X618700Y108017D01*
X618300Y108950D01*
X618167Y110000D01*
X618300Y111050D01*
X618700Y111983D01*
X619233Y112683D01*
X620033Y113267D01*
X621100Y113500D01*
G01X614233Y108833D02*
X610767D01*
G01X603900Y106500D02*
Y113500D01*
X605500Y112100D01*
G01Y106500D02*
X602300D01*
G01X594233Y110233D02*
X593700Y110583D01*
X593300Y111167D01*
X593033Y111983D01*
X593300Y112683D01*
X593833Y113150D01*
X594767Y113500D01*
X598367D01*
Y106500D01*
X593967D01*
X593033Y106967D01*
X592500Y107667D01*
X592233Y108483D01*
X592500Y109300D01*
X593300Y110000D01*
X594233Y110233D01*
X598367D01*
G01X690800Y127000D02*
Y134000D01*
G01X685200D02*
Y127000D01*
G01Y130500D02*
X690800D01*
G01X679400Y127000D02*
X680200Y127117D01*
X681000Y127583D01*
X681533Y128400D01*
X681800Y129333D01*
X681533Y130267D01*
X681000Y131083D01*
X680200Y131550D01*
X679400Y131667D01*
X678600Y131550D01*
X677800Y131083D01*
X677267Y130267D01*
X677133Y129333D01*
X677267Y128400D01*
X677800Y127583D01*
X678600Y127117D01*
X679400Y127000D01*
G01X673067D02*
Y131667D01*
G01Y130500D02*
X672533Y131083D01*
X671733Y131550D01*
X670667Y131667D01*
X669733Y131550D01*
X668933Y131083D01*
X668533Y130267D01*
Y127000D01*
G01X664200Y130150D02*
X659933D01*
X660333Y130967D01*
X661000Y131433D01*
X661933Y131667D01*
X662867Y131550D01*
X663667Y131200D01*
X664200Y130383D01*
X664467Y129683D01*
Y128983D01*
X664200Y128283D01*
X663533Y127583D01*
X662733Y127117D01*
X661800Y127000D01*
X660867Y127233D01*
X659933Y127933D01*
G01X656400Y124900D02*
X655600Y124667D01*
X654533Y124900D01*
X653867Y125367D01*
X653333Y125950D01*
X652533Y127816D01*
X650800Y131667D01*
G01X655067D02*
X652533Y127816D01*
G01X635333Y130733D02*
X634800Y131083D01*
X634400Y131667D01*
X634133Y132483D01*
X634400Y133183D01*
X634933Y133650D01*
X635867Y134000D01*
X639467D01*
Y127000D01*
X635067D01*
X634133Y127467D01*
X633600Y128167D01*
X633333Y128983D01*
X633600Y129800D01*
X634400Y130500D01*
X635333Y130733D01*
X639467D01*
G01X625400Y127000D02*
Y131667D01*
G01Y130850D02*
X625933Y131317D01*
X626733Y131550D01*
X627667Y131667D01*
X628600Y131433D01*
X629400Y130967D01*
X629933Y130267D01*
X630200Y129333D01*
X629933Y128400D01*
X629400Y127700D01*
X628600Y127233D01*
X627667Y127000D01*
X626733Y127117D01*
X625933Y127467D01*
X625400Y127933D01*
G01X616800Y134000D02*
Y127000D01*
G01Y128050D02*
X617333Y127467D01*
X618133Y127117D01*
X619067Y127000D01*
X620133Y127233D01*
X620933Y127816D01*
X621467Y128517D01*
X621600Y129333D01*
X621467Y130150D01*
X620933Y130850D01*
X620133Y131433D01*
X619067Y131667D01*
X618133Y131550D01*
X617467Y131317D01*
X616800Y130850D01*
G01X612467Y125250D02*
X611533Y124783D01*
X610467Y124667D01*
X609533Y124783D01*
X608733Y125367D01*
X608200Y126183D01*
Y131667D01*
G01Y130733D02*
X608733Y131200D01*
X609533Y131550D01*
X610467Y131667D01*
X611533Y131433D01*
X612200Y130967D01*
X612733Y130150D01*
X613000Y129333D01*
X612867Y128633D01*
X612333Y127816D01*
X611533Y127233D01*
X610467Y127000D01*
X609667Y127117D01*
X608733Y127583D01*
X608200Y128050D01*
G01X604000Y130150D02*
X599733D01*
X600133Y130967D01*
X600800Y131433D01*
X601733Y131667D01*
X602667Y131550D01*
X603467Y131200D01*
X604000Y130383D01*
X604267Y129683D01*
Y128983D01*
X604000Y128283D01*
X603333Y127583D01*
X602533Y127117D01*
X601600Y127000D01*
X600667Y127233D01*
X599733Y127933D01*
G01X595267Y127000D02*
Y131667D01*
G01Y130733D02*
X594600Y131200D01*
X593933Y131550D01*
X593000Y131667D01*
X592333Y131550D01*
X591533Y131200D01*
G01X685500Y153500D02*
Y172500D01*
X707500D01*
Y210500D01*
X725500D01*
Y232500D01*
X661500D01*
Y204000D01*
X596500D01*
Y150000D01*
X685500D01*
Y153500D01*
G01X613533Y151500D02*
Y154000D01*
X612533D01*
X612200Y153875D01*
X611950Y153583D01*
X611867Y153250D01*
X611950Y152917D01*
X612158Y152667D01*
X612533Y152542D01*
X613533D01*
G01X610433Y151500D02*
Y154000D01*
X609392D01*
X609058Y153875D01*
X608850Y153708D01*
X608767Y153375D01*
X608850Y153042D01*
X609100Y152833D01*
X609392Y152708D01*
X610433D01*
G01X609392D02*
X608767Y151500D01*
G01X606500D02*
Y154000D01*
X607000Y153500D01*
G01Y151500D02*
X606000D01*
G01X603400D02*
X603108Y151542D01*
X602775Y151667D01*
X602567Y151875D01*
X602483Y152167D01*
X602567Y152458D01*
X602817Y152708D01*
X603192Y152833D01*
X603608D01*
X603858Y152917D01*
X604067Y153125D01*
X604150Y153417D01*
X604025Y153708D01*
X603733Y153917D01*
X603400Y154000D01*
X603067Y153917D01*
X602775Y153708D01*
X602650Y153417D01*
X602733Y153125D01*
X602942Y152917D01*
X603192Y152833D01*
X603608D01*
X603983Y152708D01*
X604233Y152458D01*
X604317Y152167D01*
X604233Y151875D01*
X604025Y151667D01*
X603692Y151542D01*
X603400Y151500D01*
G01X600300D02*
Y154000D01*
X600800Y153500D01*
G01Y151500D02*
X599800D01*
G01X592292Y144267D02*
X592417Y144017D01*
X592500Y143725D01*
Y143392D01*
X592375Y143017D01*
X592167Y142725D01*
X591917Y142517D01*
X591500Y142350D01*
X591125Y142308D01*
X590750Y142392D01*
X590500Y142517D01*
X590250Y142767D01*
X590083Y143058D01*
X590000Y143350D01*
Y143642D01*
X590083Y143933D01*
X590208Y144183D01*
X590375Y144392D01*
G01X592083Y145658D02*
X592333Y145908D01*
X592458Y146200D01*
X592500Y146533D01*
X592417Y146950D01*
X592208Y147242D01*
X591958Y147325D01*
X591708Y147283D01*
X591500Y147117D01*
X591083Y146283D01*
X590792Y145908D01*
X590375Y145658D01*
X590000Y145575D01*
Y147325D01*
G01X590500Y148633D02*
X590208Y148883D01*
X590042Y149217D01*
X590000Y149592D01*
X590042Y149925D01*
X590250Y150258D01*
X590500Y150467D01*
X590750Y150508D01*
X591042Y150425D01*
X591250Y150133D01*
X591333Y149842D01*
Y149467D01*
G01Y149842D02*
X591458Y150092D01*
X591667Y150300D01*
X591917Y150383D01*
X592167Y150300D01*
X592375Y150092D01*
X592500Y149717D01*
X592458Y149342D01*
X592292Y148967D01*
G01X590000Y153150D02*
X592500D01*
X590708Y151608D01*
Y153692D01*
G01X613333Y163200D02*
Y165700D01*
X612333D01*
X612000Y165575D01*
X611750Y165283D01*
X611667Y164950D01*
X611750Y164617D01*
X611958Y164367D01*
X612333Y164242D01*
X613333D01*
G01X608483Y165492D02*
X608733Y165617D01*
X609025Y165700D01*
X609358D01*
X609733Y165575D01*
X610025Y165367D01*
X610233Y165117D01*
X610400Y164700D01*
X610442Y164325D01*
X610358Y163950D01*
X610233Y163700D01*
X609983Y163450D01*
X609692Y163283D01*
X609400Y163200D01*
X609108D01*
X608817Y163283D01*
X608567Y163408D01*
X608358Y163575D01*
G01X606300Y163200D02*
Y165700D01*
X606800Y165200D01*
G01Y163200D02*
X605800D01*
G01X603992Y165283D02*
X603742Y165533D01*
X603450Y165658D01*
X603117Y165700D01*
X602700Y165617D01*
X602408Y165408D01*
X602325Y165158D01*
X602367Y164908D01*
X602533Y164700D01*
X603367Y164283D01*
X603742Y163992D01*
X603992Y163575D01*
X604075Y163200D01*
X602325D01*
G01X600892Y164242D02*
X600600Y164533D01*
X600350Y164700D01*
X600017Y164783D01*
X599725Y164700D01*
X599517Y164533D01*
X599350Y164283D01*
X599308Y163992D01*
X599350Y163742D01*
X599517Y163492D01*
X599767Y163283D01*
X600058Y163200D01*
X600392Y163283D01*
X600683Y163533D01*
X600850Y163908D01*
X600892Y164325D01*
X600808Y164867D01*
X600683Y165158D01*
X600475Y165450D01*
X600183Y165658D01*
X599892Y165700D01*
X599600Y165617D01*
X599392Y165408D01*
G01X613233Y159100D02*
Y161600D01*
X612233D01*
X611900Y161475D01*
X611650Y161183D01*
X611567Y160850D01*
X611650Y160517D01*
X611858Y160267D01*
X612233Y160142D01*
X613233D01*
G01X610133Y159100D02*
Y161600D01*
X609092D01*
X608758Y161475D01*
X608550Y161308D01*
X608467Y160975D01*
X608550Y160642D01*
X608800Y160433D01*
X609092Y160308D01*
X610133D01*
G01X609092D02*
X608467Y159100D01*
G01X606200D02*
Y161600D01*
X606700Y161100D01*
G01Y159100D02*
X605700D01*
G01X603100D02*
X602808Y159142D01*
X602475Y159267D01*
X602267Y159475D01*
X602183Y159767D01*
X602267Y160058D01*
X602517Y160308D01*
X602892Y160433D01*
X603308D01*
X603558Y160517D01*
X603767Y160725D01*
X603850Y161017D01*
X603725Y161308D01*
X603433Y161517D01*
X603100Y161600D01*
X602767Y161517D01*
X602475Y161308D01*
X602350Y161017D01*
X602433Y160725D01*
X602642Y160517D01*
X602892Y160433D01*
X603308D01*
X603683Y160308D01*
X603933Y160058D01*
X604017Y159767D01*
X603933Y159475D01*
X603725Y159267D01*
X603392Y159142D01*
X603100Y159100D01*
G01X600917Y159600D02*
X600667Y159308D01*
X600333Y159142D01*
X599958Y159100D01*
X599625Y159142D01*
X599292Y159350D01*
X599083Y159600D01*
X599042Y159850D01*
X599125Y160142D01*
X599417Y160350D01*
X599708Y160433D01*
X600083D01*
G01X599708D02*
X599458Y160558D01*
X599250Y160767D01*
X599167Y161017D01*
X599250Y161267D01*
X599458Y161475D01*
X599833Y161600D01*
X600208Y161558D01*
X600583Y161392D01*
G01X613533Y155500D02*
Y158000D01*
X612533D01*
X612200Y157875D01*
X611950Y157583D01*
X611867Y157250D01*
X611950Y156917D01*
X612158Y156667D01*
X612533Y156542D01*
X613533D01*
G01X610433Y155500D02*
Y158000D01*
X609392D01*
X609058Y157875D01*
X608850Y157708D01*
X608767Y157375D01*
X608850Y157042D01*
X609100Y156833D01*
X609392Y156708D01*
X610433D01*
G01X609392D02*
X608767Y155500D01*
G01X606500D02*
Y158000D01*
X607000Y157500D01*
G01Y155500D02*
X606000D01*
G01X603400D02*
X603108Y155542D01*
X602775Y155667D01*
X602567Y155875D01*
X602483Y156167D01*
X602567Y156458D01*
X602817Y156708D01*
X603192Y156833D01*
X603608D01*
X603858Y156917D01*
X604067Y157125D01*
X604150Y157417D01*
X604025Y157708D01*
X603733Y157917D01*
X603400Y158000D01*
X603067Y157917D01*
X602775Y157708D01*
X602650Y157417D01*
X602733Y157125D01*
X602942Y156917D01*
X603192Y156833D01*
X603608D01*
X603983Y156708D01*
X604233Y156458D01*
X604317Y156167D01*
X604233Y155875D01*
X604025Y155667D01*
X603692Y155542D01*
X603400Y155500D01*
G01X600300Y158000D02*
X600633Y157917D01*
X600883Y157708D01*
X601050Y157458D01*
X601175Y157125D01*
X601217Y156750D01*
X601175Y156375D01*
X601050Y156042D01*
X600883Y155792D01*
X600633Y155583D01*
X600300Y155500D01*
X599967Y155583D01*
X599717Y155792D01*
X599550Y156042D01*
X599425Y156375D01*
X599383Y156750D01*
X599425Y157125D01*
X599550Y157458D01*
X599717Y157708D01*
X599967Y157917D01*
X600300Y158000D01*
G01X612983Y167000D02*
Y169500D01*
X611942D01*
X611608Y169375D01*
X611400Y169208D01*
X611317Y168875D01*
X611400Y168542D01*
X611650Y168333D01*
X611942Y168208D01*
X612983D01*
G01X611942D02*
X611317Y167000D01*
G01X609967Y167375D02*
X609717Y167167D01*
X609425Y167042D01*
X609050Y167000D01*
X608675Y167083D01*
X608383Y167250D01*
X608175Y167542D01*
X608133Y167875D01*
X608217Y168208D01*
X608425Y168417D01*
X608717Y168583D01*
X609008Y168625D01*
X609300Y168583D01*
X609675Y168417D01*
X609550Y169500D01*
X608425D01*
G01X605950D02*
X606283Y169417D01*
X606533Y169208D01*
X606700Y168958D01*
X606825Y168625D01*
X606867Y168250D01*
X606825Y167875D01*
X606700Y167542D01*
X606533Y167292D01*
X606283Y167083D01*
X605950Y167000D01*
X605617Y167083D01*
X605367Y167292D01*
X605200Y167542D01*
X605075Y167875D01*
X605033Y168250D01*
X605075Y168625D01*
X605200Y168958D01*
X605367Y169208D01*
X605617Y169417D01*
X605950Y169500D01*
G01X602350Y167000D02*
Y169500D01*
X603892Y167708D01*
X601808D01*
G01X613033Y180500D02*
Y183000D01*
X612033D01*
X611700Y182875D01*
X611450Y182583D01*
X611367Y182250D01*
X611450Y181917D01*
X611658Y181667D01*
X612033Y181542D01*
X613033D01*
G01X609933Y180500D02*
Y183000D01*
X608892D01*
X608558Y182875D01*
X608350Y182708D01*
X608267Y182375D01*
X608350Y182042D01*
X608600Y181833D01*
X608892Y181708D01*
X609933D01*
G01X608892D02*
X608267Y180500D01*
G01X606000D02*
Y183000D01*
X606500Y182500D01*
G01Y180500D02*
X605500D01*
G01X602900D02*
X602608Y180542D01*
X602275Y180667D01*
X602067Y180875D01*
X601983Y181167D01*
X602067Y181458D01*
X602317Y181708D01*
X602692Y181833D01*
X603108D01*
X603358Y181917D01*
X603567Y182125D01*
X603650Y182417D01*
X603525Y182708D01*
X603233Y182917D01*
X602900Y183000D01*
X602567Y182917D01*
X602275Y182708D01*
X602150Y182417D01*
X602233Y182125D01*
X602442Y181917D01*
X602692Y181833D01*
X603108D01*
X603483Y181708D01*
X603733Y181458D01*
X603817Y181167D01*
X603733Y180875D01*
X603525Y180667D01*
X603192Y180542D01*
X602900Y180500D01*
G01X599300D02*
Y183000D01*
X600842Y181208D01*
X598758D01*
G01X599000Y185017D02*
X601500D01*
Y186058D01*
X601375Y186392D01*
X601208Y186600D01*
X600875Y186683D01*
X600542Y186600D01*
X600333Y186350D01*
X600208Y186058D01*
Y185017D01*
G01Y186058D02*
X599000Y186683D01*
G01Y188950D02*
X601500D01*
X601000Y188450D01*
G01X599000D02*
Y189450D01*
G01X599375Y191133D02*
X599167Y191383D01*
X599042Y191675D01*
X599000Y192050D01*
X599083Y192425D01*
X599250Y192717D01*
X599542Y192925D01*
X599875Y192967D01*
X600208Y192883D01*
X600417Y192675D01*
X600583Y192383D01*
X600625Y192092D01*
X600583Y191800D01*
X600417Y191425D01*
X601500Y191550D01*
Y192675D01*
G01X599000Y195150D02*
X599042Y195442D01*
X599167Y195775D01*
X599375Y195983D01*
X599667Y196067D01*
X599958Y195983D01*
X600208Y195733D01*
X600333Y195358D01*
Y194942D01*
X600417Y194692D01*
X600625Y194483D01*
X600917Y194400D01*
X601208Y194525D01*
X601417Y194817D01*
X601500Y195150D01*
X601417Y195483D01*
X601208Y195775D01*
X600917Y195900D01*
X600625Y195817D01*
X600417Y195608D01*
X600333Y195358D01*
Y194942D01*
X600208Y194567D01*
X599958Y194317D01*
X599667Y194233D01*
X599375Y194317D01*
X599167Y194525D01*
X599042Y194858D01*
X599000Y195150D01*
G01X604792Y218767D02*
X604917Y218517D01*
X605000Y218225D01*
Y217892D01*
X604875Y217517D01*
X604667Y217225D01*
X604417Y217017D01*
X604000Y216850D01*
X603625Y216808D01*
X603250Y216892D01*
X603000Y217017D01*
X602750Y217267D01*
X602583Y217558D01*
X602500Y217850D01*
Y218142D01*
X602583Y218433D01*
X602708Y218683D01*
X602875Y218892D01*
G01X603000Y220033D02*
X602708Y220283D01*
X602542Y220617D01*
X602500Y220992D01*
X602542Y221325D01*
X602750Y221658D01*
X603000Y221867D01*
X603250Y221908D01*
X603542Y221825D01*
X603750Y221533D01*
X603833Y221242D01*
Y220867D01*
G01Y221242D02*
X603958Y221492D01*
X604167Y221700D01*
X604417Y221783D01*
X604667Y221700D01*
X604875Y221492D01*
X605000Y221117D01*
X604958Y220742D01*
X604792Y220367D01*
G01X603000Y223133D02*
X602708Y223383D01*
X602542Y223717D01*
X602500Y224092D01*
X602542Y224425D01*
X602750Y224758D01*
X603000Y224967D01*
X603250Y225008D01*
X603542Y224925D01*
X603750Y224633D01*
X603833Y224342D01*
Y223967D01*
G01Y224342D02*
X603958Y224592D01*
X604167Y224800D01*
X604417Y224883D01*
X604667Y224800D01*
X604875Y224592D01*
X605000Y224217D01*
X604958Y223842D01*
X604792Y223467D01*
G01X602500Y227150D02*
X605000D01*
X604500Y226650D01*
G01X602500D02*
Y227650D01*
G01X600792Y218767D02*
X600917Y218517D01*
X601000Y218225D01*
Y217892D01*
X600875Y217517D01*
X600667Y217225D01*
X600417Y217017D01*
X600000Y216850D01*
X599625Y216808D01*
X599250Y216892D01*
X599000Y217017D01*
X598750Y217267D01*
X598583Y217558D01*
X598500Y217850D01*
Y218142D01*
X598583Y218433D01*
X598708Y218683D01*
X598875Y218892D01*
G01X598500Y220950D02*
X601000D01*
X600500Y220450D01*
G01X598500D02*
Y221450D01*
G01X601000Y224050D02*
X600917Y223717D01*
X600708Y223467D01*
X600458Y223300D01*
X600125Y223175D01*
X599750Y223133D01*
X599375Y223175D01*
X599042Y223300D01*
X598792Y223467D01*
X598583Y223717D01*
X598500Y224050D01*
X598583Y224383D01*
X598792Y224633D01*
X599042Y224800D01*
X599375Y224925D01*
X599750Y224967D01*
X600125Y224925D01*
X600458Y224800D01*
X600708Y224633D01*
X600917Y224383D01*
X601000Y224050D01*
G01Y227150D02*
X600917Y226817D01*
X600708Y226567D01*
X600458Y226400D01*
X600125Y226275D01*
X599750Y226233D01*
X599375Y226275D01*
X599042Y226400D01*
X598792Y226567D01*
X598583Y226817D01*
X598500Y227150D01*
X598583Y227483D01*
X598792Y227733D01*
X599042Y227900D01*
X599375Y228025D01*
X599750Y228067D01*
X600125Y228025D01*
X600458Y227900D01*
X600708Y227733D01*
X600917Y227483D01*
X601000Y227150D01*
G01X691167Y116000D02*
Y123000D01*
X687967D01*
X686900Y122650D01*
X686100Y121833D01*
X685833Y120900D01*
X686100Y119967D01*
X686767Y119267D01*
X687967Y118916D01*
X691167D01*
G01X677500Y116000D02*
Y120667D01*
G01Y119850D02*
X678033Y120317D01*
X678833Y120550D01*
X679767Y120667D01*
X680700Y120433D01*
X681500Y119967D01*
X682033Y119267D01*
X682300Y118333D01*
X682033Y117400D01*
X681500Y116700D01*
X680700Y116233D01*
X679767Y116000D01*
X678833Y116117D01*
X678033Y116467D01*
X677500Y116933D01*
G01X673567Y116000D02*
Y120667D01*
G01Y119500D02*
X673033Y120083D01*
X672233Y120550D01*
X671167Y120667D01*
X670233Y120550D01*
X669433Y120083D01*
X669033Y119267D01*
Y116000D01*
G01X662700Y123000D02*
Y116000D01*
G01X664567Y120667D02*
X660833D01*
G01X656367Y116000D02*
Y123000D01*
G01Y119617D02*
X655700Y120200D01*
X655033Y120550D01*
X653967Y120667D01*
X653167Y120550D01*
X652233Y120083D01*
X651833Y119383D01*
Y116000D01*
G01X647500Y119150D02*
X643233D01*
X643633Y119967D01*
X644300Y120433D01*
X645233Y120667D01*
X646167Y120550D01*
X646967Y120200D01*
X647500Y119383D01*
X647767Y118683D01*
Y117983D01*
X647500Y117283D01*
X646833Y116583D01*
X646033Y116117D01*
X645100Y116000D01*
X644167Y116233D01*
X643233Y116933D01*
G01X638767Y116000D02*
Y120667D01*
G01Y119733D02*
X638100Y120200D01*
X637433Y120550D01*
X636500Y120667D01*
X635833Y120550D01*
X635033Y120200D01*
G01X623167Y116000D02*
Y123000D01*
X619700Y117167D01*
X616233Y123000D01*
Y116000D01*
G01X610033Y119733D02*
X609500Y120083D01*
X609100Y120667D01*
X608833Y121483D01*
X609100Y122183D01*
X609633Y122650D01*
X610567Y123000D01*
X614167D01*
Y116000D01*
X609767D01*
X608833Y116467D01*
X608300Y117167D01*
X608033Y117983D01*
X608300Y118800D01*
X609100Y119500D01*
X610033Y119733D01*
X614167D01*
G01X692167Y142500D02*
Y147500D01*
X690083D01*
X689417Y147250D01*
X689000Y146917D01*
X688833Y146250D01*
X689000Y145583D01*
X689500Y145167D01*
X690083Y144917D01*
X692167D01*
G01X690083D02*
X688833Y142500D01*
G01X684900D02*
X685567Y142583D01*
X686150Y142917D01*
X686650Y143417D01*
X686983Y144000D01*
X687150Y144667D01*
Y145333D01*
X686983Y146000D01*
X686650Y146583D01*
X686150Y147083D01*
X685567Y147417D01*
X684900Y147500D01*
X684233Y147417D01*
X683650Y147083D01*
X683150Y146583D01*
X682817Y146000D01*
X682650Y145333D01*
Y144667D01*
X682817Y144000D01*
X683150Y143417D01*
X683650Y142917D01*
X684233Y142583D01*
X684900Y142500D01*
G01X681050D02*
Y147500D01*
G01X677550D02*
Y142500D01*
G01Y145000D02*
X681050D01*
G01X675450Y143167D02*
X674783Y142750D01*
X674033Y142500D01*
X673367D01*
X672700Y142750D01*
X672200Y143167D01*
X671950Y143750D01*
X672117Y144333D01*
X672533Y144833D01*
X673283Y145167D01*
X674283Y145333D01*
X674867Y145667D01*
X675117Y146250D01*
X674950Y146833D01*
X674533Y147250D01*
X673950Y147500D01*
X673367D01*
X672783Y147333D01*
X672283Y146917D01*
G01X660667Y147083D02*
X661167Y147333D01*
X661750Y147500D01*
X662417D01*
X663167Y147250D01*
X663750Y146833D01*
X664167Y146333D01*
X664500Y145500D01*
X664583Y144750D01*
X664417Y144000D01*
X664167Y143500D01*
X663667Y143000D01*
X663083Y142667D01*
X662500Y142500D01*
X661917D01*
X661333Y142667D01*
X660833Y142917D01*
X660417Y143250D01*
G01X656900Y142500D02*
X657400Y142583D01*
X657900Y142917D01*
X658233Y143500D01*
X658400Y144167D01*
X658233Y144833D01*
X657900Y145417D01*
X657400Y145750D01*
X656900Y145833D01*
X656400Y145750D01*
X655900Y145417D01*
X655567Y144833D01*
X655483Y144167D01*
X655567Y143500D01*
X655900Y142917D01*
X656400Y142583D01*
X656900Y142500D01*
G01X653800D02*
Y145833D01*
G01Y144917D02*
X653550Y145333D01*
X653133Y145667D01*
X652550Y145833D01*
X651967Y145667D01*
X651550Y145333D01*
X651300Y144917D01*
Y142500D01*
G01Y144917D02*
X651050Y145333D01*
X650633Y145667D01*
X650050Y145833D01*
X649467Y145667D01*
X649050Y145333D01*
X648800Y144833D01*
Y142500D01*
G01X647200Y140833D02*
Y145833D01*
G01Y145083D02*
X646783Y145500D01*
X646367Y145750D01*
X645700Y145833D01*
X645117Y145750D01*
X644533Y145333D01*
X644283Y144750D01*
X644200Y144167D01*
X644283Y143583D01*
X644533Y143000D01*
X645033Y142667D01*
X645700Y142500D01*
X646283Y142583D01*
X646867Y142833D01*
X647200Y143167D01*
G01X640100Y142500D02*
Y147500D01*
G01X634500Y145833D02*
Y142500D01*
G01Y147167D02*
X634667Y147250D01*
Y147417D01*
X634500Y147500D01*
X634333Y147417D01*
Y147250D01*
X634500Y147167D01*
G01X627400Y142500D02*
Y145833D01*
G01Y145250D02*
X627733Y145583D01*
X628233Y145750D01*
X628817Y145833D01*
X629400Y145667D01*
X629900Y145333D01*
X630233Y144833D01*
X630400Y144167D01*
X630233Y143500D01*
X629900Y143000D01*
X629400Y142667D01*
X628817Y142500D01*
X628233Y142583D01*
X627733Y142833D01*
X627400Y143167D01*
G01X624717Y142500D02*
Y145833D01*
G01Y145000D02*
X624383Y145417D01*
X623883Y145750D01*
X623217Y145833D01*
X622633Y145750D01*
X622133Y145417D01*
X621883Y144833D01*
Y142500D01*
G01X616367Y145417D02*
X616950Y145750D01*
X617450Y145833D01*
X618117Y145667D01*
X618617Y145333D01*
X618950Y144750D01*
X619033Y144167D01*
X618950Y143583D01*
X618617Y143083D01*
X618117Y142667D01*
X617450Y142500D01*
X616867Y142667D01*
X616367Y143000D01*
G01X613350Y144750D02*
X610683D01*
X610933Y145333D01*
X611350Y145667D01*
X611933Y145833D01*
X612517Y145750D01*
X613017Y145500D01*
X613350Y144917D01*
X613517Y144417D01*
Y143917D01*
X613350Y143417D01*
X612933Y142917D01*
X612433Y142583D01*
X611850Y142500D01*
X611267Y142667D01*
X610683Y143167D01*
G01X627033Y189000D02*
Y191500D01*
X626033D01*
X625700Y191375D01*
X625450Y191083D01*
X625367Y190750D01*
X625450Y190417D01*
X625658Y190167D01*
X626033Y190042D01*
X627033D01*
G01X622183Y191292D02*
X622433Y191417D01*
X622725Y191500D01*
X623058D01*
X623433Y191375D01*
X623725Y191167D01*
X623933Y190917D01*
X624100Y190500D01*
X624142Y190125D01*
X624058Y189750D01*
X623933Y189500D01*
X623683Y189250D01*
X623392Y189083D01*
X623100Y189000D01*
X622808D01*
X622517Y189083D01*
X622267Y189208D01*
X622058Y189375D01*
G01X620000Y189000D02*
Y191500D01*
X620500Y191000D01*
G01Y189000D02*
X619500D01*
G01X617692Y191083D02*
X617442Y191333D01*
X617150Y191458D01*
X616817Y191500D01*
X616400Y191417D01*
X616108Y191208D01*
X616025Y190958D01*
X616067Y190708D01*
X616233Y190500D01*
X617067Y190083D01*
X617442Y189792D01*
X617692Y189375D01*
X617775Y189000D01*
X616025D01*
G01X613883D02*
X613800Y189542D01*
X613675Y190000D01*
X613508Y190417D01*
X613300Y190875D01*
X612967Y191500D01*
X614633D01*
G01X611000Y184967D02*
X608500D01*
Y186633D01*
G01Y189733D02*
Y188067D01*
X611000D01*
Y189733D01*
G01X609792Y189067D02*
Y188067D01*
G01X608500Y191083D02*
X611000D01*
Y191917D01*
X610875Y192250D01*
X610708Y192500D01*
X610458Y192708D01*
X610167Y192875D01*
X609750Y192917D01*
X609333Y192875D01*
X609042Y192708D01*
X608792Y192500D01*
X608625Y192250D01*
X608500Y191917D01*
Y191083D01*
G01Y195100D02*
X611000D01*
X610500Y194600D01*
G01X608500D02*
Y195600D01*
G01X609542Y197408D02*
X609833Y197700D01*
X610000Y197950D01*
X610083Y198283D01*
X610000Y198575D01*
X609833Y198783D01*
X609583Y198950D01*
X609292Y198992D01*
X609042Y198950D01*
X608792Y198783D01*
X608583Y198533D01*
X608500Y198242D01*
X608583Y197908D01*
X608833Y197617D01*
X609208Y197450D01*
X609625Y197408D01*
X610167Y197492D01*
X610458Y197617D01*
X610750Y197825D01*
X610958Y198117D01*
X611000Y198408D01*
X610917Y198700D01*
X610708Y198908D01*
G01X628483Y198500D02*
Y201000D01*
X627442D01*
X627108Y200875D01*
X626900Y200708D01*
X626817Y200375D01*
X626900Y200042D01*
X627150Y199833D01*
X627442Y199708D01*
X628483D01*
G01X627442D02*
X626817Y198500D01*
G01X625467Y199000D02*
X625217Y198708D01*
X624883Y198542D01*
X624508Y198500D01*
X624175Y198542D01*
X623842Y198750D01*
X623633Y199000D01*
X623592Y199250D01*
X623675Y199542D01*
X623967Y199750D01*
X624258Y199833D01*
X624633D01*
G01X624258D02*
X624008Y199958D01*
X623800Y200167D01*
X623717Y200417D01*
X623800Y200667D01*
X624008Y200875D01*
X624383Y201000D01*
X624758Y200958D01*
X625133Y200792D01*
G01X620950Y198500D02*
Y201000D01*
X622492Y199208D01*
X620408D01*
G01X617850Y198500D02*
Y201000D01*
X619392Y199208D01*
X617308D01*
G01X604000Y185017D02*
X606500D01*
Y186058D01*
X606375Y186392D01*
X606208Y186600D01*
X605875Y186683D01*
X605542Y186600D01*
X605333Y186350D01*
X605208Y186058D01*
Y185017D01*
G01Y186058D02*
X604000Y186683D01*
G01X604500Y188033D02*
X604208Y188283D01*
X604042Y188617D01*
X604000Y188992D01*
X604042Y189325D01*
X604250Y189658D01*
X604500Y189867D01*
X604750Y189908D01*
X605042Y189825D01*
X605250Y189533D01*
X605333Y189242D01*
Y188867D01*
G01Y189242D02*
X605458Y189492D01*
X605667Y189700D01*
X605917Y189783D01*
X606167Y189700D01*
X606375Y189492D01*
X606500Y189117D01*
X606458Y188742D01*
X606292Y188367D01*
G01X604292Y191342D02*
X604083Y191633D01*
X604000Y191967D01*
X604083Y192300D01*
X604333Y192592D01*
X604708Y192800D01*
X605083Y192883D01*
X605542D01*
X605917Y192800D01*
X606250Y192592D01*
X606417Y192342D01*
X606500Y192050D01*
X606417Y191717D01*
X606250Y191467D01*
X606000Y191300D01*
X605667Y191217D01*
X605375Y191300D01*
X605083Y191508D01*
X604917Y191758D01*
X604875Y192050D01*
X604958Y192383D01*
X605167Y192633D01*
X605542Y192883D01*
G01X604000Y195650D02*
X606500D01*
X604708Y194108D01*
Y196192D01*
G01X617233Y208292D02*
X617483Y208417D01*
X617775Y208500D01*
X618108D01*
X618483Y208375D01*
X618775Y208167D01*
X618983Y207917D01*
X619150Y207500D01*
X619192Y207125D01*
X619108Y206750D01*
X618983Y206500D01*
X618733Y206250D01*
X618442Y206083D01*
X618150Y206000D01*
X617858D01*
X617567Y206083D01*
X617317Y206208D01*
X617108Y206375D01*
G01X615967Y206500D02*
X615717Y206208D01*
X615383Y206042D01*
X615008Y206000D01*
X614675Y206042D01*
X614342Y206250D01*
X614133Y206500D01*
X614092Y206750D01*
X614175Y207042D01*
X614467Y207250D01*
X614758Y207333D01*
X615133D01*
G01X614758D02*
X614508Y207458D01*
X614300Y207667D01*
X614217Y207917D01*
X614300Y208167D01*
X614508Y208375D01*
X614883Y208500D01*
X615258Y208458D01*
X615633Y208292D01*
G01X612867Y206375D02*
X612617Y206167D01*
X612325Y206042D01*
X611950Y206000D01*
X611575Y206083D01*
X611283Y206250D01*
X611075Y206542D01*
X611033Y206875D01*
X611117Y207208D01*
X611325Y207417D01*
X611617Y207583D01*
X611908Y207625D01*
X612200Y207583D01*
X612575Y207417D01*
X612450Y208500D01*
X611325D01*
G01X608850Y206000D02*
X608558Y206042D01*
X608225Y206167D01*
X608017Y206375D01*
X607933Y206667D01*
X608017Y206958D01*
X608267Y207208D01*
X608642Y207333D01*
X609058D01*
X609308Y207417D01*
X609517Y207625D01*
X609600Y207917D01*
X609475Y208208D01*
X609183Y208417D01*
X608850Y208500D01*
X608517Y208417D01*
X608225Y208208D01*
X608100Y207917D01*
X608183Y207625D01*
X608392Y207417D01*
X608642Y207333D01*
X609058D01*
X609433Y207208D01*
X609683Y206958D01*
X609767Y206667D01*
X609683Y206375D01*
X609475Y206167D01*
X609142Y206042D01*
X608850Y206000D01*
G01X616792Y218767D02*
X616917Y218517D01*
X617000Y218225D01*
Y217892D01*
X616875Y217517D01*
X616667Y217225D01*
X616417Y217017D01*
X616000Y216850D01*
X615625Y216808D01*
X615250Y216892D01*
X615000Y217017D01*
X614750Y217267D01*
X614583Y217558D01*
X614500Y217850D01*
Y218142D01*
X614583Y218433D01*
X614708Y218683D01*
X614875Y218892D01*
G01X614500Y220950D02*
X617000D01*
X616500Y220450D01*
G01X614500D02*
Y221450D01*
G01X617000Y224050D02*
X616917Y223717D01*
X616708Y223467D01*
X616458Y223300D01*
X616125Y223175D01*
X615750Y223133D01*
X615375Y223175D01*
X615042Y223300D01*
X614792Y223467D01*
X614583Y223717D01*
X614500Y224050D01*
X614583Y224383D01*
X614792Y224633D01*
X615042Y224800D01*
X615375Y224925D01*
X615750Y224967D01*
X616125Y224925D01*
X616458Y224800D01*
X616708Y224633D01*
X616917Y224383D01*
X617000Y224050D01*
G01X614500Y227150D02*
X617000D01*
X616500Y226650D01*
G01X614500D02*
Y227650D01*
G01X612792Y218767D02*
X612917Y218517D01*
X613000Y218225D01*
Y217892D01*
X612875Y217517D01*
X612667Y217225D01*
X612417Y217017D01*
X612000Y216850D01*
X611625Y216808D01*
X611250Y216892D01*
X611000Y217017D01*
X610750Y217267D01*
X610583Y217558D01*
X610500Y217850D01*
Y218142D01*
X610583Y218433D01*
X610708Y218683D01*
X610875Y218892D01*
G01X611000Y220033D02*
X610708Y220283D01*
X610542Y220617D01*
X610500Y220992D01*
X610542Y221325D01*
X610750Y221658D01*
X611000Y221867D01*
X611250Y221908D01*
X611542Y221825D01*
X611750Y221533D01*
X611833Y221242D01*
Y220867D01*
G01Y221242D02*
X611958Y221492D01*
X612167Y221700D01*
X612417Y221783D01*
X612667Y221700D01*
X612875Y221492D01*
X613000Y221117D01*
X612958Y220742D01*
X612792Y220367D01*
G01X612583Y223258D02*
X612833Y223508D01*
X612958Y223800D01*
X613000Y224133D01*
X612917Y224550D01*
X612708Y224842D01*
X612458Y224925D01*
X612208Y224883D01*
X612000Y224717D01*
X611583Y223883D01*
X611292Y223508D01*
X610875Y223258D01*
X610500Y223175D01*
Y224925D01*
G01Y227650D02*
X613000D01*
X611208Y226108D01*
Y228192D01*
G01X608792Y218767D02*
X608917Y218517D01*
X609000Y218225D01*
Y217892D01*
X608875Y217517D01*
X608667Y217225D01*
X608417Y217017D01*
X608000Y216850D01*
X607625Y216808D01*
X607250Y216892D01*
X607000Y217017D01*
X606750Y217267D01*
X606583Y217558D01*
X606500Y217850D01*
Y218142D01*
X606583Y218433D01*
X606708Y218683D01*
X606875Y218892D01*
G01X606500Y220950D02*
X609000D01*
X608500Y220450D01*
G01X606500D02*
Y221450D01*
G01X609000Y224050D02*
X608917Y223717D01*
X608708Y223467D01*
X608458Y223300D01*
X608125Y223175D01*
X607750Y223133D01*
X607375Y223175D01*
X607042Y223300D01*
X606792Y223467D01*
X606583Y223717D01*
X606500Y224050D01*
X606583Y224383D01*
X606792Y224633D01*
X607042Y224800D01*
X607375Y224925D01*
X607750Y224967D01*
X608125Y224925D01*
X608458Y224800D01*
X608708Y224633D01*
X608917Y224383D01*
X609000Y224050D01*
G01X606875Y226233D02*
X606667Y226483D01*
X606542Y226775D01*
X606500Y227150D01*
X606583Y227525D01*
X606750Y227817D01*
X607042Y228025D01*
X607375Y228067D01*
X607708Y227983D01*
X607917Y227775D01*
X608083Y227483D01*
X608125Y227192D01*
X608083Y226900D01*
X607917Y226525D01*
X609000Y226650D01*
Y227775D01*
G01X617483Y285000D02*
Y287500D01*
X616442D01*
X616108Y287375D01*
X615900Y287208D01*
X615817Y286875D01*
X615900Y286542D01*
X616150Y286333D01*
X616442Y286208D01*
X617483D01*
G01X616442D02*
X615817Y285000D01*
G01X614342Y287083D02*
X614092Y287333D01*
X613800Y287458D01*
X613467Y287500D01*
X613050Y287417D01*
X612758Y287208D01*
X612675Y286958D01*
X612717Y286708D01*
X612883Y286500D01*
X613717Y286083D01*
X614092Y285792D01*
X614342Y285375D01*
X614425Y285000D01*
X612675D01*
G01X611367Y285500D02*
X611117Y285208D01*
X610783Y285042D01*
X610408Y285000D01*
X610075Y285042D01*
X609742Y285250D01*
X609533Y285500D01*
X609492Y285750D01*
X609575Y286042D01*
X609867Y286250D01*
X610158Y286333D01*
X610533D01*
G01X610158D02*
X609908Y286458D01*
X609700Y286667D01*
X609617Y286917D01*
X609700Y287167D01*
X609908Y287375D01*
X610283Y287500D01*
X610658Y287458D01*
X611033Y287292D01*
G01X608267Y285500D02*
X608017Y285208D01*
X607683Y285042D01*
X607308Y285000D01*
X606975Y285042D01*
X606642Y285250D01*
X606433Y285500D01*
X606392Y285750D01*
X606475Y286042D01*
X606767Y286250D01*
X607058Y286333D01*
X607433D01*
G01X607058D02*
X606808Y286458D01*
X606600Y286667D01*
X606517Y286917D01*
X606600Y287167D01*
X606808Y287375D01*
X607183Y287500D01*
X607558Y287458D01*
X607933Y287292D01*
G01X628292Y55774D02*
X628417Y55524D01*
X628500Y55232D01*
Y54899D01*
X628375Y54524D01*
X628167Y54232D01*
X627917Y54024D01*
X627500Y53857D01*
X627125Y53815D01*
X626750Y53899D01*
X626500Y54024D01*
X626250Y54274D01*
X626083Y54565D01*
X626000Y54857D01*
Y55149D01*
X626083Y55440D01*
X626208Y55690D01*
X626375Y55899D01*
G01X628083Y57165D02*
X628333Y57415D01*
X628458Y57707D01*
X628500Y58040D01*
X628417Y58457D01*
X628208Y58749D01*
X627958Y58832D01*
X627708Y58790D01*
X627500Y58624D01*
X627083Y57790D01*
X626792Y57415D01*
X626375Y57165D01*
X626000Y57082D01*
Y58832D01*
G01X626292Y60349D02*
X626083Y60640D01*
X626000Y60974D01*
X626083Y61307D01*
X626333Y61599D01*
X626708Y61807D01*
X627083Y61890D01*
X627542D01*
X627917Y61807D01*
X628250Y61599D01*
X628417Y61349D01*
X628500Y61057D01*
X628417Y60724D01*
X628250Y60474D01*
X628000Y60307D01*
X627667Y60224D01*
X627375Y60307D01*
X627083Y60515D01*
X626917Y60765D01*
X626875Y61057D01*
X626958Y61390D01*
X627167Y61640D01*
X627542Y61890D01*
G01X626292Y63449D02*
X626083Y63740D01*
X626000Y64074D01*
X626083Y64407D01*
X626333Y64699D01*
X626708Y64907D01*
X627083Y64990D01*
X627542D01*
X627917Y64907D01*
X628250Y64699D01*
X628417Y64449D01*
X628500Y64157D01*
X628417Y63824D01*
X628250Y63574D01*
X628000Y63407D01*
X627667Y63324D01*
X627375Y63407D01*
X627083Y63615D01*
X626917Y63865D01*
X626875Y64157D01*
X626958Y64490D01*
X627167Y64740D01*
X627542Y64990D01*
G01X633292Y55274D02*
X633417Y55024D01*
X633500Y54732D01*
Y54399D01*
X633375Y54024D01*
X633167Y53732D01*
X632917Y53524D01*
X632500Y53357D01*
X632125Y53315D01*
X631750Y53399D01*
X631500Y53524D01*
X631250Y53774D01*
X631083Y54065D01*
X631000Y54357D01*
Y54649D01*
X631083Y54940D01*
X631208Y55190D01*
X631375Y55399D01*
G01X631500Y56540D02*
X631208Y56790D01*
X631042Y57124D01*
X631000Y57499D01*
X631042Y57832D01*
X631250Y58165D01*
X631500Y58374D01*
X631750Y58415D01*
X632042Y58332D01*
X632250Y58040D01*
X632333Y57749D01*
Y57374D01*
G01Y57749D02*
X632458Y57999D01*
X632667Y58207D01*
X632917Y58290D01*
X633167Y58207D01*
X633375Y57999D01*
X633500Y57624D01*
X633458Y57249D01*
X633292Y56874D01*
G01X631500Y59640D02*
X631208Y59890D01*
X631042Y60224D01*
X631000Y60599D01*
X631042Y60932D01*
X631250Y61265D01*
X631500Y61474D01*
X631750Y61515D01*
X632042Y61432D01*
X632250Y61140D01*
X632333Y60849D01*
Y60474D01*
G01Y60849D02*
X632458Y61099D01*
X632667Y61307D01*
X632917Y61390D01*
X633167Y61307D01*
X633375Y61099D01*
X633500Y60724D01*
X633458Y60349D01*
X633292Y59974D01*
G01X631000Y64157D02*
X633500D01*
X631708Y62615D01*
Y64699D01*
G01X623292Y57774D02*
X623417Y57524D01*
X623500Y57232D01*
Y56899D01*
X623375Y56524D01*
X623167Y56232D01*
X622917Y56024D01*
X622500Y55857D01*
X622125Y55815D01*
X621750Y55899D01*
X621500Y56024D01*
X621250Y56274D01*
X621083Y56565D01*
X621000Y56857D01*
Y57149D01*
X621083Y57440D01*
X621208Y57690D01*
X621375Y57899D01*
G01X623083Y59165D02*
X623333Y59415D01*
X623458Y59707D01*
X623500Y60040D01*
X623417Y60457D01*
X623208Y60749D01*
X622958Y60832D01*
X622708Y60790D01*
X622500Y60624D01*
X622083Y59790D01*
X621792Y59415D01*
X621375Y59165D01*
X621000Y59082D01*
Y60832D01*
G01X621292Y62349D02*
X621083Y62640D01*
X621000Y62974D01*
X621083Y63307D01*
X621333Y63599D01*
X621708Y63807D01*
X622083Y63890D01*
X622542D01*
X622917Y63807D01*
X623250Y63599D01*
X623417Y63349D01*
X623500Y63057D01*
X623417Y62724D01*
X623250Y62474D01*
X623000Y62307D01*
X622667Y62224D01*
X622375Y62307D01*
X622083Y62515D01*
X621917Y62765D01*
X621875Y63057D01*
X621958Y63390D01*
X622167Y63640D01*
X622542Y63890D01*
G01X621000Y66157D02*
X621042Y66449D01*
X621167Y66782D01*
X621375Y66990D01*
X621667Y67074D01*
X621958Y66990D01*
X622208Y66740D01*
X622333Y66365D01*
Y65949D01*
X622417Y65699D01*
X622625Y65490D01*
X622917Y65407D01*
X623208Y65532D01*
X623417Y65824D01*
X623500Y66157D01*
X623417Y66490D01*
X623208Y66782D01*
X622917Y66907D01*
X622625Y66824D01*
X622417Y66615D01*
X622333Y66365D01*
Y65949D01*
X622208Y65574D01*
X621958Y65324D01*
X621667Y65240D01*
X621375Y65324D01*
X621167Y65532D01*
X621042Y65865D01*
X621000Y66157D01*
G01X630500Y163967D02*
X633000D01*
Y164967D01*
X632875Y165300D01*
X632583Y165550D01*
X632250Y165633D01*
X631917Y165550D01*
X631667Y165342D01*
X631542Y164967D01*
Y163967D01*
G01X632792Y168817D02*
X632917Y168567D01*
X633000Y168275D01*
Y167942D01*
X632875Y167567D01*
X632667Y167275D01*
X632417Y167067D01*
X632000Y166900D01*
X631625Y166858D01*
X631250Y166942D01*
X631000Y167067D01*
X630750Y167317D01*
X630583Y167608D01*
X630500Y167900D01*
Y168192D01*
X630583Y168483D01*
X630708Y168733D01*
X630875Y168942D01*
G01X630500Y171000D02*
X633000D01*
X632500Y170500D01*
G01X630500D02*
Y171500D01*
G01X632583Y173308D02*
X632833Y173558D01*
X632958Y173850D01*
X633000Y174183D01*
X632917Y174600D01*
X632708Y174892D01*
X632458Y174975D01*
X632208Y174933D01*
X632000Y174767D01*
X631583Y173933D01*
X631292Y173558D01*
X630875Y173308D01*
X630500Y173225D01*
Y174975D01*
G01Y177200D02*
X633000D01*
X632500Y176700D01*
G01X630500D02*
Y177700D01*
G01X636033Y155000D02*
Y157500D01*
X635033D01*
X634700Y157375D01*
X634450Y157083D01*
X634367Y156750D01*
X634450Y156417D01*
X634658Y156167D01*
X635033Y156042D01*
X636033D01*
G01X631183Y157292D02*
X631433Y157417D01*
X631725Y157500D01*
X632058D01*
X632433Y157375D01*
X632725Y157167D01*
X632933Y156917D01*
X633100Y156500D01*
X633142Y156125D01*
X633058Y155750D01*
X632933Y155500D01*
X632683Y155250D01*
X632392Y155083D01*
X632100Y155000D01*
X631808D01*
X631517Y155083D01*
X631267Y155208D01*
X631058Y155375D01*
G01X629000Y155000D02*
Y157500D01*
X629500Y157000D01*
G01Y155000D02*
X628500D01*
G01X626692Y157083D02*
X626442Y157333D01*
X626150Y157458D01*
X625817Y157500D01*
X625400Y157417D01*
X625108Y157208D01*
X625025Y156958D01*
X625067Y156708D01*
X625233Y156500D01*
X626067Y156083D01*
X626442Y155792D01*
X626692Y155375D01*
X626775Y155000D01*
X625025D01*
G01X622300D02*
Y157500D01*
X623842Y155708D01*
X621758D01*
G01X635933Y159000D02*
Y161500D01*
X634933D01*
X634600Y161375D01*
X634350Y161083D01*
X634267Y160750D01*
X634350Y160417D01*
X634558Y160167D01*
X634933Y160042D01*
X635933D01*
G01X631083Y161292D02*
X631333Y161417D01*
X631625Y161500D01*
X631958D01*
X632333Y161375D01*
X632625Y161167D01*
X632833Y160917D01*
X633000Y160500D01*
X633042Y160125D01*
X632958Y159750D01*
X632833Y159500D01*
X632583Y159250D01*
X632292Y159083D01*
X632000Y159000D01*
X631708D01*
X631417Y159083D01*
X631167Y159208D01*
X630958Y159375D01*
G01X628900Y159000D02*
Y161500D01*
X629400Y161000D01*
G01Y159000D02*
X628400D01*
G01X626592Y161083D02*
X626342Y161333D01*
X626050Y161458D01*
X625717Y161500D01*
X625300Y161417D01*
X625008Y161208D01*
X624925Y160958D01*
X624967Y160708D01*
X625133Y160500D01*
X625967Y160083D01*
X626342Y159792D01*
X626592Y159375D01*
X626675Y159000D01*
X624925D01*
G01X623617Y159500D02*
X623367Y159208D01*
X623033Y159042D01*
X622658Y159000D01*
X622325Y159042D01*
X621992Y159250D01*
X621783Y159500D01*
X621742Y159750D01*
X621825Y160042D01*
X622117Y160250D01*
X622408Y160333D01*
X622783D01*
G01X622408D02*
X622158Y160458D01*
X621950Y160667D01*
X621867Y160917D01*
X621950Y161167D01*
X622158Y161375D01*
X622533Y161500D01*
X622908Y161458D01*
X623283Y161292D01*
G01X622500Y164017D02*
X625000D01*
Y165017D01*
X624875Y165350D01*
X624583Y165600D01*
X624250Y165683D01*
X623917Y165600D01*
X623667Y165392D01*
X623542Y165017D01*
Y164017D01*
G01X625000Y167033D02*
X623208D01*
X622833Y167200D01*
X622583Y167533D01*
X622500Y167950D01*
X622583Y168367D01*
X622833Y168700D01*
X623208Y168867D01*
X625000D01*
G01X622500Y171050D02*
X625000D01*
X624500Y170550D01*
G01X622500D02*
Y171550D01*
G01X623000Y173233D02*
X622708Y173483D01*
X622542Y173817D01*
X622500Y174192D01*
X622542Y174525D01*
X622750Y174858D01*
X623000Y175067D01*
X623250Y175108D01*
X623542Y175025D01*
X623750Y174733D01*
X623833Y174442D01*
Y174067D01*
G01Y174442D02*
X623958Y174692D01*
X624167Y174900D01*
X624417Y174983D01*
X624667Y174900D01*
X624875Y174692D01*
X625000Y174317D01*
X624958Y173942D01*
X624792Y173567D01*
G01X644533Y179500D02*
Y182000D01*
X643533D01*
X643200Y181875D01*
X642950Y181583D01*
X642867Y181250D01*
X642950Y180917D01*
X643158Y180667D01*
X643533Y180542D01*
X644533D01*
G01X641433Y179500D02*
Y182000D01*
X640392D01*
X640058Y181875D01*
X639850Y181708D01*
X639767Y181375D01*
X639850Y181042D01*
X640100Y180833D01*
X640392Y180708D01*
X641433D01*
G01X640392D02*
X639767Y179500D01*
G01X637500D02*
Y182000D01*
X638000Y181500D01*
G01Y179500D02*
X637000D01*
G01X634483D02*
X634400Y180042D01*
X634275Y180500D01*
X634108Y180917D01*
X633900Y181375D01*
X633567Y182000D01*
X635233D01*
G01X631300Y179500D02*
Y182000D01*
X631800Y181500D01*
G01Y179500D02*
X630800D01*
G01X644533Y184500D02*
Y187000D01*
X643533D01*
X643200Y186875D01*
X642950Y186583D01*
X642867Y186250D01*
X642950Y185917D01*
X643158Y185667D01*
X643533Y185542D01*
X644533D01*
G01X641433Y184500D02*
Y187000D01*
X640392D01*
X640058Y186875D01*
X639850Y186708D01*
X639767Y186375D01*
X639850Y186042D01*
X640100Y185833D01*
X640392Y185708D01*
X641433D01*
G01X640392D02*
X639767Y184500D01*
G01X637500D02*
Y187000D01*
X638000Y186500D01*
G01Y184500D02*
X637000D01*
G01X634483D02*
X634400Y185042D01*
X634275Y185500D01*
X634108Y185917D01*
X633900Y186375D01*
X633567Y187000D01*
X635233D01*
G01X632092Y185542D02*
X631800Y185833D01*
X631550Y186000D01*
X631217Y186083D01*
X630925Y186000D01*
X630717Y185833D01*
X630550Y185583D01*
X630508Y185292D01*
X630550Y185042D01*
X630717Y184792D01*
X630967Y184583D01*
X631258Y184500D01*
X631592Y184583D01*
X631883Y184833D01*
X632050Y185208D01*
X632092Y185625D01*
X632008Y186167D01*
X631883Y186458D01*
X631675Y186750D01*
X631383Y186958D01*
X631092Y187000D01*
X630800Y186917D01*
X630592Y186708D01*
G01X628433Y194000D02*
Y196500D01*
X627433D01*
X627100Y196375D01*
X626850Y196083D01*
X626767Y195750D01*
X626850Y195417D01*
X627058Y195167D01*
X627433Y195042D01*
X628433D01*
G01X624250Y195250D02*
X623417D01*
Y194500D01*
X623667Y194250D01*
X623958Y194083D01*
X624375Y194000D01*
X624792Y194083D01*
X625083Y194250D01*
X625333Y194500D01*
X625500Y194792D01*
X625583Y195125D01*
Y195417D01*
X625500Y195667D01*
X625333Y195958D01*
X625083Y196208D01*
X624833Y196375D01*
X624500Y196500D01*
X624208D01*
X623875Y196417D01*
X623625Y196250D01*
G01X622317Y194375D02*
X622067Y194167D01*
X621775Y194042D01*
X621400Y194000D01*
X621025Y194083D01*
X620733Y194250D01*
X620525Y194542D01*
X620483Y194875D01*
X620567Y195208D01*
X620775Y195417D01*
X621067Y195583D01*
X621358Y195625D01*
X621650Y195583D01*
X622025Y195417D01*
X621900Y196500D01*
X620775D01*
G01X626292Y214767D02*
X626417Y214517D01*
X626500Y214225D01*
Y213892D01*
X626375Y213517D01*
X626167Y213225D01*
X625917Y213017D01*
X625500Y212850D01*
X625125Y212808D01*
X624750Y212892D01*
X624500Y213017D01*
X624250Y213267D01*
X624083Y213558D01*
X624000Y213850D01*
Y214142D01*
X624083Y214433D01*
X624208Y214683D01*
X624375Y214892D01*
G01X624500Y216033D02*
X624208Y216283D01*
X624042Y216617D01*
X624000Y216992D01*
X624042Y217325D01*
X624250Y217658D01*
X624500Y217867D01*
X624750Y217908D01*
X625042Y217825D01*
X625250Y217533D01*
X625333Y217242D01*
Y216867D01*
G01Y217242D02*
X625458Y217492D01*
X625667Y217700D01*
X625917Y217783D01*
X626167Y217700D01*
X626375Y217492D01*
X626500Y217117D01*
X626458Y216742D01*
X626292Y216367D01*
G01X624500Y219133D02*
X624208Y219383D01*
X624042Y219717D01*
X624000Y220092D01*
X624042Y220425D01*
X624250Y220758D01*
X624500Y220967D01*
X624750Y221008D01*
X625042Y220925D01*
X625250Y220633D01*
X625333Y220342D01*
Y219967D01*
G01Y220342D02*
X625458Y220592D01*
X625667Y220800D01*
X625917Y220883D01*
X626167Y220800D01*
X626375Y220592D01*
X626500Y220217D01*
X626458Y219842D01*
X626292Y219467D01*
G01X626500Y223150D02*
X626417Y222817D01*
X626208Y222567D01*
X625958Y222400D01*
X625625Y222275D01*
X625250Y222233D01*
X624875Y222275D01*
X624542Y222400D01*
X624292Y222567D01*
X624083Y222817D01*
X624000Y223150D01*
X624083Y223483D01*
X624292Y223733D01*
X624542Y223900D01*
X624875Y224025D01*
X625250Y224067D01*
X625625Y224025D01*
X625958Y223900D01*
X626208Y223733D01*
X626417Y223483D01*
X626500Y223150D01*
G01X630292Y214767D02*
X630417Y214517D01*
X630500Y214225D01*
Y213892D01*
X630375Y213517D01*
X630167Y213225D01*
X629917Y213017D01*
X629500Y212850D01*
X629125Y212808D01*
X628750Y212892D01*
X628500Y213017D01*
X628250Y213267D01*
X628083Y213558D01*
X628000Y213850D01*
Y214142D01*
X628083Y214433D01*
X628208Y214683D01*
X628375Y214892D01*
G01X628500Y216033D02*
X628208Y216283D01*
X628042Y216617D01*
X628000Y216992D01*
X628042Y217325D01*
X628250Y217658D01*
X628500Y217867D01*
X628750Y217908D01*
X629042Y217825D01*
X629250Y217533D01*
X629333Y217242D01*
Y216867D01*
G01Y217242D02*
X629458Y217492D01*
X629667Y217700D01*
X629917Y217783D01*
X630167Y217700D01*
X630375Y217492D01*
X630500Y217117D01*
X630458Y216742D01*
X630292Y216367D01*
G01X630083Y219258D02*
X630333Y219508D01*
X630458Y219800D01*
X630500Y220133D01*
X630417Y220550D01*
X630208Y220842D01*
X629958Y220925D01*
X629708Y220883D01*
X629500Y220717D01*
X629083Y219883D01*
X628792Y219508D01*
X628375Y219258D01*
X628000Y219175D01*
Y220925D01*
G01X628375Y222233D02*
X628167Y222483D01*
X628042Y222775D01*
X628000Y223150D01*
X628083Y223525D01*
X628250Y223817D01*
X628542Y224025D01*
X628875Y224067D01*
X629208Y223983D01*
X629417Y223775D01*
X629583Y223483D01*
X629625Y223192D01*
X629583Y222900D01*
X629417Y222525D01*
X630500Y222650D01*
Y223775D01*
G01X634292Y214767D02*
X634417Y214517D01*
X634500Y214225D01*
Y213892D01*
X634375Y213517D01*
X634167Y213225D01*
X633917Y213017D01*
X633500Y212850D01*
X633125Y212808D01*
X632750Y212892D01*
X632500Y213017D01*
X632250Y213267D01*
X632083Y213558D01*
X632000Y213850D01*
Y214142D01*
X632083Y214433D01*
X632208Y214683D01*
X632375Y214892D01*
G01X632000Y216950D02*
X634500D01*
X634000Y216450D01*
G01X632000D02*
Y217450D01*
G01X634500Y220050D02*
X634417Y219717D01*
X634208Y219467D01*
X633958Y219300D01*
X633625Y219175D01*
X633250Y219133D01*
X632875Y219175D01*
X632542Y219300D01*
X632292Y219467D01*
X632083Y219717D01*
X632000Y220050D01*
X632083Y220383D01*
X632292Y220633D01*
X632542Y220800D01*
X632875Y220925D01*
X633250Y220967D01*
X633625Y220925D01*
X633958Y220800D01*
X634208Y220633D01*
X634417Y220383D01*
X634500Y220050D01*
G01X632000Y223150D02*
X632042Y223442D01*
X632167Y223775D01*
X632375Y223983D01*
X632667Y224067D01*
X632958Y223983D01*
X633208Y223733D01*
X633333Y223358D01*
Y222942D01*
X633417Y222692D01*
X633625Y222483D01*
X633917Y222400D01*
X634208Y222525D01*
X634417Y222817D01*
X634500Y223150D01*
X634417Y223483D01*
X634208Y223775D01*
X633917Y223900D01*
X633625Y223817D01*
X633417Y223608D01*
X633333Y223358D01*
Y222942D01*
X633208Y222567D01*
X632958Y222317D01*
X632667Y222233D01*
X632375Y222317D01*
X632167Y222525D01*
X632042Y222858D01*
X632000Y223150D01*
G01X622292Y217817D02*
X622417Y217567D01*
X622500Y217275D01*
Y216942D01*
X622375Y216567D01*
X622167Y216275D01*
X621917Y216067D01*
X621500Y215900D01*
X621125Y215858D01*
X620750Y215942D01*
X620500Y216067D01*
X620250Y216317D01*
X620083Y216608D01*
X620000Y216900D01*
Y217192D01*
X620083Y217483D01*
X620208Y217733D01*
X620375Y217942D01*
G01X620292Y219292D02*
X620083Y219583D01*
X620000Y219917D01*
X620083Y220250D01*
X620333Y220542D01*
X620708Y220750D01*
X621083Y220833D01*
X621542D01*
X621917Y220750D01*
X622250Y220542D01*
X622417Y220292D01*
X622500Y220000D01*
X622417Y219667D01*
X622250Y219417D01*
X622000Y219250D01*
X621667Y219167D01*
X621375Y219250D01*
X621083Y219458D01*
X620917Y219708D01*
X620875Y220000D01*
X620958Y220333D01*
X621167Y220583D01*
X621542Y220833D01*
G01X620292Y222392D02*
X620083Y222683D01*
X620000Y223017D01*
X620083Y223350D01*
X620333Y223642D01*
X620708Y223850D01*
X621083Y223933D01*
X621542D01*
X621917Y223850D01*
X622250Y223642D01*
X622417Y223392D01*
X622500Y223100D01*
X622417Y222767D01*
X622250Y222517D01*
X622000Y222350D01*
X621667Y222267D01*
X621375Y222350D01*
X621083Y222558D01*
X620917Y222808D01*
X620875Y223100D01*
X620958Y223433D01*
X621167Y223683D01*
X621542Y223933D01*
G01X629233Y287292D02*
X629483Y287417D01*
X629775Y287500D01*
X630108D01*
X630483Y287375D01*
X630775Y287167D01*
X630983Y286917D01*
X631150Y286500D01*
X631192Y286125D01*
X631108Y285750D01*
X630983Y285500D01*
X630733Y285250D01*
X630442Y285083D01*
X630150Y285000D01*
X629858D01*
X629567Y285083D01*
X629317Y285208D01*
X629108Y285375D01*
G01X627050Y285000D02*
Y287500D01*
X627550Y287000D01*
G01Y285000D02*
X626550D01*
G01X623950Y287500D02*
X624283Y287417D01*
X624533Y287208D01*
X624700Y286958D01*
X624825Y286625D01*
X624867Y286250D01*
X624825Y285875D01*
X624700Y285542D01*
X624533Y285292D01*
X624283Y285083D01*
X623950Y285000D01*
X623617Y285083D01*
X623367Y285292D01*
X623200Y285542D01*
X623075Y285875D01*
X623033Y286250D01*
X623075Y286625D01*
X623200Y286958D01*
X623367Y287208D01*
X623617Y287417D01*
X623950Y287500D01*
G01X621558Y285292D02*
X621267Y285083D01*
X620933Y285000D01*
X620600Y285083D01*
X620308Y285333D01*
X620100Y285708D01*
X620017Y286083D01*
Y286542D01*
X620100Y286917D01*
X620308Y287250D01*
X620558Y287417D01*
X620850Y287500D01*
X621183Y287417D01*
X621433Y287250D01*
X621600Y287000D01*
X621683Y286667D01*
X621600Y286375D01*
X621392Y286083D01*
X621142Y285917D01*
X620850Y285875D01*
X620517Y285958D01*
X620267Y286167D01*
X620017Y286542D01*
G01X637292Y55274D02*
X637417Y55024D01*
X637500Y54732D01*
Y54399D01*
X637375Y54024D01*
X637167Y53732D01*
X636917Y53524D01*
X636500Y53357D01*
X636125Y53315D01*
X635750Y53399D01*
X635500Y53524D01*
X635250Y53774D01*
X635083Y54065D01*
X635000Y54357D01*
Y54649D01*
X635083Y54940D01*
X635208Y55190D01*
X635375Y55399D01*
G01X635500Y56540D02*
X635208Y56790D01*
X635042Y57124D01*
X635000Y57499D01*
X635042Y57832D01*
X635250Y58165D01*
X635500Y58374D01*
X635750Y58415D01*
X636042Y58332D01*
X636250Y58040D01*
X636333Y57749D01*
Y57374D01*
G01Y57749D02*
X636458Y57999D01*
X636667Y58207D01*
X636917Y58290D01*
X637167Y58207D01*
X637375Y57999D01*
X637500Y57624D01*
X637458Y57249D01*
X637292Y56874D01*
G01X635500Y59640D02*
X635208Y59890D01*
X635042Y60224D01*
X635000Y60599D01*
X635042Y60932D01*
X635250Y61265D01*
X635500Y61474D01*
X635750Y61515D01*
X636042Y61432D01*
X636250Y61140D01*
X636333Y60849D01*
Y60474D01*
G01Y60849D02*
X636458Y61099D01*
X636667Y61307D01*
X636917Y61390D01*
X637167Y61307D01*
X637375Y61099D01*
X637500Y60724D01*
X637458Y60349D01*
X637292Y59974D01*
G01X635500Y62740D02*
X635208Y62990D01*
X635042Y63324D01*
X635000Y63699D01*
X635042Y64032D01*
X635250Y64365D01*
X635500Y64574D01*
X635750Y64615D01*
X636042Y64532D01*
X636250Y64240D01*
X636333Y63949D01*
Y63574D01*
G01Y63949D02*
X636458Y64199D01*
X636667Y64407D01*
X636917Y64490D01*
X637167Y64407D01*
X637375Y64199D01*
X637500Y63824D01*
X637458Y63449D01*
X637292Y63074D01*
G01X651792Y57274D02*
X651917Y57024D01*
X652000Y56732D01*
Y56399D01*
X651875Y56024D01*
X651667Y55732D01*
X651417Y55524D01*
X651000Y55357D01*
X650625Y55315D01*
X650250Y55399D01*
X650000Y55524D01*
X649750Y55774D01*
X649583Y56065D01*
X649500Y56357D01*
Y56649D01*
X649583Y56940D01*
X649708Y57190D01*
X649875Y57399D01*
G01X650000Y58540D02*
X649708Y58790D01*
X649542Y59124D01*
X649500Y59499D01*
X649542Y59832D01*
X649750Y60165D01*
X650000Y60374D01*
X650250Y60415D01*
X650542Y60332D01*
X650750Y60040D01*
X650833Y59749D01*
Y59374D01*
G01Y59749D02*
X650958Y59999D01*
X651167Y60207D01*
X651417Y60290D01*
X651667Y60207D01*
X651875Y59999D01*
X652000Y59624D01*
X651958Y59249D01*
X651792Y58874D01*
G01X652000Y62557D02*
X651917Y62224D01*
X651708Y61974D01*
X651458Y61807D01*
X651125Y61682D01*
X650750Y61640D01*
X650375Y61682D01*
X650042Y61807D01*
X649792Y61974D01*
X649583Y62224D01*
X649500Y62557D01*
X649583Y62890D01*
X649792Y63140D01*
X650042Y63307D01*
X650375Y63432D01*
X650750Y63474D01*
X651125Y63432D01*
X651458Y63307D01*
X651708Y63140D01*
X651917Y62890D01*
X652000Y62557D01*
G01X649500Y65657D02*
X652000D01*
X651500Y65157D01*
G01X649500D02*
Y66157D01*
G01X641292Y55274D02*
X641417Y55024D01*
X641500Y54732D01*
Y54399D01*
X641375Y54024D01*
X641167Y53732D01*
X640917Y53524D01*
X640500Y53357D01*
X640125Y53315D01*
X639750Y53399D01*
X639500Y53524D01*
X639250Y53774D01*
X639083Y54065D01*
X639000Y54357D01*
Y54649D01*
X639083Y54940D01*
X639208Y55190D01*
X639375Y55399D01*
G01X641083Y56665D02*
X641333Y56915D01*
X641458Y57207D01*
X641500Y57540D01*
X641417Y57957D01*
X641208Y58249D01*
X640958Y58332D01*
X640708Y58290D01*
X640500Y58124D01*
X640083Y57290D01*
X639792Y56915D01*
X639375Y56665D01*
X639000Y56582D01*
Y58332D01*
G01X639292Y59849D02*
X639083Y60140D01*
X639000Y60474D01*
X639083Y60807D01*
X639333Y61099D01*
X639708Y61307D01*
X640083Y61390D01*
X640542D01*
X640917Y61307D01*
X641250Y61099D01*
X641417Y60849D01*
X641500Y60557D01*
X641417Y60224D01*
X641250Y59974D01*
X641000Y59807D01*
X640667Y59724D01*
X640375Y59807D01*
X640083Y60015D01*
X639917Y60265D01*
X639875Y60557D01*
X639958Y60890D01*
X640167Y61140D01*
X640542Y61390D01*
G01X639500Y62740D02*
X639208Y62990D01*
X639042Y63324D01*
X639000Y63699D01*
X639042Y64032D01*
X639250Y64365D01*
X639500Y64574D01*
X639750Y64615D01*
X640042Y64532D01*
X640250Y64240D01*
X640333Y63949D01*
Y63574D01*
G01Y63949D02*
X640458Y64199D01*
X640667Y64407D01*
X640917Y64490D01*
X641167Y64407D01*
X641375Y64199D01*
X641500Y63824D01*
X641458Y63449D01*
X641292Y63074D01*
G01X649792Y230267D02*
X649917Y230017D01*
X650000Y229725D01*
Y229392D01*
X649875Y229017D01*
X649667Y228725D01*
X649417Y228517D01*
X649000Y228350D01*
X648625Y228308D01*
X648250Y228392D01*
X648000Y228517D01*
X647750Y228767D01*
X647583Y229058D01*
X647500Y229350D01*
Y229642D01*
X647583Y229933D01*
X647708Y230183D01*
X647875Y230392D01*
G01X648000Y231533D02*
X647708Y231783D01*
X647542Y232117D01*
X647500Y232492D01*
X647542Y232825D01*
X647750Y233158D01*
X648000Y233367D01*
X648250Y233408D01*
X648542Y233325D01*
X648750Y233033D01*
X648833Y232742D01*
Y232367D01*
G01Y232742D02*
X648958Y232992D01*
X649167Y233200D01*
X649417Y233283D01*
X649667Y233200D01*
X649875Y232992D01*
X650000Y232617D01*
X649958Y232242D01*
X649792Y231867D01*
G01X648542Y234758D02*
X648833Y235050D01*
X649000Y235300D01*
X649083Y235633D01*
X649000Y235925D01*
X648833Y236133D01*
X648583Y236300D01*
X648292Y236342D01*
X648042Y236300D01*
X647792Y236133D01*
X647583Y235883D01*
X647500Y235592D01*
X647583Y235258D01*
X647833Y234967D01*
X648208Y234800D01*
X648625Y234758D01*
X649167Y234842D01*
X649458Y234967D01*
X649750Y235175D01*
X649958Y235467D01*
X650000Y235758D01*
X649917Y236050D01*
X649708Y236258D01*
G01X647500Y238650D02*
X650000D01*
X649500Y238150D01*
G01X647500D02*
Y239150D01*
G01X661792Y57274D02*
X661917Y57024D01*
X662000Y56732D01*
Y56399D01*
X661875Y56024D01*
X661667Y55732D01*
X661417Y55524D01*
X661000Y55357D01*
X660625Y55315D01*
X660250Y55399D01*
X660000Y55524D01*
X659750Y55774D01*
X659583Y56065D01*
X659500Y56357D01*
Y56649D01*
X659583Y56940D01*
X659708Y57190D01*
X659875Y57399D01*
G01X661583Y58665D02*
X661833Y58915D01*
X661958Y59207D01*
X662000Y59540D01*
X661917Y59957D01*
X661708Y60249D01*
X661458Y60332D01*
X661208Y60290D01*
X661000Y60124D01*
X660583Y59290D01*
X660292Y58915D01*
X659875Y58665D01*
X659500Y58582D01*
Y60332D01*
G01X659792Y61849D02*
X659583Y62140D01*
X659500Y62474D01*
X659583Y62807D01*
X659833Y63099D01*
X660208Y63307D01*
X660583Y63390D01*
X661042D01*
X661417Y63307D01*
X661750Y63099D01*
X661917Y62849D01*
X662000Y62557D01*
X661917Y62224D01*
X661750Y61974D01*
X661500Y61807D01*
X661167Y61724D01*
X660875Y61807D01*
X660583Y62015D01*
X660417Y62265D01*
X660375Y62557D01*
X660458Y62890D01*
X660667Y63140D01*
X661042Y63390D01*
G01X659500Y65574D02*
X660042Y65657D01*
X660500Y65782D01*
X660917Y65949D01*
X661375Y66157D01*
X662000Y66490D01*
Y64824D01*
G01X657792Y57274D02*
X657917Y57024D01*
X658000Y56732D01*
Y56399D01*
X657875Y56024D01*
X657667Y55732D01*
X657417Y55524D01*
X657000Y55357D01*
X656625Y55315D01*
X656250Y55399D01*
X656000Y55524D01*
X655750Y55774D01*
X655583Y56065D01*
X655500Y56357D01*
Y56649D01*
X655583Y56940D01*
X655708Y57190D01*
X655875Y57399D01*
G01X656000Y58540D02*
X655708Y58790D01*
X655542Y59124D01*
X655500Y59499D01*
X655542Y59832D01*
X655750Y60165D01*
X656000Y60374D01*
X656250Y60415D01*
X656542Y60332D01*
X656750Y60040D01*
X656833Y59749D01*
Y59374D01*
G01Y59749D02*
X656958Y59999D01*
X657167Y60207D01*
X657417Y60290D01*
X657667Y60207D01*
X657875Y59999D01*
X658000Y59624D01*
X657958Y59249D01*
X657792Y58874D01*
G01X655500Y63057D02*
X658000D01*
X656208Y61515D01*
Y63599D01*
G01X658000Y65657D02*
X657917Y65324D01*
X657708Y65074D01*
X657458Y64907D01*
X657125Y64782D01*
X656750Y64740D01*
X656375Y64782D01*
X656042Y64907D01*
X655792Y65074D01*
X655583Y65324D01*
X655500Y65657D01*
X655583Y65990D01*
X655792Y66240D01*
X656042Y66407D01*
X656375Y66532D01*
X656750Y66574D01*
X657125Y66532D01*
X657458Y66407D01*
X657708Y66240D01*
X657917Y65990D01*
X658000Y65657D01*
G01X665792Y57274D02*
X665917Y57024D01*
X666000Y56732D01*
Y56399D01*
X665875Y56024D01*
X665667Y55732D01*
X665417Y55524D01*
X665000Y55357D01*
X664625Y55315D01*
X664250Y55399D01*
X664000Y55524D01*
X663750Y55774D01*
X663583Y56065D01*
X663500Y56357D01*
Y56649D01*
X663583Y56940D01*
X663708Y57190D01*
X663875Y57399D01*
G01X664000Y58540D02*
X663708Y58790D01*
X663542Y59124D01*
X663500Y59499D01*
X663542Y59832D01*
X663750Y60165D01*
X664000Y60374D01*
X664250Y60415D01*
X664542Y60332D01*
X664750Y60040D01*
X664833Y59749D01*
Y59374D01*
G01Y59749D02*
X664958Y59999D01*
X665167Y60207D01*
X665417Y60290D01*
X665667Y60207D01*
X665875Y59999D01*
X666000Y59624D01*
X665958Y59249D01*
X665792Y58874D01*
G01X664000Y61640D02*
X663708Y61890D01*
X663542Y62224D01*
X663500Y62599D01*
X663542Y62932D01*
X663750Y63265D01*
X664000Y63474D01*
X664250Y63515D01*
X664542Y63432D01*
X664750Y63140D01*
X664833Y62849D01*
Y62474D01*
G01Y62849D02*
X664958Y63099D01*
X665167Y63307D01*
X665417Y63390D01*
X665667Y63307D01*
X665875Y63099D01*
X666000Y62724D01*
X665958Y62349D01*
X665792Y61974D01*
G01X665583Y64865D02*
X665833Y65115D01*
X665958Y65407D01*
X666000Y65740D01*
X665917Y66157D01*
X665708Y66449D01*
X665458Y66532D01*
X665208Y66490D01*
X665000Y66324D01*
X664583Y65490D01*
X664292Y65115D01*
X663875Y64865D01*
X663500Y64782D01*
Y66532D01*
G01X675033Y165900D02*
Y168400D01*
X674033D01*
X673700Y168275D01*
X673450Y167983D01*
X673367Y167650D01*
X673450Y167317D01*
X673658Y167067D01*
X674033Y166942D01*
X675033D01*
G01X671933Y165900D02*
Y168400D01*
X670892D01*
X670558Y168275D01*
X670350Y168108D01*
X670267Y167775D01*
X670350Y167442D01*
X670600Y167233D01*
X670892Y167108D01*
X671933D01*
G01X670892D02*
X670267Y165900D01*
G01X668792Y167983D02*
X668542Y168233D01*
X668250Y168358D01*
X667917Y168400D01*
X667500Y168317D01*
X667208Y168108D01*
X667125Y167858D01*
X667167Y167608D01*
X667333Y167400D01*
X668167Y166983D01*
X668542Y166692D01*
X668792Y166275D01*
X668875Y165900D01*
X667125D01*
G01X665692Y167983D02*
X665442Y168233D01*
X665150Y168358D01*
X664817Y168400D01*
X664400Y168317D01*
X664108Y168108D01*
X664025Y167858D01*
X664067Y167608D01*
X664233Y167400D01*
X665067Y166983D01*
X665442Y166692D01*
X665692Y166275D01*
X665775Y165900D01*
X664025D01*
G01X662717Y166275D02*
X662467Y166067D01*
X662175Y165942D01*
X661800Y165900D01*
X661425Y165983D01*
X661133Y166150D01*
X660925Y166442D01*
X660883Y166775D01*
X660967Y167108D01*
X661175Y167317D01*
X661467Y167483D01*
X661758Y167525D01*
X662050Y167483D01*
X662425Y167317D01*
X662300Y168400D01*
X661175D01*
G01X652500Y156467D02*
X655000D01*
Y157467D01*
X654875Y157800D01*
X654583Y158050D01*
X654250Y158133D01*
X653917Y158050D01*
X653667Y157842D01*
X653542Y157467D01*
Y156467D01*
G01X654792Y161317D02*
X654917Y161067D01*
X655000Y160775D01*
Y160442D01*
X654875Y160067D01*
X654667Y159775D01*
X654417Y159567D01*
X654000Y159400D01*
X653625Y159358D01*
X653250Y159442D01*
X653000Y159567D01*
X652750Y159817D01*
X652583Y160108D01*
X652500Y160400D01*
Y160692D01*
X652583Y160983D01*
X652708Y161233D01*
X652875Y161442D01*
G01X652500Y163500D02*
X655000D01*
X654500Y163000D01*
G01X652500D02*
Y164000D01*
G01X654583Y165808D02*
X654833Y166058D01*
X654958Y166350D01*
X655000Y166683D01*
X654917Y167100D01*
X654708Y167392D01*
X654458Y167475D01*
X654208Y167433D01*
X654000Y167267D01*
X653583Y166433D01*
X653292Y166058D01*
X652875Y165808D01*
X652500Y165725D01*
Y167475D01*
G01X655000Y169700D02*
X654917Y169367D01*
X654708Y169117D01*
X654458Y168950D01*
X654125Y168825D01*
X653750Y168783D01*
X653375Y168825D01*
X653042Y168950D01*
X652792Y169117D01*
X652583Y169367D01*
X652500Y169700D01*
X652583Y170033D01*
X652792Y170283D01*
X653042Y170450D01*
X653375Y170575D01*
X653750Y170617D01*
X654125Y170575D01*
X654458Y170450D01*
X654708Y170283D01*
X654917Y170033D01*
X655000Y169700D01*
G01X674833Y156400D02*
Y158900D01*
X673833D01*
X673500Y158775D01*
X673250Y158483D01*
X673167Y158150D01*
X673250Y157817D01*
X673458Y157567D01*
X673833Y157442D01*
X674833D01*
G01X669983Y158692D02*
X670233Y158817D01*
X670525Y158900D01*
X670858D01*
X671233Y158775D01*
X671525Y158567D01*
X671733Y158317D01*
X671900Y157900D01*
X671942Y157525D01*
X671858Y157150D01*
X671733Y156900D01*
X671483Y156650D01*
X671192Y156483D01*
X670900Y156400D01*
X670608D01*
X670317Y156483D01*
X670067Y156608D01*
X669858Y156775D01*
G01X668592Y158483D02*
X668342Y158733D01*
X668050Y158858D01*
X667717Y158900D01*
X667300Y158817D01*
X667008Y158608D01*
X666925Y158358D01*
X666967Y158108D01*
X667133Y157900D01*
X667967Y157483D01*
X668342Y157192D01*
X668592Y156775D01*
X668675Y156400D01*
X666925D01*
G01X664700Y158900D02*
X665033Y158817D01*
X665283Y158608D01*
X665450Y158358D01*
X665575Y158025D01*
X665617Y157650D01*
X665575Y157275D01*
X665450Y156942D01*
X665283Y156692D01*
X665033Y156483D01*
X664700Y156400D01*
X664367Y156483D01*
X664117Y156692D01*
X663950Y156942D01*
X663825Y157275D01*
X663783Y157650D01*
X663825Y158025D01*
X663950Y158358D01*
X664117Y158608D01*
X664367Y158817D01*
X664700Y158900D01*
G01X661600D02*
X661933Y158817D01*
X662183Y158608D01*
X662350Y158358D01*
X662475Y158025D01*
X662517Y157650D01*
X662475Y157275D01*
X662350Y156942D01*
X662183Y156692D01*
X661933Y156483D01*
X661600Y156400D01*
X661267Y156483D01*
X661017Y156692D01*
X660850Y156942D01*
X660725Y157275D01*
X660683Y157650D01*
X660725Y158025D01*
X660850Y158358D01*
X661017Y158608D01*
X661267Y158817D01*
X661600Y158900D01*
G01X675033Y161100D02*
Y163600D01*
X674033D01*
X673700Y163475D01*
X673450Y163183D01*
X673367Y162850D01*
X673450Y162517D01*
X673658Y162267D01*
X674033Y162142D01*
X675033D01*
G01X670183Y163392D02*
X670433Y163517D01*
X670725Y163600D01*
X671058D01*
X671433Y163475D01*
X671725Y163267D01*
X671933Y163017D01*
X672100Y162600D01*
X672142Y162225D01*
X672058Y161850D01*
X671933Y161600D01*
X671683Y161350D01*
X671392Y161183D01*
X671100Y161100D01*
X670808D01*
X670517Y161183D01*
X670267Y161308D01*
X670058Y161475D01*
G01X668000Y161100D02*
Y163600D01*
X668500Y163100D01*
G01Y161100D02*
X667500D01*
G01X665608Y161392D02*
X665317Y161183D01*
X664983Y161100D01*
X664650Y161183D01*
X664358Y161433D01*
X664150Y161808D01*
X664067Y162183D01*
Y162642D01*
X664150Y163017D01*
X664358Y163350D01*
X664608Y163517D01*
X664900Y163600D01*
X665233Y163517D01*
X665483Y163350D01*
X665650Y163100D01*
X665733Y162767D01*
X665650Y162475D01*
X665442Y162183D01*
X665192Y162017D01*
X664900Y161975D01*
X664567Y162058D01*
X664317Y162267D01*
X664067Y162642D01*
G01X661800Y161100D02*
X661508Y161142D01*
X661175Y161267D01*
X660967Y161475D01*
X660883Y161767D01*
X660967Y162058D01*
X661217Y162308D01*
X661592Y162433D01*
X662008D01*
X662258Y162517D01*
X662467Y162725D01*
X662550Y163017D01*
X662425Y163308D01*
X662133Y163517D01*
X661800Y163600D01*
X661467Y163517D01*
X661175Y163308D01*
X661050Y163017D01*
X661133Y162725D01*
X661342Y162517D01*
X661592Y162433D01*
X662008D01*
X662383Y162308D01*
X662633Y162058D01*
X662717Y161767D01*
X662633Y161475D01*
X662425Y161267D01*
X662092Y161142D01*
X661800Y161100D01*
G01X664533Y181500D02*
Y184000D01*
X663533D01*
X663200Y183875D01*
X662950Y183583D01*
X662867Y183250D01*
X662950Y182917D01*
X663158Y182667D01*
X663533Y182542D01*
X664533D01*
G01X661433Y181500D02*
Y184000D01*
X660392D01*
X660058Y183875D01*
X659850Y183708D01*
X659767Y183375D01*
X659850Y183042D01*
X660100Y182833D01*
X660392Y182708D01*
X661433D01*
G01X660392D02*
X659767Y181500D01*
G01X657500D02*
Y184000D01*
X658000Y183500D01*
G01Y181500D02*
X657000D01*
G01X654483D02*
X654400Y182042D01*
X654275Y182500D01*
X654108Y182917D01*
X653900Y183375D01*
X653567Y184000D01*
X655233D01*
G01X652217Y182000D02*
X651967Y181708D01*
X651633Y181542D01*
X651258Y181500D01*
X650925Y181542D01*
X650592Y181750D01*
X650383Y182000D01*
X650342Y182250D01*
X650425Y182542D01*
X650717Y182750D01*
X651008Y182833D01*
X651383D01*
G01X651008D02*
X650758Y182958D01*
X650550Y183167D01*
X650467Y183417D01*
X650550Y183667D01*
X650758Y183875D01*
X651133Y184000D01*
X651508Y183958D01*
X651883Y183792D01*
G01X664983Y194000D02*
Y196500D01*
X663942D01*
X663608Y196375D01*
X663400Y196208D01*
X663317Y195875D01*
X663400Y195542D01*
X663650Y195333D01*
X663942Y195208D01*
X664983D01*
G01X663942D02*
X663317Y194000D01*
G01X661967Y194500D02*
X661717Y194208D01*
X661383Y194042D01*
X661008Y194000D01*
X660675Y194042D01*
X660342Y194250D01*
X660133Y194500D01*
X660092Y194750D01*
X660175Y195042D01*
X660467Y195250D01*
X660758Y195333D01*
X661133D01*
G01X660758D02*
X660508Y195458D01*
X660300Y195667D01*
X660217Y195917D01*
X660300Y196167D01*
X660508Y196375D01*
X660883Y196500D01*
X661258Y196458D01*
X661633Y196292D01*
G01X658033Y194000D02*
X657950Y194542D01*
X657825Y195000D01*
X657658Y195417D01*
X657450Y195875D01*
X657117Y196500D01*
X658783D01*
G01X655767Y194375D02*
X655517Y194167D01*
X655225Y194042D01*
X654850Y194000D01*
X654475Y194083D01*
X654183Y194250D01*
X653975Y194542D01*
X653933Y194875D01*
X654017Y195208D01*
X654225Y195417D01*
X654517Y195583D01*
X654808Y195625D01*
X655100Y195583D01*
X655475Y195417D01*
X655350Y196500D01*
X654225D01*
G01X664533Y186000D02*
Y188500D01*
X663533D01*
X663200Y188375D01*
X662950Y188083D01*
X662867Y187750D01*
X662950Y187417D01*
X663158Y187167D01*
X663533Y187042D01*
X664533D01*
G01X661433Y186000D02*
Y188500D01*
X660392D01*
X660058Y188375D01*
X659850Y188208D01*
X659767Y187875D01*
X659850Y187542D01*
X660100Y187333D01*
X660392Y187208D01*
X661433D01*
G01X660392D02*
X659767Y186000D01*
G01X657500D02*
Y188500D01*
X658000Y188000D01*
G01Y186000D02*
X657000D01*
G01X654483D02*
X654400Y186542D01*
X654275Y187000D01*
X654108Y187417D01*
X653900Y187875D01*
X653567Y188500D01*
X655233D01*
G01X652092Y188083D02*
X651842Y188333D01*
X651550Y188458D01*
X651217Y188500D01*
X650800Y188417D01*
X650508Y188208D01*
X650425Y187958D01*
X650467Y187708D01*
X650633Y187500D01*
X651467Y187083D01*
X651842Y186792D01*
X652092Y186375D01*
X652175Y186000D01*
X650425D01*
G01X653792Y230267D02*
X653917Y230017D01*
X654000Y229725D01*
Y229392D01*
X653875Y229017D01*
X653667Y228725D01*
X653417Y228517D01*
X653000Y228350D01*
X652625Y228308D01*
X652250Y228392D01*
X652000Y228517D01*
X651750Y228767D01*
X651583Y229058D01*
X651500Y229350D01*
Y229642D01*
X651583Y229933D01*
X651708Y230183D01*
X651875Y230392D01*
G01X652000Y231533D02*
X651708Y231783D01*
X651542Y232117D01*
X651500Y232492D01*
X651542Y232825D01*
X651750Y233158D01*
X652000Y233367D01*
X652250Y233408D01*
X652542Y233325D01*
X652750Y233033D01*
X652833Y232742D01*
Y232367D01*
G01Y232742D02*
X652958Y232992D01*
X653167Y233200D01*
X653417Y233283D01*
X653667Y233200D01*
X653875Y232992D01*
X654000Y232617D01*
X653958Y232242D01*
X653792Y231867D01*
G01X652542Y234758D02*
X652833Y235050D01*
X653000Y235300D01*
X653083Y235633D01*
X653000Y235925D01*
X652833Y236133D01*
X652583Y236300D01*
X652292Y236342D01*
X652042Y236300D01*
X651792Y236133D01*
X651583Y235883D01*
X651500Y235592D01*
X651583Y235258D01*
X651833Y234967D01*
X652208Y234800D01*
X652625Y234758D01*
X653167Y234842D01*
X653458Y234967D01*
X653750Y235175D01*
X653958Y235467D01*
X654000Y235758D01*
X653917Y236050D01*
X653708Y236258D01*
G01X653583Y237858D02*
X653833Y238108D01*
X653958Y238400D01*
X654000Y238733D01*
X653917Y239150D01*
X653708Y239442D01*
X653458Y239525D01*
X653208Y239483D01*
X653000Y239317D01*
X652583Y238483D01*
X652292Y238108D01*
X651875Y237858D01*
X651500Y237775D01*
Y239525D01*
G01X677500Y155467D02*
X680000D01*
Y156467D01*
X679875Y156800D01*
X679583Y157050D01*
X679250Y157133D01*
X678917Y157050D01*
X678667Y156842D01*
X678542Y156467D01*
Y155467D01*
G01X679792Y160317D02*
X679917Y160067D01*
X680000Y159775D01*
Y159442D01*
X679875Y159067D01*
X679667Y158775D01*
X679417Y158567D01*
X679000Y158400D01*
X678625Y158358D01*
X678250Y158442D01*
X678000Y158567D01*
X677750Y158817D01*
X677583Y159108D01*
X677500Y159400D01*
Y159692D01*
X677583Y159983D01*
X677708Y160233D01*
X677875Y160442D01*
G01X679583Y161708D02*
X679833Y161958D01*
X679958Y162250D01*
X680000Y162583D01*
X679917Y163000D01*
X679708Y163292D01*
X679458Y163375D01*
X679208Y163333D01*
X679000Y163167D01*
X678583Y162333D01*
X678292Y161958D01*
X677875Y161708D01*
X677500Y161625D01*
Y163375D01*
G01X680000Y165600D02*
X679917Y165267D01*
X679708Y165017D01*
X679458Y164850D01*
X679125Y164725D01*
X678750Y164683D01*
X678375Y164725D01*
X678042Y164850D01*
X677792Y165017D01*
X677583Y165267D01*
X677500Y165600D01*
X677583Y165933D01*
X677792Y166183D01*
X678042Y166350D01*
X678375Y166475D01*
X678750Y166517D01*
X679125Y166475D01*
X679458Y166350D01*
X679708Y166183D01*
X679917Y165933D01*
X680000Y165600D01*
G01X677875Y167783D02*
X677667Y168033D01*
X677542Y168325D01*
X677500Y168700D01*
X677583Y169075D01*
X677750Y169367D01*
X678042Y169575D01*
X678375Y169617D01*
X678708Y169533D01*
X678917Y169325D01*
X679083Y169033D01*
X679125Y168742D01*
X679083Y168450D01*
X678917Y168075D01*
X680000Y168200D01*
Y169325D01*
G01X686533Y174500D02*
Y177000D01*
X685533D01*
X685200Y176875D01*
X684950Y176583D01*
X684867Y176250D01*
X684950Y175917D01*
X685158Y175667D01*
X685533Y175542D01*
X686533D01*
G01X681683Y176792D02*
X681933Y176917D01*
X682225Y177000D01*
X682558D01*
X682933Y176875D01*
X683225Y176667D01*
X683433Y176417D01*
X683600Y176000D01*
X683642Y175625D01*
X683558Y175250D01*
X683433Y175000D01*
X683183Y174750D01*
X682892Y174583D01*
X682600Y174500D01*
X682308D01*
X682017Y174583D01*
X681767Y174708D01*
X681558Y174875D01*
G01X679500Y174500D02*
Y177000D01*
X680000Y176500D01*
G01Y174500D02*
X679000D01*
G01X677108Y174792D02*
X676817Y174583D01*
X676483Y174500D01*
X676150Y174583D01*
X675858Y174833D01*
X675650Y175208D01*
X675567Y175583D01*
Y176042D01*
X675650Y176417D01*
X675858Y176750D01*
X676108Y176917D01*
X676400Y177000D01*
X676733Y176917D01*
X676983Y176750D01*
X677150Y176500D01*
X677233Y176167D01*
X677150Y175875D01*
X676942Y175583D01*
X676692Y175417D01*
X676400Y175375D01*
X676067Y175458D01*
X675817Y175667D01*
X675567Y176042D01*
G01X674217Y174875D02*
X673967Y174667D01*
X673675Y174542D01*
X673300Y174500D01*
X672925Y174583D01*
X672633Y174750D01*
X672425Y175042D01*
X672383Y175375D01*
X672467Y175708D01*
X672675Y175917D01*
X672967Y176083D01*
X673258Y176125D01*
X673550Y176083D01*
X673925Y175917D01*
X673800Y177000D01*
X672675D01*
G01X667000Y170467D02*
X669500D01*
Y171467D01*
X669375Y171800D01*
X669083Y172050D01*
X668750Y172133D01*
X668417Y172050D01*
X668167Y171842D01*
X668042Y171467D01*
Y170467D01*
G01X667000Y173567D02*
X669500D01*
Y174608D01*
X669375Y174942D01*
X669208Y175150D01*
X668875Y175233D01*
X668542Y175150D01*
X668333Y174900D01*
X668208Y174608D01*
Y173567D01*
G01Y174608D02*
X667000Y175233D01*
G01X669083Y176708D02*
X669333Y176958D01*
X669458Y177250D01*
X669500Y177583D01*
X669417Y178000D01*
X669208Y178292D01*
X668958Y178375D01*
X668708Y178333D01*
X668500Y178167D01*
X668083Y177333D01*
X667792Y176958D01*
X667375Y176708D01*
X667000Y176625D01*
Y178375D01*
G01X669083Y179808D02*
X669333Y180058D01*
X669458Y180350D01*
X669500Y180683D01*
X669417Y181100D01*
X669208Y181392D01*
X668958Y181475D01*
X668708Y181433D01*
X668500Y181267D01*
X668083Y180433D01*
X667792Y180058D01*
X667375Y179808D01*
X667000Y179725D01*
Y181475D01*
G01X669083Y182908D02*
X669333Y183158D01*
X669458Y183450D01*
X669500Y183783D01*
X669417Y184200D01*
X669208Y184492D01*
X668958Y184575D01*
X668708Y184533D01*
X668500Y184367D01*
X668083Y183533D01*
X667792Y183158D01*
X667375Y182908D01*
X667000Y182825D01*
Y184575D01*
G01X676000Y184467D02*
X678500D01*
Y185467D01*
X678375Y185800D01*
X678083Y186050D01*
X677750Y186133D01*
X677417Y186050D01*
X677167Y185842D01*
X677042Y185467D01*
Y184467D01*
G01X676000Y187567D02*
X678500D01*
Y188608D01*
X678375Y188942D01*
X678208Y189150D01*
X677875Y189233D01*
X677542Y189150D01*
X677333Y188900D01*
X677208Y188608D01*
Y187567D01*
G01Y188608D02*
X676000Y189233D01*
G01X678083Y190708D02*
X678333Y190958D01*
X678458Y191250D01*
X678500Y191583D01*
X678417Y192000D01*
X678208Y192292D01*
X677958Y192375D01*
X677708Y192333D01*
X677500Y192167D01*
X677083Y191333D01*
X676792Y190958D01*
X676375Y190708D01*
X676000Y190625D01*
Y192375D01*
G01X678083Y193808D02*
X678333Y194058D01*
X678458Y194350D01*
X678500Y194683D01*
X678417Y195100D01*
X678208Y195392D01*
X677958Y195475D01*
X677708Y195433D01*
X677500Y195267D01*
X677083Y194433D01*
X676792Y194058D01*
X676375Y193808D01*
X676000Y193725D01*
Y195475D01*
G01X678500Y197700D02*
X678417Y197367D01*
X678208Y197117D01*
X677958Y196950D01*
X677625Y196825D01*
X677250Y196783D01*
X676875Y196825D01*
X676542Y196950D01*
X676292Y197117D01*
X676083Y197367D01*
X676000Y197700D01*
X676083Y198033D01*
X676292Y198283D01*
X676542Y198450D01*
X676875Y198575D01*
X677250Y198617D01*
X677625Y198575D01*
X677958Y198450D01*
X678208Y198283D01*
X678417Y198033D01*
X678500Y197700D01*
G01X666000Y215017D02*
X668500D01*
Y216058D01*
X668375Y216392D01*
X668208Y216600D01*
X667875Y216683D01*
X667542Y216600D01*
X667333Y216350D01*
X667208Y216058D01*
Y215017D01*
G01Y216058D02*
X666000Y216683D01*
G01Y219450D02*
X668500D01*
X666708Y217908D01*
Y219992D01*
G01X668500Y222050D02*
X668417Y221717D01*
X668208Y221467D01*
X667958Y221300D01*
X667625Y221175D01*
X667250Y221133D01*
X666875Y221175D01*
X666542Y221300D01*
X666292Y221467D01*
X666083Y221717D01*
X666000Y222050D01*
X666083Y222383D01*
X666292Y222633D01*
X666542Y222800D01*
X666875Y222925D01*
X667250Y222967D01*
X667625Y222925D01*
X667958Y222800D01*
X668208Y222633D01*
X668417Y222383D01*
X668500Y222050D01*
G01X666000Y225067D02*
X666542Y225150D01*
X667000Y225275D01*
X667417Y225442D01*
X667875Y225650D01*
X668500Y225983D01*
Y224317D01*
G01X674500Y215017D02*
X677000D01*
Y216058D01*
X676875Y216392D01*
X676708Y216600D01*
X676375Y216683D01*
X676042Y216600D01*
X675833Y216350D01*
X675708Y216058D01*
Y215017D01*
G01Y216058D02*
X674500Y216683D01*
G01Y219450D02*
X677000D01*
X675208Y217908D01*
Y219992D01*
G01X677000Y222050D02*
X676917Y221717D01*
X676708Y221467D01*
X676458Y221300D01*
X676125Y221175D01*
X675750Y221133D01*
X675375Y221175D01*
X675042Y221300D01*
X674792Y221467D01*
X674583Y221717D01*
X674500Y222050D01*
X674583Y222383D01*
X674792Y222633D01*
X675042Y222800D01*
X675375Y222925D01*
X675750Y222967D01*
X676125Y222925D01*
X676458Y222800D01*
X676708Y222633D01*
X676917Y222383D01*
X677000Y222050D01*
G01X674792Y224442D02*
X674583Y224733D01*
X674500Y225067D01*
X674583Y225400D01*
X674833Y225692D01*
X675208Y225900D01*
X675583Y225983D01*
X676042D01*
X676417Y225900D01*
X676750Y225692D01*
X676917Y225442D01*
X677000Y225150D01*
X676917Y224817D01*
X676750Y224567D01*
X676500Y224400D01*
X676167Y224317D01*
X675875Y224400D01*
X675583Y224608D01*
X675417Y224858D01*
X675375Y225150D01*
X675458Y225483D01*
X675667Y225733D01*
X676042Y225983D01*
G01X670500Y215017D02*
X673000D01*
Y216058D01*
X672875Y216392D01*
X672708Y216600D01*
X672375Y216683D01*
X672042Y216600D01*
X671833Y216350D01*
X671708Y216058D01*
Y215017D01*
G01Y216058D02*
X670500Y216683D01*
G01Y219450D02*
X673000D01*
X671208Y217908D01*
Y219992D01*
G01X673000Y222050D02*
X672917Y221717D01*
X672708Y221467D01*
X672458Y221300D01*
X672125Y221175D01*
X671750Y221133D01*
X671375Y221175D01*
X671042Y221300D01*
X670792Y221467D01*
X670583Y221717D01*
X670500Y222050D01*
X670583Y222383D01*
X670792Y222633D01*
X671042Y222800D01*
X671375Y222925D01*
X671750Y222967D01*
X672125Y222925D01*
X672458Y222800D01*
X672708Y222633D01*
X672917Y222383D01*
X673000Y222050D01*
G01X670500Y225150D02*
X670542Y225442D01*
X670667Y225775D01*
X670875Y225983D01*
X671167Y226067D01*
X671458Y225983D01*
X671708Y225733D01*
X671833Y225358D01*
Y224942D01*
X671917Y224692D01*
X672125Y224483D01*
X672417Y224400D01*
X672708Y224525D01*
X672917Y224817D01*
X673000Y225150D01*
X672917Y225483D01*
X672708Y225775D01*
X672417Y225900D01*
X672125Y225817D01*
X671917Y225608D01*
X671833Y225358D01*
Y224942D01*
X671708Y224567D01*
X671458Y224317D01*
X671167Y224233D01*
X670875Y224317D01*
X670667Y224525D01*
X670542Y224858D01*
X670500Y225150D01*
G01X678500Y215017D02*
X681000D01*
Y216058D01*
X680875Y216392D01*
X680708Y216600D01*
X680375Y216683D01*
X680042Y216600D01*
X679833Y216350D01*
X679708Y216058D01*
Y215017D01*
G01Y216058D02*
X678500Y216683D01*
G01Y219450D02*
X681000D01*
X679208Y217908D01*
Y219992D01*
G01X681000Y222050D02*
X680917Y221717D01*
X680708Y221467D01*
X680458Y221300D01*
X680125Y221175D01*
X679750Y221133D01*
X679375Y221175D01*
X679042Y221300D01*
X678792Y221467D01*
X678583Y221717D01*
X678500Y222050D01*
X678583Y222383D01*
X678792Y222633D01*
X679042Y222800D01*
X679375Y222925D01*
X679750Y222967D01*
X680125Y222925D01*
X680458Y222800D01*
X680708Y222633D01*
X680917Y222383D01*
X681000Y222050D01*
G01X679542Y224358D02*
X679833Y224650D01*
X680000Y224900D01*
X680083Y225233D01*
X680000Y225525D01*
X679833Y225733D01*
X679583Y225900D01*
X679292Y225942D01*
X679042Y225900D01*
X678792Y225733D01*
X678583Y225483D01*
X678500Y225192D01*
X678583Y224858D01*
X678833Y224567D01*
X679208Y224400D01*
X679625Y224358D01*
X680167Y224442D01*
X680458Y224567D01*
X680750Y224775D01*
X680958Y225067D01*
X681000Y225358D01*
X680917Y225650D01*
X680708Y225858D01*
G01X687792Y47774D02*
X687917Y47524D01*
X688000Y47232D01*
Y46899D01*
X687875Y46524D01*
X687667Y46232D01*
X687417Y46024D01*
X687000Y45857D01*
X686625Y45815D01*
X686250Y45899D01*
X686000Y46024D01*
X685750Y46274D01*
X685583Y46565D01*
X685500Y46857D01*
Y47149D01*
X685583Y47440D01*
X685708Y47690D01*
X685875Y47899D01*
G01X686000Y49040D02*
X685708Y49290D01*
X685542Y49624D01*
X685500Y49999D01*
X685542Y50332D01*
X685750Y50665D01*
X686000Y50874D01*
X686250Y50915D01*
X686542Y50832D01*
X686750Y50540D01*
X686833Y50249D01*
Y49874D01*
G01Y50249D02*
X686958Y50499D01*
X687167Y50707D01*
X687417Y50790D01*
X687667Y50707D01*
X687875Y50499D01*
X688000Y50124D01*
X687958Y49749D01*
X687792Y49374D01*
G01X686542Y52265D02*
X686833Y52557D01*
X687000Y52807D01*
X687083Y53140D01*
X687000Y53432D01*
X686833Y53640D01*
X686583Y53807D01*
X686292Y53849D01*
X686042Y53807D01*
X685792Y53640D01*
X685583Y53390D01*
X685500Y53099D01*
X685583Y52765D01*
X685833Y52474D01*
X686208Y52307D01*
X686625Y52265D01*
X687167Y52349D01*
X687458Y52474D01*
X687750Y52682D01*
X687958Y52974D01*
X688000Y53265D01*
X687917Y53557D01*
X687708Y53765D01*
G01X686542Y55365D02*
X686833Y55657D01*
X687000Y55907D01*
X687083Y56240D01*
X687000Y56532D01*
X686833Y56740D01*
X686583Y56907D01*
X686292Y56949D01*
X686042Y56907D01*
X685792Y56740D01*
X685583Y56490D01*
X685500Y56199D01*
X685583Y55865D01*
X685833Y55574D01*
X686208Y55407D01*
X686625Y55365D01*
X687167Y55449D01*
X687458Y55574D01*
X687750Y55782D01*
X687958Y56074D01*
X688000Y56365D01*
X687917Y56657D01*
X687708Y56865D01*
G01X683792Y47774D02*
X683917Y47524D01*
X684000Y47232D01*
Y46899D01*
X683875Y46524D01*
X683667Y46232D01*
X683417Y46024D01*
X683000Y45857D01*
X682625Y45815D01*
X682250Y45899D01*
X682000Y46024D01*
X681750Y46274D01*
X681583Y46565D01*
X681500Y46857D01*
Y47149D01*
X681583Y47440D01*
X681708Y47690D01*
X681875Y47899D01*
G01X682000Y49040D02*
X681708Y49290D01*
X681542Y49624D01*
X681500Y49999D01*
X681542Y50332D01*
X681750Y50665D01*
X682000Y50874D01*
X682250Y50915D01*
X682542Y50832D01*
X682750Y50540D01*
X682833Y50249D01*
Y49874D01*
G01Y50249D02*
X682958Y50499D01*
X683167Y50707D01*
X683417Y50790D01*
X683667Y50707D01*
X683875Y50499D01*
X684000Y50124D01*
X683958Y49749D01*
X683792Y49374D01*
G01X682542Y52265D02*
X682833Y52557D01*
X683000Y52807D01*
X683083Y53140D01*
X683000Y53432D01*
X682833Y53640D01*
X682583Y53807D01*
X682292Y53849D01*
X682042Y53807D01*
X681792Y53640D01*
X681583Y53390D01*
X681500Y53099D01*
X681583Y52765D01*
X681833Y52474D01*
X682208Y52307D01*
X682625Y52265D01*
X683167Y52349D01*
X683458Y52474D01*
X683750Y52682D01*
X683958Y52974D01*
X684000Y53265D01*
X683917Y53557D01*
X683708Y53765D01*
G01X681875Y55240D02*
X681667Y55490D01*
X681542Y55782D01*
X681500Y56157D01*
X681583Y56532D01*
X681750Y56824D01*
X682042Y57032D01*
X682375Y57074D01*
X682708Y56990D01*
X682917Y56782D01*
X683083Y56490D01*
X683125Y56199D01*
X683083Y55907D01*
X682917Y55532D01*
X684000Y55657D01*
Y56782D01*
G01X704483Y45007D02*
Y47507D01*
X703442D01*
X703108Y47382D01*
X702900Y47215D01*
X702817Y46882D01*
X702900Y46549D01*
X703150Y46340D01*
X703442Y46215D01*
X704483D01*
G01X703442D02*
X702817Y45007D01*
G01X700550D02*
Y47507D01*
X701050Y47007D01*
G01Y45007D02*
X700050D01*
G01X698158Y45299D02*
X697867Y45090D01*
X697533Y45007D01*
X697200Y45090D01*
X696908Y45340D01*
X696700Y45715D01*
X696617Y46090D01*
Y46549D01*
X696700Y46924D01*
X696908Y47257D01*
X697158Y47424D01*
X697450Y47507D01*
X697783Y47424D01*
X698033Y47257D01*
X698200Y47007D01*
X698283Y46674D01*
X698200Y46382D01*
X697992Y46090D01*
X697742Y45924D01*
X697450Y45882D01*
X697117Y45965D01*
X696867Y46174D01*
X696617Y46549D01*
G01X695267Y45382D02*
X695017Y45174D01*
X694725Y45049D01*
X694350Y45007D01*
X693975Y45090D01*
X693683Y45257D01*
X693475Y45549D01*
X693433Y45882D01*
X693517Y46215D01*
X693725Y46424D01*
X694017Y46590D01*
X694308Y46632D01*
X694600Y46590D01*
X694975Y46424D01*
X694850Y47507D01*
X693725D01*
G01X709033Y113000D02*
Y115500D01*
X708033D01*
X707700Y115375D01*
X707450Y115083D01*
X707367Y114750D01*
X707450Y114417D01*
X707658Y114167D01*
X708033Y114042D01*
X709033D01*
G01X704183Y115292D02*
X704433Y115417D01*
X704725Y115500D01*
X705058D01*
X705433Y115375D01*
X705725Y115167D01*
X705933Y114917D01*
X706100Y114500D01*
X706142Y114125D01*
X706058Y113750D01*
X705933Y113500D01*
X705683Y113250D01*
X705392Y113083D01*
X705100Y113000D01*
X704808D01*
X704517Y113083D01*
X704267Y113208D01*
X704058Y113375D01*
G01X702000Y113000D02*
Y115500D01*
X702500Y115000D01*
G01Y113000D02*
X701500D01*
G01X699608Y113292D02*
X699317Y113083D01*
X698983Y113000D01*
X698650Y113083D01*
X698358Y113333D01*
X698150Y113708D01*
X698067Y114083D01*
Y114542D01*
X698150Y114917D01*
X698358Y115250D01*
X698608Y115417D01*
X698900Y115500D01*
X699233Y115417D01*
X699483Y115250D01*
X699650Y115000D01*
X699733Y114667D01*
X699650Y114375D01*
X699442Y114083D01*
X699192Y113917D01*
X698900Y113875D01*
X698567Y113958D01*
X698317Y114167D01*
X698067Y114542D01*
G01X696592Y115083D02*
X696342Y115333D01*
X696050Y115458D01*
X695717Y115500D01*
X695300Y115417D01*
X695008Y115208D01*
X694925Y114958D01*
X694967Y114708D01*
X695133Y114500D01*
X695967Y114083D01*
X696342Y113792D01*
X696592Y113375D01*
X696675Y113000D01*
X694925D01*
G01X709533Y118500D02*
Y121000D01*
X708533D01*
X708200Y120875D01*
X707950Y120583D01*
X707867Y120250D01*
X707950Y119917D01*
X708158Y119667D01*
X708533Y119542D01*
X709533D01*
G01X706433Y118500D02*
Y121000D01*
X705392D01*
X705058Y120875D01*
X704850Y120708D01*
X704767Y120375D01*
X704850Y120042D01*
X705100Y119833D01*
X705392Y119708D01*
X706433D01*
G01X705392D02*
X704767Y118500D01*
G01X703292Y120583D02*
X703042Y120833D01*
X702750Y120958D01*
X702417Y121000D01*
X702000Y120917D01*
X701708Y120708D01*
X701625Y120458D01*
X701667Y120208D01*
X701833Y120000D01*
X702667Y119583D01*
X703042Y119292D01*
X703292Y118875D01*
X703375Y118500D01*
X701625D01*
G01X699400D02*
Y121000D01*
X699900Y120500D01*
G01Y118500D02*
X698900D01*
G01X697217Y119000D02*
X696967Y118708D01*
X696633Y118542D01*
X696258Y118500D01*
X695925Y118542D01*
X695592Y118750D01*
X695383Y119000D01*
X695342Y119250D01*
X695425Y119542D01*
X695717Y119750D01*
X696008Y119833D01*
X696383D01*
G01X696008D02*
X695758Y119958D01*
X695550Y120167D01*
X695467Y120417D01*
X695550Y120667D01*
X695758Y120875D01*
X696133Y121000D01*
X696508Y120958D01*
X696883Y120792D01*
G01X694292Y151767D02*
X694417Y151517D01*
X694500Y151225D01*
Y150892D01*
X694375Y150517D01*
X694167Y150225D01*
X693917Y150017D01*
X693500Y149850D01*
X693125Y149808D01*
X692750Y149892D01*
X692500Y150017D01*
X692250Y150267D01*
X692083Y150558D01*
X692000Y150850D01*
Y151142D01*
X692083Y151433D01*
X692208Y151683D01*
X692375Y151892D01*
G01X692500Y153033D02*
X692208Y153283D01*
X692042Y153617D01*
X692000Y153992D01*
X692042Y154325D01*
X692250Y154658D01*
X692500Y154867D01*
X692750Y154908D01*
X693042Y154825D01*
X693250Y154533D01*
X693333Y154242D01*
Y153867D01*
G01Y154242D02*
X693458Y154492D01*
X693667Y154700D01*
X693917Y154783D01*
X694167Y154700D01*
X694375Y154492D01*
X694500Y154117D01*
X694458Y153742D01*
X694292Y153367D01*
G01X692375Y156133D02*
X692167Y156383D01*
X692042Y156675D01*
X692000Y157050D01*
X692083Y157425D01*
X692250Y157717D01*
X692542Y157925D01*
X692875Y157967D01*
X693208Y157883D01*
X693417Y157675D01*
X693583Y157383D01*
X693625Y157092D01*
X693583Y156800D01*
X693417Y156425D01*
X694500Y156550D01*
Y157675D01*
G01X692000Y160067D02*
X692542Y160150D01*
X693000Y160275D01*
X693417Y160442D01*
X693875Y160650D01*
X694500Y160983D01*
Y159317D01*
G01X705533Y178000D02*
Y180500D01*
X704533D01*
X704200Y180375D01*
X703950Y180083D01*
X703867Y179750D01*
X703950Y179417D01*
X704158Y179167D01*
X704533Y179042D01*
X705533D01*
G01X700683Y180292D02*
X700933Y180417D01*
X701225Y180500D01*
X701558D01*
X701933Y180375D01*
X702225Y180167D01*
X702433Y179917D01*
X702600Y179500D01*
X702642Y179125D01*
X702558Y178750D01*
X702433Y178500D01*
X702183Y178250D01*
X701892Y178083D01*
X701600Y178000D01*
X701308D01*
X701017Y178083D01*
X700767Y178208D01*
X700558Y178375D01*
G01X698500Y178000D02*
Y180500D01*
X699000Y180000D01*
G01Y178000D02*
X698000D01*
G01X696108Y178292D02*
X695817Y178083D01*
X695483Y178000D01*
X695150Y178083D01*
X694858Y178333D01*
X694650Y178708D01*
X694567Y179083D01*
Y179542D01*
X694650Y179917D01*
X694858Y180250D01*
X695108Y180417D01*
X695400Y180500D01*
X695733Y180417D01*
X695983Y180250D01*
X696150Y180000D01*
X696233Y179667D01*
X696150Y179375D01*
X695942Y179083D01*
X695692Y178917D01*
X695400Y178875D01*
X695067Y178958D01*
X694817Y179167D01*
X694567Y179542D01*
G01X693217Y178500D02*
X692967Y178208D01*
X692633Y178042D01*
X692258Y178000D01*
X691925Y178042D01*
X691592Y178250D01*
X691383Y178500D01*
X691342Y178750D01*
X691425Y179042D01*
X691717Y179250D01*
X692008Y179333D01*
X692383D01*
G01X692008D02*
X691758Y179458D01*
X691550Y179667D01*
X691467Y179917D01*
X691550Y180167D01*
X691758Y180375D01*
X692133Y180500D01*
X692508Y180458D01*
X692883Y180292D01*
G01X700933Y197000D02*
Y204000D01*
G01X695867D02*
X700933Y199683D01*
G01X695067Y197000D02*
X698667Y201667D01*
G01X688500Y183467D02*
X691000D01*
Y184467D01*
X690875Y184800D01*
X690583Y185050D01*
X690250Y185133D01*
X689917Y185050D01*
X689667Y184842D01*
X689542Y184467D01*
Y183467D01*
G01X688500Y186567D02*
X691000D01*
Y187608D01*
X690875Y187942D01*
X690708Y188150D01*
X690375Y188233D01*
X690042Y188150D01*
X689833Y187900D01*
X689708Y187608D01*
Y186567D01*
G01Y187608D02*
X688500Y188233D01*
G01X690583Y189708D02*
X690833Y189958D01*
X690958Y190250D01*
X691000Y190583D01*
X690917Y191000D01*
X690708Y191292D01*
X690458Y191375D01*
X690208Y191333D01*
X690000Y191167D01*
X689583Y190333D01*
X689292Y189958D01*
X688875Y189708D01*
X688500Y189625D01*
Y191375D01*
G01Y193600D02*
X691000D01*
X690500Y193100D01*
G01X688500D02*
Y194100D01*
G01X688792Y195992D02*
X688583Y196283D01*
X688500Y196617D01*
X688583Y196950D01*
X688833Y197242D01*
X689208Y197450D01*
X689583Y197533D01*
X690042D01*
X690417Y197450D01*
X690750Y197242D01*
X690917Y196992D01*
X691000Y196700D01*
X690917Y196367D01*
X690750Y196117D01*
X690500Y195950D01*
X690167Y195867D01*
X689875Y195950D01*
X689583Y196158D01*
X689417Y196408D01*
X689375Y196700D01*
X689458Y197033D01*
X689667Y197283D01*
X690042Y197533D01*
G01X683000Y184517D02*
X685500D01*
Y185558D01*
X685375Y185892D01*
X685208Y186100D01*
X684875Y186183D01*
X684542Y186100D01*
X684333Y185850D01*
X684208Y185558D01*
Y184517D01*
G01Y185558D02*
X683000Y186183D01*
G01X683500Y187533D02*
X683208Y187783D01*
X683042Y188117D01*
X683000Y188492D01*
X683042Y188825D01*
X683250Y189158D01*
X683500Y189367D01*
X683750Y189408D01*
X684042Y189325D01*
X684250Y189033D01*
X684333Y188742D01*
Y188367D01*
G01Y188742D02*
X684458Y188992D01*
X684667Y189200D01*
X684917Y189283D01*
X685167Y189200D01*
X685375Y188992D01*
X685500Y188617D01*
X685458Y188242D01*
X685292Y187867D01*
G01X683000Y191467D02*
X683542Y191550D01*
X684000Y191675D01*
X684417Y191842D01*
X684875Y192050D01*
X685500Y192383D01*
Y190717D01*
G01X683292Y193942D02*
X683083Y194233D01*
X683000Y194567D01*
X683083Y194900D01*
X683333Y195192D01*
X683708Y195400D01*
X684083Y195483D01*
X684542D01*
X684917Y195400D01*
X685250Y195192D01*
X685417Y194942D01*
X685500Y194650D01*
X685417Y194317D01*
X685250Y194067D01*
X685000Y193900D01*
X684667Y193817D01*
X684375Y193900D01*
X684083Y194108D01*
X683917Y194358D01*
X683875Y194650D01*
X683958Y194983D01*
X684167Y195233D01*
X684542Y195483D01*
G01X688500Y202517D02*
X691000D01*
Y203558D01*
X690875Y203892D01*
X690708Y204100D01*
X690375Y204183D01*
X690042Y204100D01*
X689833Y203850D01*
X689708Y203558D01*
Y202517D01*
G01Y203558D02*
X688500Y204183D01*
G01X689000Y205533D02*
X688708Y205783D01*
X688542Y206117D01*
X688500Y206492D01*
X688542Y206825D01*
X688750Y207158D01*
X689000Y207367D01*
X689250Y207408D01*
X689542Y207325D01*
X689750Y207033D01*
X689833Y206742D01*
Y206367D01*
G01Y206742D02*
X689958Y206992D01*
X690167Y207200D01*
X690417Y207283D01*
X690667Y207200D01*
X690875Y206992D01*
X691000Y206617D01*
X690958Y206242D01*
X690792Y205867D01*
G01X691000Y209550D02*
X690917Y209217D01*
X690708Y208967D01*
X690458Y208800D01*
X690125Y208675D01*
X689750Y208633D01*
X689375Y208675D01*
X689042Y208800D01*
X688792Y208967D01*
X688583Y209217D01*
X688500Y209550D01*
X688583Y209883D01*
X688792Y210133D01*
X689042Y210300D01*
X689375Y210425D01*
X689750Y210467D01*
X690125Y210425D01*
X690458Y210300D01*
X690708Y210133D01*
X690917Y209883D01*
X691000Y209550D01*
G01X688500Y213150D02*
X691000D01*
X689208Y211608D01*
Y213692D01*
G01X684500Y202517D02*
X687000D01*
Y203558D01*
X686875Y203892D01*
X686708Y204100D01*
X686375Y204183D01*
X686042Y204100D01*
X685833Y203850D01*
X685708Y203558D01*
Y202517D01*
G01Y203558D02*
X684500Y204183D01*
G01X685000Y205533D02*
X684708Y205783D01*
X684542Y206117D01*
X684500Y206492D01*
X684542Y206825D01*
X684750Y207158D01*
X685000Y207367D01*
X685250Y207408D01*
X685542Y207325D01*
X685750Y207033D01*
X685833Y206742D01*
Y206367D01*
G01Y206742D02*
X685958Y206992D01*
X686167Y207200D01*
X686417Y207283D01*
X686667Y207200D01*
X686875Y206992D01*
X687000Y206617D01*
X686958Y206242D01*
X686792Y205867D01*
G01X687000Y209550D02*
X686917Y209217D01*
X686708Y208967D01*
X686458Y208800D01*
X686125Y208675D01*
X685750Y208633D01*
X685375Y208675D01*
X685042Y208800D01*
X684792Y208967D01*
X684583Y209217D01*
X684500Y209550D01*
X684583Y209883D01*
X684792Y210133D01*
X685042Y210300D01*
X685375Y210425D01*
X685750Y210467D01*
X686125Y210425D01*
X686458Y210300D01*
X686708Y210133D01*
X686917Y209883D01*
X687000Y209550D01*
G01X684500Y212567D02*
X685042Y212650D01*
X685500Y212775D01*
X685917Y212942D01*
X686375Y213150D01*
X687000Y213483D01*
Y211817D01*
G01X685000Y219517D02*
X687500D01*
Y220558D01*
X687375Y220892D01*
X687208Y221100D01*
X686875Y221183D01*
X686542Y221100D01*
X686333Y220850D01*
X686208Y220558D01*
Y219517D01*
G01Y220558D02*
X685000Y221183D01*
G01X685500Y222533D02*
X685208Y222783D01*
X685042Y223117D01*
X685000Y223492D01*
X685042Y223825D01*
X685250Y224158D01*
X685500Y224367D01*
X685750Y224408D01*
X686042Y224325D01*
X686250Y224033D01*
X686333Y223742D01*
Y223367D01*
G01Y223742D02*
X686458Y223992D01*
X686667Y224200D01*
X686917Y224283D01*
X687167Y224200D01*
X687375Y223992D01*
X687500Y223617D01*
X687458Y223242D01*
X687292Y222867D01*
G01X686042Y225758D02*
X686333Y226050D01*
X686500Y226300D01*
X686583Y226633D01*
X686500Y226925D01*
X686333Y227133D01*
X686083Y227300D01*
X685792Y227342D01*
X685542Y227300D01*
X685292Y227133D01*
X685083Y226883D01*
X685000Y226592D01*
X685083Y226258D01*
X685333Y225967D01*
X685708Y225800D01*
X686125Y225758D01*
X686667Y225842D01*
X686958Y225967D01*
X687250Y226175D01*
X687458Y226467D01*
X687500Y226758D01*
X687417Y227050D01*
X687208Y227258D01*
G01X685000Y230150D02*
X687500D01*
X685708Y228608D01*
Y230692D01*
G01X721533Y53700D02*
Y56200D01*
X720533D01*
X720200Y56075D01*
X719950Y55783D01*
X719867Y55450D01*
X719950Y55117D01*
X720158Y54867D01*
X720533Y54742D01*
X721533D01*
G01X716683Y55992D02*
X716933Y56117D01*
X717225Y56200D01*
X717558D01*
X717933Y56075D01*
X718225Y55867D01*
X718433Y55617D01*
X718600Y55200D01*
X718642Y54825D01*
X718558Y54450D01*
X718433Y54200D01*
X718183Y53950D01*
X717892Y53783D01*
X717600Y53700D01*
X717308D01*
X717017Y53783D01*
X716767Y53908D01*
X716558Y54075D01*
G01X715292Y55783D02*
X715042Y56033D01*
X714750Y56158D01*
X714417Y56200D01*
X714000Y56117D01*
X713708Y55908D01*
X713625Y55658D01*
X713667Y55408D01*
X713833Y55200D01*
X714667Y54783D01*
X715042Y54492D01*
X715292Y54075D01*
X715375Y53700D01*
X713625D01*
G01X711400Y56200D02*
X711733Y56117D01*
X711983Y55908D01*
X712150Y55658D01*
X712275Y55325D01*
X712317Y54950D01*
X712275Y54575D01*
X712150Y54242D01*
X711983Y53992D01*
X711733Y53783D01*
X711400Y53700D01*
X711067Y53783D01*
X710817Y53992D01*
X710650Y54242D01*
X710525Y54575D01*
X710483Y54950D01*
X710525Y55325D01*
X710650Y55658D01*
X710817Y55908D01*
X711067Y56117D01*
X711400Y56200D01*
G01X709092Y54742D02*
X708800Y55033D01*
X708550Y55200D01*
X708217Y55283D01*
X707925Y55200D01*
X707717Y55033D01*
X707550Y54783D01*
X707508Y54492D01*
X707550Y54242D01*
X707717Y53992D01*
X707967Y53783D01*
X708258Y53700D01*
X708592Y53783D01*
X708883Y54033D01*
X709050Y54408D01*
X709092Y54825D01*
X709008Y55367D01*
X708883Y55658D01*
X708675Y55950D01*
X708383Y56158D01*
X708092Y56200D01*
X707800Y56117D01*
X707592Y55908D01*
G01X721533Y58700D02*
Y61200D01*
X720533D01*
X720200Y61075D01*
X719950Y60783D01*
X719867Y60450D01*
X719950Y60117D01*
X720158Y59867D01*
X720533Y59742D01*
X721533D01*
G01X716683Y60992D02*
X716933Y61117D01*
X717225Y61200D01*
X717558D01*
X717933Y61075D01*
X718225Y60867D01*
X718433Y60617D01*
X718600Y60200D01*
X718642Y59825D01*
X718558Y59450D01*
X718433Y59200D01*
X718183Y58950D01*
X717892Y58783D01*
X717600Y58700D01*
X717308D01*
X717017Y58783D01*
X716767Y58908D01*
X716558Y59075D01*
G01X715292Y60783D02*
X715042Y61033D01*
X714750Y61158D01*
X714417Y61200D01*
X714000Y61117D01*
X713708Y60908D01*
X713625Y60658D01*
X713667Y60408D01*
X713833Y60200D01*
X714667Y59783D01*
X715042Y59492D01*
X715292Y59075D01*
X715375Y58700D01*
X713625D01*
G01X711400Y61200D02*
X711733Y61117D01*
X711983Y60908D01*
X712150Y60658D01*
X712275Y60325D01*
X712317Y59950D01*
X712275Y59575D01*
X712150Y59242D01*
X711983Y58992D01*
X711733Y58783D01*
X711400Y58700D01*
X711067Y58783D01*
X710817Y58992D01*
X710650Y59242D01*
X710525Y59575D01*
X710483Y59950D01*
X710525Y60325D01*
X710650Y60658D01*
X710817Y60908D01*
X711067Y61117D01*
X711400Y61200D01*
G01X708383Y58700D02*
X708300Y59242D01*
X708175Y59700D01*
X708008Y60117D01*
X707800Y60575D01*
X707467Y61200D01*
X709133D01*
G01X717183Y45007D02*
Y47507D01*
X716142D01*
X715808Y47382D01*
X715600Y47215D01*
X715517Y46882D01*
X715600Y46549D01*
X715850Y46340D01*
X716142Y46215D01*
X717183D01*
G01X716142D02*
X715517Y45007D01*
G01X713250D02*
Y47507D01*
X713750Y47007D01*
G01Y45007D02*
X712750D01*
G01X710858Y45299D02*
X710567Y45090D01*
X710233Y45007D01*
X709900Y45090D01*
X709608Y45340D01*
X709400Y45715D01*
X709317Y46090D01*
Y46549D01*
X709400Y46924D01*
X709608Y47257D01*
X709858Y47424D01*
X710150Y47507D01*
X710483Y47424D01*
X710733Y47257D01*
X710900Y47007D01*
X710983Y46674D01*
X710900Y46382D01*
X710692Y46090D01*
X710442Y45924D01*
X710150Y45882D01*
X709817Y45965D01*
X709567Y46174D01*
X709317Y46549D01*
G01X707842Y46049D02*
X707550Y46340D01*
X707300Y46507D01*
X706967Y46590D01*
X706675Y46507D01*
X706467Y46340D01*
X706300Y46090D01*
X706258Y45799D01*
X706300Y45549D01*
X706467Y45299D01*
X706717Y45090D01*
X707008Y45007D01*
X707342Y45090D01*
X707633Y45340D01*
X707800Y45715D01*
X707842Y46132D01*
X707758Y46674D01*
X707633Y46965D01*
X707425Y47257D01*
X707133Y47465D01*
X706842Y47507D01*
X706550Y47424D01*
X706342Y47215D01*
G01X708500Y80467D02*
X711000D01*
Y81467D01*
X710875Y81800D01*
X710583Y82050D01*
X710250Y82133D01*
X709917Y82050D01*
X709667Y81842D01*
X709542Y81467D01*
Y80467D01*
G01X708500Y83567D02*
X711000D01*
Y84608D01*
X710875Y84942D01*
X710708Y85150D01*
X710375Y85233D01*
X710042Y85150D01*
X709833Y84900D01*
X709708Y84608D01*
Y83567D01*
G01Y84608D02*
X708500Y85233D01*
G01X710583Y86708D02*
X710833Y86958D01*
X710958Y87250D01*
X711000Y87583D01*
X710917Y88000D01*
X710708Y88292D01*
X710458Y88375D01*
X710208Y88333D01*
X710000Y88167D01*
X709583Y87333D01*
X709292Y86958D01*
X708875Y86708D01*
X708500Y86625D01*
Y88375D01*
G01Y90600D02*
X711000D01*
X710500Y90100D01*
G01X708500D02*
Y91100D01*
G01Y93700D02*
X708542Y93992D01*
X708667Y94325D01*
X708875Y94533D01*
X709167Y94617D01*
X709458Y94533D01*
X709708Y94283D01*
X709833Y93908D01*
Y93492D01*
X709917Y93242D01*
X710125Y93033D01*
X710417Y92950D01*
X710708Y93075D01*
X710917Y93367D01*
X711000Y93700D01*
X710917Y94033D01*
X710708Y94325D01*
X710417Y94450D01*
X710125Y94367D01*
X709917Y94158D01*
X709833Y93908D01*
Y93492D01*
X709708Y93117D01*
X709458Y92867D01*
X709167Y92783D01*
X708875Y92867D01*
X708667Y93075D01*
X708542Y93408D01*
X708500Y93700D01*
G01X697000Y150017D02*
X699500D01*
Y151058D01*
X699375Y151392D01*
X699208Y151600D01*
X698875Y151683D01*
X698542Y151600D01*
X698333Y151350D01*
X698208Y151058D01*
Y150017D01*
G01Y151058D02*
X697000Y151683D01*
G01Y153950D02*
X699500D01*
X699000Y153450D01*
G01X697000D02*
Y154450D01*
G01Y156967D02*
X697542Y157050D01*
X698000Y157175D01*
X698417Y157342D01*
X698875Y157550D01*
X699500Y157883D01*
Y156217D01*
G01X697000Y160067D02*
X697542Y160150D01*
X698000Y160275D01*
X698417Y160442D01*
X698875Y160650D01*
X699500Y160983D01*
Y159317D01*
G01X701500Y150017D02*
X704000D01*
Y151058D01*
X703875Y151392D01*
X703708Y151600D01*
X703375Y151683D01*
X703042Y151600D01*
X702833Y151350D01*
X702708Y151058D01*
Y150017D01*
G01Y151058D02*
X701500Y151683D01*
G01Y153950D02*
X704000D01*
X703500Y153450D01*
G01X701500D02*
Y154450D01*
G01Y156967D02*
X702042Y157050D01*
X702500Y157175D01*
X702917Y157342D01*
X703375Y157550D01*
X704000Y157883D01*
Y156217D01*
G01X701875Y159233D02*
X701667Y159483D01*
X701542Y159775D01*
X701500Y160150D01*
X701583Y160525D01*
X701750Y160817D01*
X702042Y161025D01*
X702375Y161067D01*
X702708Y160983D01*
X702917Y160775D01*
X703083Y160483D01*
X703125Y160192D01*
X703083Y159900D01*
X702917Y159525D01*
X704000Y159650D01*
Y160775D01*
G01X704840Y214657D02*
X707340D01*
Y215698D01*
X707215Y216032D01*
X707048Y216240D01*
X706715Y216323D01*
X706382Y216240D01*
X706173Y215990D01*
X706048Y215698D01*
Y214657D01*
G01Y215698D02*
X704840Y216323D01*
G01X705340Y217673D02*
X705048Y217923D01*
X704882Y218257D01*
X704840Y218632D01*
X704882Y218965D01*
X705090Y219298D01*
X705340Y219507D01*
X705590Y219548D01*
X705882Y219465D01*
X706090Y219173D01*
X706173Y218882D01*
Y218507D01*
G01Y218882D02*
X706298Y219132D01*
X706507Y219340D01*
X706757Y219423D01*
X707007Y219340D01*
X707215Y219132D01*
X707340Y218757D01*
X707298Y218382D01*
X707132Y218007D01*
G01X704840Y221607D02*
X705382Y221690D01*
X705840Y221815D01*
X706257Y221982D01*
X706715Y222190D01*
X707340Y222523D01*
Y220857D01*
G01X704840Y224707D02*
X705382Y224790D01*
X705840Y224915D01*
X706257Y225082D01*
X706715Y225290D01*
X707340Y225623D01*
Y223957D01*
G01X700500Y214517D02*
X703000D01*
Y215558D01*
X702875Y215892D01*
X702708Y216100D01*
X702375Y216183D01*
X702042Y216100D01*
X701833Y215850D01*
X701708Y215558D01*
Y214517D01*
G01Y215558D02*
X700500Y216183D01*
G01X701000Y217533D02*
X700708Y217783D01*
X700542Y218117D01*
X700500Y218492D01*
X700542Y218825D01*
X700750Y219158D01*
X701000Y219367D01*
X701250Y219408D01*
X701542Y219325D01*
X701750Y219033D01*
X701833Y218742D01*
Y218367D01*
G01Y218742D02*
X701958Y218992D01*
X702167Y219200D01*
X702417Y219283D01*
X702667Y219200D01*
X702875Y218992D01*
X703000Y218617D01*
X702958Y218242D01*
X702792Y217867D01*
G01X700500Y221467D02*
X701042Y221550D01*
X701500Y221675D01*
X701917Y221842D01*
X702375Y222050D01*
X703000Y222383D01*
Y220717D01*
G01X700500Y224650D02*
X700542Y224942D01*
X700667Y225275D01*
X700875Y225483D01*
X701167Y225567D01*
X701458Y225483D01*
X701708Y225233D01*
X701833Y224858D01*
Y224442D01*
X701917Y224192D01*
X702125Y223983D01*
X702417Y223900D01*
X702708Y224025D01*
X702917Y224317D01*
X703000Y224650D01*
X702917Y224983D01*
X702708Y225275D01*
X702417Y225400D01*
X702125Y225317D01*
X701917Y225108D01*
X701833Y224858D01*
Y224442D01*
X701708Y224067D01*
X701458Y223817D01*
X701167Y223733D01*
X700875Y223817D01*
X700667Y224025D01*
X700542Y224358D01*
X700500Y224650D01*
G01X696500Y219017D02*
X699000D01*
Y220058D01*
X698875Y220392D01*
X698708Y220600D01*
X698375Y220683D01*
X698042Y220600D01*
X697833Y220350D01*
X697708Y220058D01*
Y219017D01*
G01Y220058D02*
X696500Y220683D01*
G01X697000Y222033D02*
X696708Y222283D01*
X696542Y222617D01*
X696500Y222992D01*
X696542Y223325D01*
X696750Y223658D01*
X697000Y223867D01*
X697250Y223908D01*
X697542Y223825D01*
X697750Y223533D01*
X697833Y223242D01*
Y222867D01*
G01Y223242D02*
X697958Y223492D01*
X698167Y223700D01*
X698417Y223783D01*
X698667Y223700D01*
X698875Y223492D01*
X699000Y223117D01*
X698958Y222742D01*
X698792Y222367D01*
G01X696500Y225967D02*
X697042Y226050D01*
X697500Y226175D01*
X697917Y226342D01*
X698375Y226550D01*
X699000Y226883D01*
Y225217D01*
G01X698583Y228358D02*
X698833Y228608D01*
X698958Y228900D01*
X699000Y229233D01*
X698917Y229650D01*
X698708Y229942D01*
X698458Y230025D01*
X698208Y229983D01*
X698000Y229817D01*
X697583Y228983D01*
X697292Y228608D01*
X696875Y228358D01*
X696500Y228275D01*
Y230025D01*
G01X729883Y45007D02*
Y47507D01*
X728842D01*
X728508Y47382D01*
X728300Y47215D01*
X728217Y46882D01*
X728300Y46549D01*
X728550Y46340D01*
X728842Y46215D01*
X729883D01*
G01X728842D02*
X728217Y45007D01*
G01X725950D02*
Y47507D01*
X726450Y47007D01*
G01Y45007D02*
X725450D01*
G01X723558Y45299D02*
X723267Y45090D01*
X722933Y45007D01*
X722600Y45090D01*
X722308Y45340D01*
X722100Y45715D01*
X722017Y46090D01*
Y46549D01*
X722100Y46924D01*
X722308Y47257D01*
X722558Y47424D01*
X722850Y47507D01*
X723183Y47424D01*
X723433Y47257D01*
X723600Y47007D01*
X723683Y46674D01*
X723600Y46382D01*
X723392Y46090D01*
X723142Y45924D01*
X722850Y45882D01*
X722517Y45965D01*
X722267Y46174D01*
X722017Y46549D01*
G01X719833Y45007D02*
X719750Y45549D01*
X719625Y46007D01*
X719458Y46424D01*
X719250Y46882D01*
X718917Y47507D01*
X720583D01*
G01X736033Y72000D02*
Y74500D01*
X735033D01*
X734700Y74375D01*
X734450Y74083D01*
X734367Y73750D01*
X734450Y73417D01*
X734658Y73167D01*
X735033Y73042D01*
X736033D01*
G01X731183Y74292D02*
X731433Y74417D01*
X731725Y74500D01*
X732058D01*
X732433Y74375D01*
X732725Y74167D01*
X732933Y73917D01*
X733100Y73500D01*
X733142Y73125D01*
X733058Y72750D01*
X732933Y72500D01*
X732683Y72250D01*
X732392Y72083D01*
X732100Y72000D01*
X731808D01*
X731517Y72083D01*
X731267Y72208D01*
X731058Y72375D01*
G01X729792Y74083D02*
X729542Y74333D01*
X729250Y74458D01*
X728917Y74500D01*
X728500Y74417D01*
X728208Y74208D01*
X728125Y73958D01*
X728167Y73708D01*
X728333Y73500D01*
X729167Y73083D01*
X729542Y72792D01*
X729792Y72375D01*
X729875Y72000D01*
X728125D01*
G01X725900Y74500D02*
X726233Y74417D01*
X726483Y74208D01*
X726650Y73958D01*
X726775Y73625D01*
X726817Y73250D01*
X726775Y72875D01*
X726650Y72542D01*
X726483Y72292D01*
X726233Y72083D01*
X725900Y72000D01*
X725567Y72083D01*
X725317Y72292D01*
X725150Y72542D01*
X725025Y72875D01*
X724983Y73250D01*
X725025Y73625D01*
X725150Y73958D01*
X725317Y74208D01*
X725567Y74417D01*
X725900Y74500D01*
G01X722300Y72000D02*
Y74500D01*
X723842Y72708D01*
X721758D01*
G01X730233Y67792D02*
X730483Y67917D01*
X730775Y68000D01*
X731108D01*
X731483Y67875D01*
X731775Y67667D01*
X731983Y67417D01*
X732150Y67000D01*
X732192Y66625D01*
X732108Y66250D01*
X731983Y66000D01*
X731733Y65750D01*
X731442Y65583D01*
X731150Y65500D01*
X730858D01*
X730567Y65583D01*
X730317Y65708D01*
X730108Y65875D01*
G01X728842Y67583D02*
X728592Y67833D01*
X728300Y67958D01*
X727967Y68000D01*
X727550Y67917D01*
X727258Y67708D01*
X727175Y67458D01*
X727217Y67208D01*
X727383Y67000D01*
X728217Y66583D01*
X728592Y66292D01*
X728842Y65875D01*
X728925Y65500D01*
X727175D01*
G01X725658Y65792D02*
X725367Y65583D01*
X725033Y65500D01*
X724700Y65583D01*
X724408Y65833D01*
X724200Y66208D01*
X724117Y66583D01*
Y67042D01*
X724200Y67417D01*
X724408Y67750D01*
X724658Y67917D01*
X724950Y68000D01*
X725283Y67917D01*
X725533Y67750D01*
X725700Y67500D01*
X725783Y67167D01*
X725700Y66875D01*
X725492Y66583D01*
X725242Y66417D01*
X724950Y66375D01*
X724617Y66458D01*
X724367Y66667D01*
X724117Y67042D01*
G01X721850Y65500D02*
Y68000D01*
X722350Y67500D01*
G01Y65500D02*
X721350D01*
G01X712900Y80767D02*
X715400D01*
Y81767D01*
X715275Y82100D01*
X714983Y82350D01*
X714650Y82433D01*
X714317Y82350D01*
X714067Y82142D01*
X713942Y81767D01*
Y80767D01*
G01X712900Y83867D02*
X715400D01*
Y84908D01*
X715275Y85242D01*
X715108Y85450D01*
X714775Y85533D01*
X714442Y85450D01*
X714233Y85200D01*
X714108Y84908D01*
Y83867D01*
G01Y84908D02*
X712900Y85533D01*
G01Y87800D02*
X715400D01*
X714900Y87300D01*
G01X712900D02*
Y88300D01*
G01Y91400D02*
X715400D01*
X713608Y89858D01*
Y91942D01*
G01X712900Y94000D02*
X712942Y94292D01*
X713067Y94625D01*
X713275Y94833D01*
X713567Y94917D01*
X713858Y94833D01*
X714108Y94583D01*
X714233Y94208D01*
Y93792D01*
X714317Y93542D01*
X714525Y93333D01*
X714817Y93250D01*
X715108Y93375D01*
X715317Y93667D01*
X715400Y94000D01*
X715317Y94333D01*
X715108Y94625D01*
X714817Y94750D01*
X714525Y94667D01*
X714317Y94458D01*
X714233Y94208D01*
Y93792D01*
X714108Y93417D01*
X713858Y93167D01*
X713567Y93083D01*
X713275Y93167D01*
X713067Y93375D01*
X712942Y93708D01*
X712900Y94000D01*
G01X731033Y82000D02*
Y84500D01*
X730033D01*
X729700Y84375D01*
X729450Y84083D01*
X729367Y83750D01*
X729450Y83417D01*
X729658Y83167D01*
X730033Y83042D01*
X731033D01*
G01X727933Y82000D02*
Y84500D01*
X726892D01*
X726558Y84375D01*
X726350Y84208D01*
X726267Y83875D01*
X726350Y83542D01*
X726600Y83333D01*
X726892Y83208D01*
X727933D01*
G01X726892D02*
X726267Y82000D01*
G01X724792Y84083D02*
X724542Y84333D01*
X724250Y84458D01*
X723917Y84500D01*
X723500Y84417D01*
X723208Y84208D01*
X723125Y83958D01*
X723167Y83708D01*
X723333Y83500D01*
X724167Y83083D01*
X724542Y82792D01*
X724792Y82375D01*
X724875Y82000D01*
X723125D01*
G01X720900D02*
Y84500D01*
X721400Y84000D01*
G01Y82000D02*
X720400D01*
G01X717800Y84500D02*
X718133Y84417D01*
X718383Y84208D01*
X718550Y83958D01*
X718675Y83625D01*
X718717Y83250D01*
X718675Y82875D01*
X718550Y82542D01*
X718383Y82292D01*
X718133Y82083D01*
X717800Y82000D01*
X717467Y82083D01*
X717217Y82292D01*
X717050Y82542D01*
X716925Y82875D01*
X716883Y83250D01*
X716925Y83625D01*
X717050Y83958D01*
X717217Y84208D01*
X717467Y84417D01*
X717800Y84500D01*
G01X730933Y77500D02*
Y80000D01*
X729933D01*
X729600Y79875D01*
X729350Y79583D01*
X729267Y79250D01*
X729350Y78917D01*
X729558Y78667D01*
X729933Y78542D01*
X730933D01*
G01X727833Y77500D02*
Y80000D01*
X726792D01*
X726458Y79875D01*
X726250Y79708D01*
X726167Y79375D01*
X726250Y79042D01*
X726500Y78833D01*
X726792Y78708D01*
X727833D01*
G01X726792D02*
X726167Y77500D01*
G01X723900D02*
Y80000D01*
X724400Y79500D01*
G01Y77500D02*
X723400D01*
G01X721592Y78542D02*
X721300Y78833D01*
X721050Y79000D01*
X720717Y79083D01*
X720425Y79000D01*
X720217Y78833D01*
X720050Y78583D01*
X720008Y78292D01*
X720050Y78042D01*
X720217Y77792D01*
X720467Y77583D01*
X720758Y77500D01*
X721092Y77583D01*
X721383Y77833D01*
X721550Y78208D01*
X721592Y78625D01*
X721508Y79167D01*
X721383Y79458D01*
X721175Y79750D01*
X720883Y79958D01*
X720592Y80000D01*
X720300Y79917D01*
X720092Y79708D01*
G01X717200Y77500D02*
Y80000D01*
X718742Y78208D01*
X716658D01*
G01X723183Y89792D02*
X723433Y89917D01*
X723725Y90000D01*
X724058D01*
X724433Y89875D01*
X724725Y89667D01*
X724933Y89417D01*
X725100Y89000D01*
X725142Y88625D01*
X725058Y88250D01*
X724933Y88000D01*
X724683Y87750D01*
X724392Y87583D01*
X724100Y87500D01*
X723808D01*
X723517Y87583D01*
X723267Y87708D01*
X723058Y87875D01*
G01X721083Y87500D02*
X721000Y88042D01*
X720875Y88500D01*
X720708Y88917D01*
X720500Y89375D01*
X720167Y90000D01*
X721833D01*
G01X718817Y87875D02*
X718567Y87667D01*
X718275Y87542D01*
X717900Y87500D01*
X717525Y87583D01*
X717233Y87750D01*
X717025Y88042D01*
X716983Y88375D01*
X717067Y88708D01*
X717275Y88917D01*
X717567Y89083D01*
X717858Y89125D01*
X718150Y89083D01*
X718525Y88917D01*
X718400Y90000D01*
X717275D01*
G01X730533Y92000D02*
Y94500D01*
X729533D01*
X729200Y94375D01*
X728950Y94083D01*
X728867Y93750D01*
X728950Y93417D01*
X729158Y93167D01*
X729533Y93042D01*
X730533D01*
G01X725683Y94292D02*
X725933Y94417D01*
X726225Y94500D01*
X726558D01*
X726933Y94375D01*
X727225Y94167D01*
X727433Y93917D01*
X727600Y93500D01*
X727642Y93125D01*
X727558Y92750D01*
X727433Y92500D01*
X727183Y92250D01*
X726892Y92083D01*
X726600Y92000D01*
X726308D01*
X726017Y92083D01*
X725767Y92208D01*
X725558Y92375D01*
G01X723500Y92000D02*
Y94500D01*
X724000Y94000D01*
G01Y92000D02*
X723000D01*
G01X720400D02*
X720108Y92042D01*
X719775Y92167D01*
X719567Y92375D01*
X719483Y92667D01*
X719567Y92958D01*
X719817Y93208D01*
X720192Y93333D01*
X720608D01*
X720858Y93417D01*
X721067Y93625D01*
X721150Y93917D01*
X721025Y94208D01*
X720733Y94417D01*
X720400Y94500D01*
X720067Y94417D01*
X719775Y94208D01*
X719650Y93917D01*
X719733Y93625D01*
X719942Y93417D01*
X720192Y93333D01*
X720608D01*
X720983Y93208D01*
X721233Y92958D01*
X721317Y92667D01*
X721233Y92375D01*
X721025Y92167D01*
X720692Y92042D01*
X720400Y92000D01*
G01X718008Y92292D02*
X717717Y92083D01*
X717383Y92000D01*
X717050Y92083D01*
X716758Y92333D01*
X716550Y92708D01*
X716467Y93083D01*
Y93542D01*
X716550Y93917D01*
X716758Y94250D01*
X717008Y94417D01*
X717300Y94500D01*
X717633Y94417D01*
X717883Y94250D01*
X718050Y94000D01*
X718133Y93667D01*
X718050Y93375D01*
X717842Y93083D01*
X717592Y92917D01*
X717300Y92875D01*
X716967Y92958D01*
X716717Y93167D01*
X716467Y93542D01*
G01X712500Y107967D02*
X715000D01*
Y108967D01*
X714875Y109300D01*
X714583Y109550D01*
X714250Y109633D01*
X713917Y109550D01*
X713667Y109342D01*
X713542Y108967D01*
Y107967D01*
G01X712500Y111067D02*
X715000D01*
Y112108D01*
X714875Y112442D01*
X714708Y112650D01*
X714375Y112733D01*
X714042Y112650D01*
X713833Y112400D01*
X713708Y112108D01*
Y111067D01*
G01Y112108D02*
X712500Y112733D01*
G01X714583Y114208D02*
X714833Y114458D01*
X714958Y114750D01*
X715000Y115083D01*
X714917Y115500D01*
X714708Y115792D01*
X714458Y115875D01*
X714208Y115833D01*
X714000Y115667D01*
X713583Y114833D01*
X713292Y114458D01*
X712875Y114208D01*
X712500Y114125D01*
Y115875D01*
G01Y118100D02*
X715000D01*
X714500Y117600D01*
G01X712500D02*
Y118600D01*
G01Y121700D02*
X715000D01*
X713208Y120158D01*
Y122242D01*
G01X717000Y124967D02*
X719500D01*
Y125967D01*
X719375Y126300D01*
X719083Y126550D01*
X718750Y126633D01*
X718417Y126550D01*
X718167Y126342D01*
X718042Y125967D01*
Y124967D01*
G01X717000Y128067D02*
X719500D01*
Y129108D01*
X719375Y129442D01*
X719208Y129650D01*
X718875Y129733D01*
X718542Y129650D01*
X718333Y129400D01*
X718208Y129108D01*
Y128067D01*
G01Y129108D02*
X717000Y129733D01*
G01Y132000D02*
X719500D01*
X719000Y131500D01*
G01X717000D02*
Y132500D01*
G01Y135600D02*
X719500D01*
X717708Y134058D01*
Y136142D01*
G01X717000Y138700D02*
X719500D01*
X717708Y137158D01*
Y139242D01*
G01X713000Y124967D02*
X715500D01*
Y125967D01*
X715375Y126300D01*
X715083Y126550D01*
X714750Y126633D01*
X714417Y126550D01*
X714167Y126342D01*
X714042Y125967D01*
Y124967D01*
G01X713000Y128067D02*
X715500D01*
Y129108D01*
X715375Y129442D01*
X715208Y129650D01*
X714875Y129733D01*
X714542Y129650D01*
X714333Y129400D01*
X714208Y129108D01*
Y128067D01*
G01Y129108D02*
X713000Y129733D01*
G01Y132000D02*
X715500D01*
X715000Y131500D01*
G01X713000D02*
Y132500D01*
G01Y135600D02*
X715500D01*
X713708Y134058D01*
Y136142D01*
G01X713375Y137283D02*
X713167Y137533D01*
X713042Y137825D01*
X713000Y138200D01*
X713083Y138575D01*
X713250Y138867D01*
X713542Y139075D01*
X713875Y139117D01*
X714208Y139033D01*
X714417Y138825D01*
X714583Y138533D01*
X714625Y138242D01*
X714583Y137950D01*
X714417Y137575D01*
X715500Y137700D01*
Y138825D01*
G01X723000Y156467D02*
X725500D01*
Y157467D01*
X725375Y157800D01*
X725083Y158050D01*
X724750Y158133D01*
X724417Y158050D01*
X724167Y157842D01*
X724042Y157467D01*
Y156467D01*
G01X723000Y159567D02*
X725500D01*
Y160608D01*
X725375Y160942D01*
X725208Y161150D01*
X724875Y161233D01*
X724542Y161150D01*
X724333Y160900D01*
X724208Y160608D01*
Y159567D01*
G01Y160608D02*
X723000Y161233D01*
G01Y163500D02*
X725500D01*
X725000Y163000D01*
G01X723000D02*
Y164000D01*
G01X724042Y165808D02*
X724333Y166100D01*
X724500Y166350D01*
X724583Y166683D01*
X724500Y166975D01*
X724333Y167183D01*
X724083Y167350D01*
X723792Y167392D01*
X723542Y167350D01*
X723292Y167183D01*
X723083Y166933D01*
X723000Y166642D01*
X723083Y166308D01*
X723333Y166017D01*
X723708Y165850D01*
X724125Y165808D01*
X724667Y165892D01*
X724958Y166017D01*
X725250Y166225D01*
X725458Y166517D01*
X725500Y166808D01*
X725417Y167100D01*
X725208Y167308D01*
G01X723000Y169617D02*
X723542Y169700D01*
X724000Y169825D01*
X724417Y169992D01*
X724875Y170200D01*
X725500Y170533D01*
Y168867D01*
G01X726700Y156567D02*
X729200D01*
Y157567D01*
X729075Y157900D01*
X728783Y158150D01*
X728450Y158233D01*
X728117Y158150D01*
X727867Y157942D01*
X727742Y157567D01*
Y156567D01*
G01X726700Y160500D02*
X726742Y160167D01*
X726908Y159875D01*
X727158Y159625D01*
X727450Y159458D01*
X727783Y159375D01*
X728117D01*
X728450Y159458D01*
X728742Y159625D01*
X728992Y159875D01*
X729158Y160167D01*
X729200Y160500D01*
X729158Y160833D01*
X728992Y161125D01*
X728742Y161375D01*
X728450Y161542D01*
X728117Y161625D01*
X727783D01*
X727450Y161542D01*
X727158Y161375D01*
X726908Y161125D01*
X726742Y160833D01*
X726700Y160500D01*
G01X727367Y160833D02*
X726700Y161333D01*
G01X727200Y162683D02*
X726908Y162933D01*
X726742Y163267D01*
X726700Y163642D01*
X726742Y163975D01*
X726950Y164308D01*
X727200Y164517D01*
X727450Y164558D01*
X727742Y164475D01*
X727950Y164183D01*
X728033Y163892D01*
Y163517D01*
G01Y163892D02*
X728158Y164142D01*
X728367Y164350D01*
X728617Y164433D01*
X728867Y164350D01*
X729075Y164142D01*
X729200Y163767D01*
X729158Y163392D01*
X728992Y163017D01*
G01X730933Y172500D02*
Y175000D01*
X729933D01*
X729600Y174875D01*
X729350Y174583D01*
X729267Y174250D01*
X729350Y173917D01*
X729558Y173667D01*
X729933Y173542D01*
X730933D01*
G01X727917Y172500D02*
Y175000D01*
X727083D01*
X726750Y174875D01*
X726500Y174708D01*
X726292Y174458D01*
X726125Y174167D01*
X726083Y173750D01*
X726125Y173333D01*
X726292Y173042D01*
X726500Y172792D01*
X726750Y172625D01*
X727083Y172500D01*
X727917D01*
G01X724692Y174583D02*
X724442Y174833D01*
X724150Y174958D01*
X723817Y175000D01*
X723400Y174917D01*
X723108Y174708D01*
X723025Y174458D01*
X723067Y174208D01*
X723233Y174000D01*
X724067Y173583D01*
X724442Y173292D01*
X724692Y172875D01*
X724775Y172500D01*
X723025D01*
G01X721233Y226792D02*
X721483Y226917D01*
X721775Y227000D01*
X722108D01*
X722483Y226875D01*
X722775Y226667D01*
X722983Y226417D01*
X723150Y226000D01*
X723192Y225625D01*
X723108Y225250D01*
X722983Y225000D01*
X722733Y224750D01*
X722442Y224583D01*
X722150Y224500D01*
X721858D01*
X721567Y224583D01*
X721317Y224708D01*
X721108Y224875D01*
G01X719842Y226583D02*
X719592Y226833D01*
X719300Y226958D01*
X718967Y227000D01*
X718550Y226917D01*
X718258Y226708D01*
X718175Y226458D01*
X718217Y226208D01*
X718383Y226000D01*
X719217Y225583D01*
X719592Y225292D01*
X719842Y224875D01*
X719925Y224500D01*
X718175D01*
G01X716742Y226583D02*
X716492Y226833D01*
X716200Y226958D01*
X715867Y227000D01*
X715450Y226917D01*
X715158Y226708D01*
X715075Y226458D01*
X715117Y226208D01*
X715283Y226000D01*
X716117Y225583D01*
X716492Y225292D01*
X716742Y224875D01*
X716825Y224500D01*
X715075D01*
G01X712850D02*
Y227000D01*
X713350Y226500D01*
G01Y224500D02*
X712350D01*
G01X721233Y222792D02*
X721483Y222917D01*
X721775Y223000D01*
X722108D01*
X722483Y222875D01*
X722775Y222667D01*
X722983Y222417D01*
X723150Y222000D01*
X723192Y221625D01*
X723108Y221250D01*
X722983Y221000D01*
X722733Y220750D01*
X722442Y220583D01*
X722150Y220500D01*
X721858D01*
X721567Y220583D01*
X721317Y220708D01*
X721108Y220875D01*
G01X719842Y222583D02*
X719592Y222833D01*
X719300Y222958D01*
X718967Y223000D01*
X718550Y222917D01*
X718258Y222708D01*
X718175Y222458D01*
X718217Y222208D01*
X718383Y222000D01*
X719217Y221583D01*
X719592Y221292D01*
X719842Y220875D01*
X719925Y220500D01*
X718175D01*
G01X716742Y222583D02*
X716492Y222833D01*
X716200Y222958D01*
X715867Y223000D01*
X715450Y222917D01*
X715158Y222708D01*
X715075Y222458D01*
X715117Y222208D01*
X715283Y222000D01*
X716117Y221583D01*
X716492Y221292D01*
X716742Y220875D01*
X716825Y220500D01*
X715075D01*
G01X712350D02*
Y223000D01*
X713892Y221208D01*
X711808D01*
G01X721233Y218292D02*
X721483Y218417D01*
X721775Y218500D01*
X722108D01*
X722483Y218375D01*
X722775Y218167D01*
X722983Y217917D01*
X723150Y217500D01*
X723192Y217125D01*
X723108Y216750D01*
X722983Y216500D01*
X722733Y216250D01*
X722442Y216083D01*
X722150Y216000D01*
X721858D01*
X721567Y216083D01*
X721317Y216208D01*
X721108Y216375D01*
G01X719050Y216000D02*
Y218500D01*
X719550Y218000D01*
G01Y216000D02*
X718550D01*
G01X716867Y216375D02*
X716617Y216167D01*
X716325Y216042D01*
X715950Y216000D01*
X715575Y216083D01*
X715283Y216250D01*
X715075Y216542D01*
X715033Y216875D01*
X715117Y217208D01*
X715325Y217417D01*
X715617Y217583D01*
X715908Y217625D01*
X716200Y217583D01*
X716575Y217417D01*
X716450Y218500D01*
X715325D01*
G01X712850Y216000D02*
Y218500D01*
X713350Y218000D01*
G01Y216000D02*
X712350D01*
G01X750383Y52507D02*
Y55007D01*
X749342D01*
X749008Y54882D01*
X748800Y54715D01*
X748717Y54382D01*
X748800Y54049D01*
X749050Y53840D01*
X749342Y53715D01*
X750383D01*
G01X749342D02*
X748717Y52507D01*
G01X746450D02*
Y55007D01*
X746950Y54507D01*
G01Y52507D02*
X745950D01*
G01X744058Y52799D02*
X743767Y52590D01*
X743433Y52507D01*
X743100Y52590D01*
X742808Y52840D01*
X742600Y53215D01*
X742517Y53590D01*
Y54049D01*
X742600Y54424D01*
X742808Y54757D01*
X743058Y54924D01*
X743350Y55007D01*
X743683Y54924D01*
X743933Y54757D01*
X744100Y54507D01*
X744183Y54174D01*
X744100Y53882D01*
X743892Y53590D01*
X743642Y53424D01*
X743350Y53382D01*
X743017Y53465D01*
X742767Y53674D01*
X742517Y54049D01*
G01X740250Y52507D02*
X739958Y52549D01*
X739625Y52674D01*
X739417Y52882D01*
X739333Y53174D01*
X739417Y53465D01*
X739667Y53715D01*
X740042Y53840D01*
X740458D01*
X740708Y53924D01*
X740917Y54132D01*
X741000Y54424D01*
X740875Y54715D01*
X740583Y54924D01*
X740250Y55007D01*
X739917Y54924D01*
X739625Y54715D01*
X739500Y54424D01*
X739583Y54132D01*
X739792Y53924D01*
X740042Y53840D01*
X740458D01*
X740833Y53715D01*
X741083Y53465D01*
X741167Y53174D01*
X741083Y52882D01*
X740875Y52674D01*
X740542Y52549D01*
X740250Y52507D01*
G01X747233Y74292D02*
X747483Y74417D01*
X747775Y74500D01*
X748108D01*
X748483Y74375D01*
X748775Y74167D01*
X748983Y73917D01*
X749150Y73500D01*
X749192Y73125D01*
X749108Y72750D01*
X748983Y72500D01*
X748733Y72250D01*
X748442Y72083D01*
X748150Y72000D01*
X747858D01*
X747567Y72083D01*
X747317Y72208D01*
X747108Y72375D01*
G01X745842Y74083D02*
X745592Y74333D01*
X745300Y74458D01*
X744967Y74500D01*
X744550Y74417D01*
X744258Y74208D01*
X744175Y73958D01*
X744217Y73708D01*
X744383Y73500D01*
X745217Y73083D01*
X745592Y72792D01*
X745842Y72375D01*
X745925Y72000D01*
X744175D01*
G01X741950D02*
X741658Y72042D01*
X741325Y72167D01*
X741117Y72375D01*
X741033Y72667D01*
X741117Y72958D01*
X741367Y73208D01*
X741742Y73333D01*
X742158D01*
X742408Y73417D01*
X742617Y73625D01*
X742700Y73917D01*
X742575Y74208D01*
X742283Y74417D01*
X741950Y74500D01*
X741617Y74417D01*
X741325Y74208D01*
X741200Y73917D01*
X741283Y73625D01*
X741492Y73417D01*
X741742Y73333D01*
X742158D01*
X742533Y73208D01*
X742783Y72958D01*
X742867Y72667D01*
X742783Y72375D01*
X742575Y72167D01*
X742242Y72042D01*
X741950Y72000D01*
G01X739558Y72292D02*
X739267Y72083D01*
X738933Y72000D01*
X738600Y72083D01*
X738308Y72333D01*
X738100Y72708D01*
X738017Y73083D01*
Y73542D01*
X738100Y73917D01*
X738308Y74250D01*
X738558Y74417D01*
X738850Y74500D01*
X739183Y74417D01*
X739433Y74250D01*
X739600Y74000D01*
X739683Y73667D01*
X739600Y73375D01*
X739392Y73083D01*
X739142Y72917D01*
X738850Y72875D01*
X738517Y72958D01*
X738267Y73167D01*
X738017Y73542D01*
G01X733500Y78967D02*
X736000D01*
Y79967D01*
X735875Y80300D01*
X735583Y80550D01*
X735250Y80633D01*
X734917Y80550D01*
X734667Y80342D01*
X734542Y79967D01*
Y78967D01*
G01X735792Y83817D02*
X735917Y83567D01*
X736000Y83275D01*
Y82942D01*
X735875Y82567D01*
X735667Y82275D01*
X735417Y82067D01*
X735000Y81900D01*
X734625Y81858D01*
X734250Y81942D01*
X734000Y82067D01*
X733750Y82317D01*
X733583Y82608D01*
X733500Y82900D01*
Y83192D01*
X733583Y83483D01*
X733708Y83733D01*
X733875Y83942D01*
G01X733500Y86000D02*
X736000D01*
X735500Y85500D01*
G01X733500D02*
Y86500D01*
G01X733792Y88392D02*
X733583Y88683D01*
X733500Y89017D01*
X733583Y89350D01*
X733833Y89642D01*
X734208Y89850D01*
X734583Y89933D01*
X735042D01*
X735417Y89850D01*
X735750Y89642D01*
X735917Y89392D01*
X736000Y89100D01*
X735917Y88767D01*
X735750Y88517D01*
X735500Y88350D01*
X735167Y88267D01*
X734875Y88350D01*
X734583Y88558D01*
X734417Y88808D01*
X734375Y89100D01*
X734458Y89433D01*
X734667Y89683D01*
X735042Y89933D01*
G01X736000Y92200D02*
X735917Y91867D01*
X735708Y91617D01*
X735458Y91450D01*
X735125Y91325D01*
X734750Y91283D01*
X734375Y91325D01*
X734042Y91450D01*
X733792Y91617D01*
X733583Y91867D01*
X733500Y92200D01*
X733583Y92533D01*
X733792Y92783D01*
X734042Y92950D01*
X734375Y93075D01*
X734750Y93117D01*
X735125Y93075D01*
X735458Y92950D01*
X735708Y92783D01*
X735917Y92533D01*
X736000Y92200D01*
G01X737500Y78967D02*
X740000D01*
Y79967D01*
X739875Y80300D01*
X739583Y80550D01*
X739250Y80633D01*
X738917Y80550D01*
X738667Y80342D01*
X738542Y79967D01*
Y78967D01*
G01X737500Y82067D02*
X740000D01*
Y83108D01*
X739875Y83442D01*
X739708Y83650D01*
X739375Y83733D01*
X739042Y83650D01*
X738833Y83400D01*
X738708Y83108D01*
Y82067D01*
G01Y83108D02*
X737500Y83733D01*
G01X739583Y85208D02*
X739833Y85458D01*
X739958Y85750D01*
X740000Y86083D01*
X739917Y86500D01*
X739708Y86792D01*
X739458Y86875D01*
X739208Y86833D01*
X739000Y86667D01*
X738583Y85833D01*
X738292Y85458D01*
X737875Y85208D01*
X737500Y85125D01*
Y86875D01*
G01Y89100D02*
X740000D01*
X739500Y88600D01*
G01X737500D02*
Y89600D01*
G01X739583Y91408D02*
X739833Y91658D01*
X739958Y91950D01*
X740000Y92283D01*
X739917Y92700D01*
X739708Y92992D01*
X739458Y93075D01*
X739208Y93033D01*
X739000Y92867D01*
X738583Y92033D01*
X738292Y91658D01*
X737875Y91408D01*
X737500Y91325D01*
Y93075D01*
G01X741500Y78967D02*
X744000D01*
Y79967D01*
X743875Y80300D01*
X743583Y80550D01*
X743250Y80633D01*
X742917Y80550D01*
X742667Y80342D01*
X742542Y79967D01*
Y78967D01*
G01X741500Y82067D02*
X744000D01*
Y83108D01*
X743875Y83442D01*
X743708Y83650D01*
X743375Y83733D01*
X743042Y83650D01*
X742833Y83400D01*
X742708Y83108D01*
Y82067D01*
G01Y83108D02*
X741500Y83733D01*
G01X743583Y85208D02*
X743833Y85458D01*
X743958Y85750D01*
X744000Y86083D01*
X743917Y86500D01*
X743708Y86792D01*
X743458Y86875D01*
X743208Y86833D01*
X743000Y86667D01*
X742583Y85833D01*
X742292Y85458D01*
X741875Y85208D01*
X741500Y85125D01*
Y86875D01*
G01Y89100D02*
X744000D01*
X743500Y88600D01*
G01X741500D02*
Y89600D01*
G01X742542Y91408D02*
X742833Y91700D01*
X743000Y91950D01*
X743083Y92283D01*
X743000Y92575D01*
X742833Y92783D01*
X742583Y92950D01*
X742292Y92992D01*
X742042Y92950D01*
X741792Y92783D01*
X741583Y92533D01*
X741500Y92242D01*
X741583Y91908D01*
X741833Y91617D01*
X742208Y91450D01*
X742625Y91408D01*
X743167Y91492D01*
X743458Y91617D01*
X743750Y91825D01*
X743958Y92117D01*
X744000Y92408D01*
X743917Y92700D01*
X743708Y92908D01*
G01X746483Y140500D02*
Y143000D01*
X745483D01*
X745150Y142875D01*
X744900Y142583D01*
X744817Y142250D01*
X744900Y141917D01*
X745108Y141667D01*
X745483Y141542D01*
X746483D01*
G01X741633Y142792D02*
X741883Y142917D01*
X742175Y143000D01*
X742508D01*
X742883Y142875D01*
X743175Y142667D01*
X743383Y142417D01*
X743550Y142000D01*
X743592Y141625D01*
X743508Y141250D01*
X743383Y141000D01*
X743133Y140750D01*
X742842Y140583D01*
X742550Y140500D01*
X742258D01*
X741967Y140583D01*
X741717Y140708D01*
X741508Y140875D01*
G01X740158Y140792D02*
X739867Y140583D01*
X739533Y140500D01*
X739200Y140583D01*
X738908Y140833D01*
X738700Y141208D01*
X738617Y141583D01*
Y142042D01*
X738700Y142417D01*
X738908Y142750D01*
X739158Y142917D01*
X739450Y143000D01*
X739783Y142917D01*
X740033Y142750D01*
X740200Y142500D01*
X740283Y142167D01*
X740200Y141875D01*
X739992Y141583D01*
X739742Y141417D01*
X739450Y141375D01*
X739117Y141458D01*
X738867Y141667D01*
X738617Y142042D01*
G01X737058Y140792D02*
X736767Y140583D01*
X736433Y140500D01*
X736100Y140583D01*
X735808Y140833D01*
X735600Y141208D01*
X735517Y141583D01*
Y142042D01*
X735600Y142417D01*
X735808Y142750D01*
X736058Y142917D01*
X736350Y143000D01*
X736683Y142917D01*
X736933Y142750D01*
X737100Y142500D01*
X737183Y142167D01*
X737100Y141875D01*
X736892Y141583D01*
X736642Y141417D01*
X736350Y141375D01*
X736017Y141458D01*
X735767Y141667D01*
X735517Y142042D01*
G01X746483Y148500D02*
Y151000D01*
X745483D01*
X745150Y150875D01*
X744900Y150583D01*
X744817Y150250D01*
X744900Y149917D01*
X745108Y149667D01*
X745483Y149542D01*
X746483D01*
G01X741633Y150792D02*
X741883Y150917D01*
X742175Y151000D01*
X742508D01*
X742883Y150875D01*
X743175Y150667D01*
X743383Y150417D01*
X743550Y150000D01*
X743592Y149625D01*
X743508Y149250D01*
X743383Y149000D01*
X743133Y148750D01*
X742842Y148583D01*
X742550Y148500D01*
X742258D01*
X741967Y148583D01*
X741717Y148708D01*
X741508Y148875D01*
G01X740158Y148792D02*
X739867Y148583D01*
X739533Y148500D01*
X739200Y148583D01*
X738908Y148833D01*
X738700Y149208D01*
X738617Y149583D01*
Y150042D01*
X738700Y150417D01*
X738908Y150750D01*
X739158Y150917D01*
X739450Y151000D01*
X739783Y150917D01*
X740033Y150750D01*
X740200Y150500D01*
X740283Y150167D01*
X740200Y149875D01*
X739992Y149583D01*
X739742Y149417D01*
X739450Y149375D01*
X739117Y149458D01*
X738867Y149667D01*
X738617Y150042D01*
G01X736433Y148500D02*
X736350Y149042D01*
X736225Y149500D01*
X736058Y149917D01*
X735850Y150375D01*
X735517Y151000D01*
X737183D01*
G01X746483Y144500D02*
Y147000D01*
X745483D01*
X745150Y146875D01*
X744900Y146583D01*
X744817Y146250D01*
X744900Y145917D01*
X745108Y145667D01*
X745483Y145542D01*
X746483D01*
G01X743383Y144500D02*
Y147000D01*
X742342D01*
X742008Y146875D01*
X741800Y146708D01*
X741717Y146375D01*
X741800Y146042D01*
X742050Y145833D01*
X742342Y145708D01*
X743383D01*
G01X742342D02*
X741717Y144500D01*
G01X739450D02*
Y147000D01*
X739950Y146500D01*
G01Y144500D02*
X738950D01*
G01X735850D02*
Y147000D01*
X737392Y145208D01*
X735308D01*
G01X733250Y144500D02*
Y147000D01*
X733750Y146500D01*
G01Y144500D02*
X732750D01*
G01X744683Y156000D02*
Y158500D01*
X743683D01*
X743350Y158375D01*
X743100Y158083D01*
X743017Y157750D01*
X743100Y157417D01*
X743308Y157167D01*
X743683Y157042D01*
X744683D01*
G01X739833Y158292D02*
X740083Y158417D01*
X740375Y158500D01*
X740708D01*
X741083Y158375D01*
X741375Y158167D01*
X741583Y157917D01*
X741750Y157500D01*
X741792Y157125D01*
X741708Y156750D01*
X741583Y156500D01*
X741333Y156250D01*
X741042Y156083D01*
X740750Y156000D01*
X740458D01*
X740167Y156083D01*
X739917Y156208D01*
X739708Y156375D01*
G01X737650Y156000D02*
Y158500D01*
X738150Y158000D01*
G01Y156000D02*
X737150D01*
G01X734550D02*
Y158500D01*
X735050Y158000D01*
G01Y156000D02*
X734050D01*
G01X731450D02*
Y158500D01*
X731950Y158000D01*
G01Y156000D02*
X730950D01*
G01X745483Y160500D02*
Y163000D01*
X744442D01*
X744108Y162875D01*
X743900Y162708D01*
X743817Y162375D01*
X743900Y162042D01*
X744150Y161833D01*
X744442Y161708D01*
X745483D01*
G01X744442D02*
X743817Y160500D01*
G01X741550D02*
Y163000D01*
X742050Y162500D01*
G01Y160500D02*
X741050D01*
G01X739367Y160875D02*
X739117Y160667D01*
X738825Y160542D01*
X738450Y160500D01*
X738075Y160583D01*
X737783Y160750D01*
X737575Y161042D01*
X737533Y161375D01*
X737617Y161708D01*
X737825Y161917D01*
X738117Y162083D01*
X738408Y162125D01*
X738700Y162083D01*
X739075Y161917D01*
X738950Y163000D01*
X737825D01*
G01X736267Y161000D02*
X736017Y160708D01*
X735683Y160542D01*
X735308Y160500D01*
X734975Y160542D01*
X734642Y160750D01*
X734433Y161000D01*
X734392Y161250D01*
X734475Y161542D01*
X734767Y161750D01*
X735058Y161833D01*
X735433D01*
G01X735058D02*
X734808Y161958D01*
X734600Y162167D01*
X734517Y162417D01*
X734600Y162667D01*
X734808Y162875D01*
X735183Y163000D01*
X735558Y162958D01*
X735933Y162792D01*
G01X745483Y164500D02*
Y167000D01*
X744442D01*
X744108Y166875D01*
X743900Y166708D01*
X743817Y166375D01*
X743900Y166042D01*
X744150Y165833D01*
X744442Y165708D01*
X745483D01*
G01X744442D02*
X743817Y164500D01*
G01X741550D02*
Y167000D01*
X742050Y166500D01*
G01Y164500D02*
X741050D01*
G01X739367Y164875D02*
X739117Y164667D01*
X738825Y164542D01*
X738450Y164500D01*
X738075Y164583D01*
X737783Y164750D01*
X737575Y165042D01*
X737533Y165375D01*
X737617Y165708D01*
X737825Y165917D01*
X738117Y166083D01*
X738408Y166125D01*
X738700Y166083D01*
X739075Y165917D01*
X738950Y167000D01*
X737825D01*
G01X734850Y164500D02*
Y167000D01*
X736392Y165208D01*
X734308D01*
G01X745483Y168500D02*
Y171000D01*
X744442D01*
X744108Y170875D01*
X743900Y170708D01*
X743817Y170375D01*
X743900Y170042D01*
X744150Y169833D01*
X744442Y169708D01*
X745483D01*
G01X744442D02*
X743817Y168500D01*
G01X741550D02*
Y171000D01*
X742050Y170500D01*
G01Y168500D02*
X741050D01*
G01X739367Y168875D02*
X739117Y168667D01*
X738825Y168542D01*
X738450Y168500D01*
X738075Y168583D01*
X737783Y168750D01*
X737575Y169042D01*
X737533Y169375D01*
X737617Y169708D01*
X737825Y169917D01*
X738117Y170083D01*
X738408Y170125D01*
X738700Y170083D01*
X739075Y169917D01*
X738950Y171000D01*
X737825D01*
G01X736267Y168875D02*
X736017Y168667D01*
X735725Y168542D01*
X735350Y168500D01*
X734975Y168583D01*
X734683Y168750D01*
X734475Y169042D01*
X734433Y169375D01*
X734517Y169708D01*
X734725Y169917D01*
X735017Y170083D01*
X735308Y170125D01*
X735600Y170083D01*
X735975Y169917D01*
X735850Y171000D01*
X734725D01*
G01X745483Y172500D02*
Y175000D01*
X744442D01*
X744108Y174875D01*
X743900Y174708D01*
X743817Y174375D01*
X743900Y174042D01*
X744150Y173833D01*
X744442Y173708D01*
X745483D01*
G01X744442D02*
X743817Y172500D01*
G01X741550D02*
Y175000D01*
X742050Y174500D01*
G01Y172500D02*
X741050D01*
G01X739367Y172875D02*
X739117Y172667D01*
X738825Y172542D01*
X738450Y172500D01*
X738075Y172583D01*
X737783Y172750D01*
X737575Y173042D01*
X737533Y173375D01*
X737617Y173708D01*
X737825Y173917D01*
X738117Y174083D01*
X738408Y174125D01*
X738700Y174083D01*
X739075Y173917D01*
X738950Y175000D01*
X737825D01*
G01X736142Y173542D02*
X735850Y173833D01*
X735600Y174000D01*
X735267Y174083D01*
X734975Y174000D01*
X734767Y173833D01*
X734600Y173583D01*
X734558Y173292D01*
X734600Y173042D01*
X734767Y172792D01*
X735017Y172583D01*
X735308Y172500D01*
X735642Y172583D01*
X735933Y172833D01*
X736100Y173208D01*
X736142Y173625D01*
X736058Y174167D01*
X735933Y174458D01*
X735725Y174750D01*
X735433Y174958D01*
X735142Y175000D01*
X734850Y174917D01*
X734642Y174708D01*
G01X744433Y191500D02*
Y194000D01*
X743433D01*
X743100Y193875D01*
X742850Y193583D01*
X742767Y193250D01*
X742850Y192917D01*
X743058Y192667D01*
X743433Y192542D01*
X744433D01*
G01X739583Y193792D02*
X739833Y193917D01*
X740125Y194000D01*
X740458D01*
X740833Y193875D01*
X741125Y193667D01*
X741333Y193417D01*
X741500Y193000D01*
X741542Y192625D01*
X741458Y192250D01*
X741333Y192000D01*
X741083Y191750D01*
X740792Y191583D01*
X740500Y191500D01*
X740208D01*
X739917Y191583D01*
X739667Y191708D01*
X739458Y191875D01*
G01X737400Y191500D02*
Y194000D01*
X737900Y193500D01*
G01Y191500D02*
X736900D01*
G01X734383D02*
X734300Y192042D01*
X734175Y192500D01*
X734008Y192917D01*
X733800Y193375D01*
X733467Y194000D01*
X735133D01*
G01X731283Y191500D02*
X731200Y192042D01*
X731075Y192500D01*
X730908Y192917D01*
X730700Y193375D01*
X730367Y194000D01*
X732033D01*
G01X744333Y196000D02*
Y198500D01*
X743333D01*
X743000Y198375D01*
X742750Y198083D01*
X742667Y197750D01*
X742750Y197417D01*
X742958Y197167D01*
X743333Y197042D01*
X744333D01*
G01X739483Y198292D02*
X739733Y198417D01*
X740025Y198500D01*
X740358D01*
X740733Y198375D01*
X741025Y198167D01*
X741233Y197917D01*
X741400Y197500D01*
X741442Y197125D01*
X741358Y196750D01*
X741233Y196500D01*
X740983Y196250D01*
X740692Y196083D01*
X740400Y196000D01*
X740108D01*
X739817Y196083D01*
X739567Y196208D01*
X739358Y196375D01*
G01X737300Y196000D02*
Y198500D01*
X737800Y198000D01*
G01Y196000D02*
X736800D01*
G01X734992Y197042D02*
X734700Y197333D01*
X734450Y197500D01*
X734117Y197583D01*
X733825Y197500D01*
X733617Y197333D01*
X733450Y197083D01*
X733408Y196792D01*
X733450Y196542D01*
X733617Y196292D01*
X733867Y196083D01*
X734158Y196000D01*
X734492Y196083D01*
X734783Y196333D01*
X734950Y196708D01*
X734992Y197125D01*
X734908Y197667D01*
X734783Y197958D01*
X734575Y198250D01*
X734283Y198458D01*
X733992Y198500D01*
X733700Y198417D01*
X733492Y198208D01*
G01X732017Y196500D02*
X731767Y196208D01*
X731433Y196042D01*
X731058Y196000D01*
X730725Y196042D01*
X730392Y196250D01*
X730183Y196500D01*
X730142Y196750D01*
X730225Y197042D01*
X730517Y197250D01*
X730808Y197333D01*
X731183D01*
G01X730808D02*
X730558Y197458D01*
X730350Y197667D01*
X730267Y197917D01*
X730350Y198167D01*
X730558Y198375D01*
X730933Y198500D01*
X731308Y198458D01*
X731683Y198292D01*
G01X743533Y201000D02*
Y203500D01*
X742533D01*
X742200Y203375D01*
X741950Y203083D01*
X741867Y202750D01*
X741950Y202417D01*
X742158Y202167D01*
X742533Y202042D01*
X743533D01*
G01X738683Y203292D02*
X738933Y203417D01*
X739225Y203500D01*
X739558D01*
X739933Y203375D01*
X740225Y203167D01*
X740433Y202917D01*
X740600Y202500D01*
X740642Y202125D01*
X740558Y201750D01*
X740433Y201500D01*
X740183Y201250D01*
X739892Y201083D01*
X739600Y201000D01*
X739308D01*
X739017Y201083D01*
X738767Y201208D01*
X738558Y201375D01*
G01X736500Y201000D02*
Y203500D01*
X737000Y203000D01*
G01Y201000D02*
X736000D01*
G01X734317Y201375D02*
X734067Y201167D01*
X733775Y201042D01*
X733400Y201000D01*
X733025Y201083D01*
X732733Y201250D01*
X732525Y201542D01*
X732483Y201875D01*
X732567Y202208D01*
X732775Y202417D01*
X733067Y202583D01*
X733358Y202625D01*
X733650Y202583D01*
X734025Y202417D01*
X733900Y203500D01*
X732775D01*
G01X731092Y202042D02*
X730800Y202333D01*
X730550Y202500D01*
X730217Y202583D01*
X729925Y202500D01*
X729717Y202333D01*
X729550Y202083D01*
X729508Y201792D01*
X729550Y201542D01*
X729717Y201292D01*
X729967Y201083D01*
X730258Y201000D01*
X730592Y201083D01*
X730883Y201333D01*
X731050Y201708D01*
X731092Y202125D01*
X731008Y202667D01*
X730883Y202958D01*
X730675Y203250D01*
X730383Y203458D01*
X730092Y203500D01*
X729800Y203417D01*
X729592Y203208D01*
G01X744033Y209500D02*
Y212000D01*
X743033D01*
X742700Y211875D01*
X742450Y211583D01*
X742367Y211250D01*
X742450Y210917D01*
X742658Y210667D01*
X743033Y210542D01*
X744033D01*
G01X739183Y211792D02*
X739433Y211917D01*
X739725Y212000D01*
X740058D01*
X740433Y211875D01*
X740725Y211667D01*
X740933Y211417D01*
X741100Y211000D01*
X741142Y210625D01*
X741058Y210250D01*
X740933Y210000D01*
X740683Y209750D01*
X740392Y209583D01*
X740100Y209500D01*
X739808D01*
X739517Y209583D01*
X739267Y209708D01*
X739058Y209875D01*
G01X737000Y209500D02*
Y212000D01*
X737500Y211500D01*
G01Y209500D02*
X736500D01*
G01X734692Y210542D02*
X734400Y210833D01*
X734150Y211000D01*
X733817Y211083D01*
X733525Y211000D01*
X733317Y210833D01*
X733150Y210583D01*
X733108Y210292D01*
X733150Y210042D01*
X733317Y209792D01*
X733567Y209583D01*
X733858Y209500D01*
X734192Y209583D01*
X734483Y209833D01*
X734650Y210208D01*
X734692Y210625D01*
X734608Y211167D01*
X734483Y211458D01*
X734275Y211750D01*
X733983Y211958D01*
X733692Y212000D01*
X733400Y211917D01*
X733192Y211708D01*
G01X730800Y209500D02*
X730508Y209542D01*
X730175Y209667D01*
X729967Y209875D01*
X729883Y210167D01*
X729967Y210458D01*
X730217Y210708D01*
X730592Y210833D01*
X731008D01*
X731258Y210917D01*
X731467Y211125D01*
X731550Y211417D01*
X731425Y211708D01*
X731133Y211917D01*
X730800Y212000D01*
X730467Y211917D01*
X730175Y211708D01*
X730050Y211417D01*
X730133Y211125D01*
X730342Y210917D01*
X730592Y210833D01*
X731008D01*
X731383Y210708D01*
X731633Y210458D01*
X731717Y210167D01*
X731633Y209875D01*
X731425Y209667D01*
X731092Y209542D01*
X730800Y209500D01*
G01X744533Y205000D02*
Y207500D01*
X743533D01*
X743200Y207375D01*
X742950Y207083D01*
X742867Y206750D01*
X742950Y206417D01*
X743158Y206167D01*
X743533Y206042D01*
X744533D01*
G01X739683Y207292D02*
X739933Y207417D01*
X740225Y207500D01*
X740558D01*
X740933Y207375D01*
X741225Y207167D01*
X741433Y206917D01*
X741600Y206500D01*
X741642Y206125D01*
X741558Y205750D01*
X741433Y205500D01*
X741183Y205250D01*
X740892Y205083D01*
X740600Y205000D01*
X740308D01*
X740017Y205083D01*
X739767Y205208D01*
X739558Y205375D01*
G01X737500Y205000D02*
Y207500D01*
X738000Y207000D01*
G01Y205000D02*
X737000D01*
G01X735317Y205375D02*
X735067Y205167D01*
X734775Y205042D01*
X734400Y205000D01*
X734025Y205083D01*
X733733Y205250D01*
X733525Y205542D01*
X733483Y205875D01*
X733567Y206208D01*
X733775Y206417D01*
X734067Y206583D01*
X734358Y206625D01*
X734650Y206583D01*
X735025Y206417D01*
X734900Y207500D01*
X733775D01*
G01X731300Y205000D02*
X731008Y205042D01*
X730675Y205167D01*
X730467Y205375D01*
X730383Y205667D01*
X730467Y205958D01*
X730717Y206208D01*
X731092Y206333D01*
X731508D01*
X731758Y206417D01*
X731967Y206625D01*
X732050Y206917D01*
X731925Y207208D01*
X731633Y207417D01*
X731300Y207500D01*
X730967Y207417D01*
X730675Y207208D01*
X730550Y206917D01*
X730633Y206625D01*
X730842Y206417D01*
X731092Y206333D01*
X731508D01*
X731883Y206208D01*
X732133Y205958D01*
X732217Y205667D01*
X732133Y205375D01*
X731925Y205167D01*
X731592Y205042D01*
X731300Y205000D01*
G01X742983Y213500D02*
Y216000D01*
X741942D01*
X741608Y215875D01*
X741400Y215708D01*
X741317Y215375D01*
X741400Y215042D01*
X741650Y214833D01*
X741942Y214708D01*
X742983D01*
G01X741942D02*
X741317Y213500D01*
G01X738550D02*
Y216000D01*
X740092Y214208D01*
X738008D01*
G01X735950Y216000D02*
X736283Y215917D01*
X736533Y215708D01*
X736700Y215458D01*
X736825Y215125D01*
X736867Y214750D01*
X736825Y214375D01*
X736700Y214042D01*
X736533Y213792D01*
X736283Y213583D01*
X735950Y213500D01*
X735617Y213583D01*
X735367Y213792D01*
X735200Y214042D01*
X735075Y214375D01*
X735033Y214750D01*
X735075Y215125D01*
X735200Y215458D01*
X735367Y215708D01*
X735617Y215917D01*
X735950Y216000D01*
G01X732850D02*
X733183Y215917D01*
X733433Y215708D01*
X733600Y215458D01*
X733725Y215125D01*
X733767Y214750D01*
X733725Y214375D01*
X733600Y214042D01*
X733433Y213792D01*
X733183Y213583D01*
X732850Y213500D01*
X732517Y213583D01*
X732267Y213792D01*
X732100Y214042D01*
X731975Y214375D01*
X731933Y214750D01*
X731975Y215125D01*
X732100Y215458D01*
X732267Y215708D01*
X732517Y215917D01*
X732850Y216000D01*
G01X734292Y230767D02*
X734417Y230517D01*
X734500Y230225D01*
Y229892D01*
X734375Y229517D01*
X734167Y229225D01*
X733917Y229017D01*
X733500Y228850D01*
X733125Y228808D01*
X732750Y228892D01*
X732500Y229017D01*
X732250Y229267D01*
X732083Y229558D01*
X732000Y229850D01*
Y230142D01*
X732083Y230433D01*
X732208Y230683D01*
X732375Y230892D01*
G01X732000Y232950D02*
X734500D01*
X734000Y232450D01*
G01X732000D02*
Y233450D01*
G01X734500Y236050D02*
X734417Y235717D01*
X734208Y235467D01*
X733958Y235300D01*
X733625Y235175D01*
X733250Y235133D01*
X732875Y235175D01*
X732542Y235300D01*
X732292Y235467D01*
X732083Y235717D01*
X732000Y236050D01*
X732083Y236383D01*
X732292Y236633D01*
X732542Y236800D01*
X732875Y236925D01*
X733250Y236967D01*
X733625Y236925D01*
X733958Y236800D01*
X734208Y236633D01*
X734417Y236383D01*
X734500Y236050D01*
G01X732000Y239067D02*
X732542Y239150D01*
X733000Y239275D01*
X733417Y239442D01*
X733875Y239650D01*
X734500Y239983D01*
Y238317D01*
G01X730292Y230767D02*
X730417Y230517D01*
X730500Y230225D01*
Y229892D01*
X730375Y229517D01*
X730167Y229225D01*
X729917Y229017D01*
X729500Y228850D01*
X729125Y228808D01*
X728750Y228892D01*
X728500Y229017D01*
X728250Y229267D01*
X728083Y229558D01*
X728000Y229850D01*
Y230142D01*
X728083Y230433D01*
X728208Y230683D01*
X728375Y230892D01*
G01X728500Y232033D02*
X728208Y232283D01*
X728042Y232617D01*
X728000Y232992D01*
X728042Y233325D01*
X728250Y233658D01*
X728500Y233867D01*
X728750Y233908D01*
X729042Y233825D01*
X729250Y233533D01*
X729333Y233242D01*
Y232867D01*
G01Y233242D02*
X729458Y233492D01*
X729667Y233700D01*
X729917Y233783D01*
X730167Y233700D01*
X730375Y233492D01*
X730500Y233117D01*
X730458Y232742D01*
X730292Y232367D01*
G01X728375Y235133D02*
X728167Y235383D01*
X728042Y235675D01*
X728000Y236050D01*
X728083Y236425D01*
X728250Y236717D01*
X728542Y236925D01*
X728875Y236967D01*
X729208Y236883D01*
X729417Y236675D01*
X729583Y236383D01*
X729625Y236092D01*
X729583Y235800D01*
X729417Y235425D01*
X730500Y235550D01*
Y236675D01*
G01X730083Y238358D02*
X730333Y238608D01*
X730458Y238900D01*
X730500Y239233D01*
X730417Y239650D01*
X730208Y239942D01*
X729958Y240025D01*
X729708Y239983D01*
X729500Y239817D01*
X729083Y238983D01*
X728792Y238608D01*
X728375Y238358D01*
X728000Y238275D01*
Y240025D01*
G01X742100Y225500D02*
X742433Y225542D01*
X742725Y225708D01*
X742975Y225958D01*
X743142Y226250D01*
X743225Y226583D01*
Y226917D01*
X743142Y227250D01*
X742975Y227542D01*
X742725Y227792D01*
X742433Y227958D01*
X742100Y228000D01*
X741767Y227958D01*
X741475Y227792D01*
X741225Y227542D01*
X741058Y227250D01*
X740975Y226917D01*
Y226583D01*
X741058Y226250D01*
X741225Y225958D01*
X741475Y225708D01*
X741767Y225542D01*
X742100Y225500D01*
G01X741767Y226167D02*
X741267Y225500D01*
G01X739000D02*
Y228000D01*
X739500Y227500D01*
G01Y225500D02*
X738500D01*
G01X736817Y226000D02*
X736567Y225708D01*
X736233Y225542D01*
X735858Y225500D01*
X735525Y225542D01*
X735192Y225750D01*
X734983Y226000D01*
X734942Y226250D01*
X735025Y226542D01*
X735317Y226750D01*
X735608Y226833D01*
X735983D01*
G01X735608D02*
X735358Y226958D01*
X735150Y227167D01*
X735067Y227417D01*
X735150Y227667D01*
X735358Y227875D01*
X735733Y228000D01*
X736108Y227958D01*
X736483Y227792D01*
G01X742983Y221500D02*
Y224000D01*
X741942D01*
X741608Y223875D01*
X741400Y223708D01*
X741317Y223375D01*
X741400Y223042D01*
X741650Y222833D01*
X741942Y222708D01*
X742983D01*
G01X741942D02*
X741317Y221500D01*
G01X738550D02*
Y224000D01*
X740092Y222208D01*
X738008D01*
G01X735950Y221500D02*
Y224000D01*
X736450Y223500D01*
G01Y221500D02*
X735450D01*
G01X732850Y224000D02*
X733183Y223917D01*
X733433Y223708D01*
X733600Y223458D01*
X733725Y223125D01*
X733767Y222750D01*
X733725Y222375D01*
X733600Y222042D01*
X733433Y221792D01*
X733183Y221583D01*
X732850Y221500D01*
X732517Y221583D01*
X732267Y221792D01*
X732100Y222042D01*
X731975Y222375D01*
X731933Y222750D01*
X731975Y223125D01*
X732100Y223458D01*
X732267Y223708D01*
X732517Y223917D01*
X732850Y224000D01*
G01X742933Y217500D02*
Y220000D01*
X741892D01*
X741558Y219875D01*
X741350Y219708D01*
X741267Y219375D01*
X741350Y219042D01*
X741600Y218833D01*
X741892Y218708D01*
X742933D01*
G01X741892D02*
X741267Y217500D01*
G01X739000D02*
X738708Y217542D01*
X738375Y217667D01*
X738167Y217875D01*
X738083Y218167D01*
X738167Y218458D01*
X738417Y218708D01*
X738792Y218833D01*
X739208D01*
X739458Y218917D01*
X739667Y219125D01*
X739750Y219417D01*
X739625Y219708D01*
X739333Y219917D01*
X739000Y220000D01*
X738667Y219917D01*
X738375Y219708D01*
X738250Y219417D01*
X738333Y219125D01*
X738542Y218917D01*
X738792Y218833D01*
X739208D01*
X739583Y218708D01*
X739833Y218458D01*
X739917Y218167D01*
X739833Y217875D01*
X739625Y217667D01*
X739292Y217542D01*
X739000Y217500D01*
G01X736817Y217875D02*
X736567Y217667D01*
X736275Y217542D01*
X735900Y217500D01*
X735525Y217583D01*
X735233Y217750D01*
X735025Y218042D01*
X734983Y218375D01*
X735067Y218708D01*
X735275Y218917D01*
X735567Y219083D01*
X735858Y219125D01*
X736150Y219083D01*
X736525Y218917D01*
X736400Y220000D01*
X735275D01*
G01X756258Y-1284D02*
Y2716D01*
X758258Y716D01*
X754258D01*
X756258Y2716D01*
G01X765042Y5583D02*
X764792Y5833D01*
X764500Y5958D01*
X764167Y6000D01*
X763750Y5917D01*
X763458Y5708D01*
X763375Y5458D01*
X763417Y5208D01*
X763583Y5000D01*
X764417Y4583D01*
X764792Y4292D01*
X765042Y3875D01*
X765125Y3500D01*
X763375D01*
G01X761150Y6000D02*
X761483Y5917D01*
X761733Y5708D01*
X761900Y5458D01*
X762025Y5125D01*
X762067Y4750D01*
X762025Y4375D01*
X761900Y4042D01*
X761733Y3792D01*
X761483Y3583D01*
X761150Y3500D01*
X760817Y3583D01*
X760567Y3792D01*
X760400Y4042D01*
X760275Y4375D01*
X760233Y4750D01*
X760275Y5125D01*
X760400Y5458D01*
X760567Y5708D01*
X760817Y5917D01*
X761150Y6000D01*
G01X757550Y3500D02*
Y6000D01*
X759092Y4208D01*
X757008D01*
G01X749500Y85467D02*
X752000D01*
Y86467D01*
X751875Y86800D01*
X751583Y87050D01*
X751250Y87133D01*
X750917Y87050D01*
X750667Y86842D01*
X750542Y86467D01*
Y85467D01*
G01X749500Y88567D02*
X752000D01*
Y89608D01*
X751875Y89942D01*
X751708Y90150D01*
X751375Y90233D01*
X751042Y90150D01*
X750833Y89900D01*
X750708Y89608D01*
Y88567D01*
G01Y89608D02*
X749500Y90233D01*
G01Y92500D02*
X752000D01*
X751500Y92000D01*
G01X749500D02*
Y93000D01*
G01X749875Y94683D02*
X749667Y94933D01*
X749542Y95225D01*
X749500Y95600D01*
X749583Y95975D01*
X749750Y96267D01*
X750042Y96475D01*
X750375Y96517D01*
X750708Y96433D01*
X750917Y96225D01*
X751083Y95933D01*
X751125Y95642D01*
X751083Y95350D01*
X750917Y94975D01*
X752000Y95100D01*
Y96225D01*
G01X749500Y99200D02*
X752000D01*
X750208Y97658D01*
Y99742D01*
G01X745500Y78967D02*
X748000D01*
Y79967D01*
X747875Y80300D01*
X747583Y80550D01*
X747250Y80633D01*
X746917Y80550D01*
X746667Y80342D01*
X746542Y79967D01*
Y78967D01*
G01X745500Y82067D02*
X748000D01*
Y83108D01*
X747875Y83442D01*
X747708Y83650D01*
X747375Y83733D01*
X747042Y83650D01*
X746833Y83400D01*
X746708Y83108D01*
Y82067D01*
G01Y83108D02*
X745500Y83733D01*
G01X747583Y85208D02*
X747833Y85458D01*
X747958Y85750D01*
X748000Y86083D01*
X747917Y86500D01*
X747708Y86792D01*
X747458Y86875D01*
X747208Y86833D01*
X747000Y86667D01*
X746583Y85833D01*
X746292Y85458D01*
X745875Y85208D01*
X745500Y85125D01*
Y86875D01*
G01Y89100D02*
X748000D01*
X747500Y88600D01*
G01X745500D02*
Y89600D01*
G01X745875Y91283D02*
X745667Y91533D01*
X745542Y91825D01*
X745500Y92200D01*
X745583Y92575D01*
X745750Y92867D01*
X746042Y93075D01*
X746375Y93117D01*
X746708Y93033D01*
X746917Y92825D01*
X747083Y92533D01*
X747125Y92242D01*
X747083Y91950D01*
X746917Y91575D01*
X748000Y91700D01*
Y92825D01*
G01X756500Y121467D02*
X759000D01*
Y122467D01*
X758875Y122800D01*
X758583Y123050D01*
X758250Y123133D01*
X757917Y123050D01*
X757667Y122842D01*
X757542Y122467D01*
Y121467D01*
G01X758792Y126317D02*
X758917Y126067D01*
X759000Y125775D01*
Y125442D01*
X758875Y125067D01*
X758667Y124775D01*
X758417Y124567D01*
X758000Y124400D01*
X757625Y124358D01*
X757250Y124442D01*
X757000Y124567D01*
X756750Y124817D01*
X756583Y125108D01*
X756500Y125400D01*
Y125692D01*
X756583Y125983D01*
X756708Y126233D01*
X756875Y126442D01*
G01X756500Y128500D02*
X759000D01*
X758500Y128000D01*
G01X756500D02*
Y129000D01*
G01X759000Y131600D02*
X758917Y131267D01*
X758708Y131017D01*
X758458Y130850D01*
X758125Y130725D01*
X757750Y130683D01*
X757375Y130725D01*
X757042Y130850D01*
X756792Y131017D01*
X756583Y131267D01*
X756500Y131600D01*
X756583Y131933D01*
X756792Y132183D01*
X757042Y132350D01*
X757375Y132475D01*
X757750Y132517D01*
X758125Y132475D01*
X758458Y132350D01*
X758708Y132183D01*
X758917Y131933D01*
X759000Y131600D01*
G01X758583Y133908D02*
X758833Y134158D01*
X758958Y134450D01*
X759000Y134783D01*
X758917Y135200D01*
X758708Y135492D01*
X758458Y135575D01*
X758208Y135533D01*
X758000Y135367D01*
X757583Y134533D01*
X757292Y134158D01*
X756875Y133908D01*
X756500Y133825D01*
Y135575D01*
G01X752000Y121467D02*
X754500D01*
Y122467D01*
X754375Y122800D01*
X754083Y123050D01*
X753750Y123133D01*
X753417Y123050D01*
X753167Y122842D01*
X753042Y122467D01*
Y121467D01*
G01X752000Y124567D02*
X754500D01*
Y125608D01*
X754375Y125942D01*
X754208Y126150D01*
X753875Y126233D01*
X753542Y126150D01*
X753333Y125900D01*
X753208Y125608D01*
Y124567D01*
G01Y125608D02*
X752000Y126233D01*
G01X754083Y127708D02*
X754333Y127958D01*
X754458Y128250D01*
X754500Y128583D01*
X754417Y129000D01*
X754208Y129292D01*
X753958Y129375D01*
X753708Y129333D01*
X753500Y129167D01*
X753083Y128333D01*
X752792Y127958D01*
X752375Y127708D01*
X752000Y127625D01*
Y129375D01*
G01X754500Y131600D02*
X754417Y131267D01*
X754208Y131017D01*
X753958Y130850D01*
X753625Y130725D01*
X753250Y130683D01*
X752875Y130725D01*
X752542Y130850D01*
X752292Y131017D01*
X752083Y131267D01*
X752000Y131600D01*
X752083Y131933D01*
X752292Y132183D01*
X752542Y132350D01*
X752875Y132475D01*
X753250Y132517D01*
X753625Y132475D01*
X753958Y132350D01*
X754208Y132183D01*
X754417Y131933D01*
X754500Y131600D01*
G01X752000Y134700D02*
X752042Y134992D01*
X752167Y135325D01*
X752375Y135533D01*
X752667Y135617D01*
X752958Y135533D01*
X753208Y135283D01*
X753333Y134908D01*
Y134492D01*
X753417Y134242D01*
X753625Y134033D01*
X753917Y133950D01*
X754208Y134075D01*
X754417Y134367D01*
X754500Y134700D01*
X754417Y135033D01*
X754208Y135325D01*
X753917Y135450D01*
X753625Y135367D01*
X753417Y135158D01*
X753333Y134908D01*
Y134492D01*
X753208Y134117D01*
X752958Y133867D01*
X752667Y133783D01*
X752375Y133867D01*
X752167Y134075D01*
X752042Y134408D01*
X752000Y134700D01*
G01X750750Y235000D02*
Y237500D01*
X751250Y237000D01*
G01Y235000D02*
X750250D01*
G01X748266Y237348D02*
Y241348D01*
X746266Y239348D01*
X750266D01*
X748266Y241348D01*
G01X782967Y254000D02*
Y256500D01*
X784633D01*
G01X787733D02*
X786067D01*
Y254000D01*
X787733D01*
G01X787067Y255208D02*
X786067D01*
G01X789083Y256500D02*
Y254000D01*
X789917D01*
X790250Y254125D01*
X790500Y254292D01*
X790708Y254542D01*
X790875Y254833D01*
X790917Y255250D01*
X790875Y255667D01*
X790708Y255958D01*
X790500Y256208D01*
X790250Y256375D01*
X789917Y256500D01*
X789083D01*
G01X793100D02*
Y254000D01*
X792600Y254500D01*
G01Y256500D02*
X793600D01*
G01X796117D02*
X796200Y255958D01*
X796325Y255500D01*
X796492Y255083D01*
X796700Y254625D01*
X797033Y254000D01*
X795367D01*
G01X777750Y269250D02*
X774250D01*
Y282750D01*
X777750D01*
Y269250D01*
G01X779517Y285000D02*
Y287500D01*
X781183D01*
G01X784283D02*
X782617D01*
Y285000D01*
X784283D01*
G01X783617Y286208D02*
X782617D01*
G01X785633Y287500D02*
Y285000D01*
X786467D01*
X786800Y285125D01*
X787050Y285292D01*
X787258Y285542D01*
X787425Y285833D01*
X787467Y286250D01*
X787425Y286667D01*
X787258Y286958D01*
X787050Y287208D01*
X786800Y287375D01*
X786467Y287500D01*
X785633D01*
G01X789650D02*
Y285000D01*
X789150Y285500D01*
G01Y287500D02*
X790150D01*
G01X789500Y71890D02*
X792000D01*
Y72724D01*
X791875Y73057D01*
X791708Y73307D01*
X791458Y73515D01*
X791167Y73682D01*
X790750Y73724D01*
X790333Y73682D01*
X790042Y73515D01*
X789792Y73307D01*
X789625Y73057D01*
X789500Y72724D01*
Y71890D01*
G01X792000Y75407D02*
Y76407D01*
G01Y75907D02*
X789500D01*
G01Y75407D02*
Y76407D01*
G01Y77924D02*
X792000D01*
X789917Y79007D01*
X792000Y80090D01*
X789500D01*
G01Y81024D02*
X792000D01*
X789917Y82107D01*
X792000Y83190D01*
X789500D01*
G01X790000Y84290D02*
X789708Y84540D01*
X789542Y84874D01*
X789500Y85249D01*
X789542Y85582D01*
X789750Y85915D01*
X790000Y86124D01*
X790250Y86165D01*
X790542Y86082D01*
X790750Y85790D01*
X790833Y85499D01*
Y85124D01*
G01Y85499D02*
X790958Y85749D01*
X791167Y85957D01*
X791417Y86040D01*
X791667Y85957D01*
X791875Y85749D01*
X792000Y85374D01*
X791958Y84999D01*
X791792Y84624D01*
G01X809483Y88500D02*
Y91000D01*
X808442D01*
X808108Y90875D01*
X807900Y90708D01*
X807817Y90375D01*
X807900Y90042D01*
X808150Y89833D01*
X808442Y89708D01*
X809483D01*
G01X808442D02*
X807817Y88500D01*
G01X805550D02*
Y91000D01*
X806050Y90500D01*
G01Y88500D02*
X805050D01*
G01X801950D02*
Y91000D01*
X803492Y89208D01*
X801408D01*
G01X800058Y88792D02*
X799767Y88583D01*
X799433Y88500D01*
X799100Y88583D01*
X798808Y88833D01*
X798600Y89208D01*
X798517Y89583D01*
Y90042D01*
X798600Y90417D01*
X798808Y90750D01*
X799058Y90917D01*
X799350Y91000D01*
X799683Y90917D01*
X799933Y90750D01*
X800100Y90500D01*
X800183Y90167D01*
X800100Y89875D01*
X799892Y89583D01*
X799642Y89417D01*
X799350Y89375D01*
X799017Y89458D01*
X798767Y89667D01*
X798517Y90042D01*
G01X809983Y92500D02*
Y95000D01*
X808942D01*
X808608Y94875D01*
X808400Y94708D01*
X808317Y94375D01*
X808400Y94042D01*
X808650Y93833D01*
X808942Y93708D01*
X809983D01*
G01X808942D02*
X808317Y92500D01*
G01X806050D02*
Y95000D01*
X806550Y94500D01*
G01Y92500D02*
X805550D01*
G01X803867Y92875D02*
X803617Y92667D01*
X803325Y92542D01*
X802950Y92500D01*
X802575Y92583D01*
X802283Y92750D01*
X802075Y93042D01*
X802033Y93375D01*
X802117Y93708D01*
X802325Y93917D01*
X802617Y94083D01*
X802908Y94125D01*
X803200Y94083D01*
X803575Y93917D01*
X803450Y95000D01*
X802325D01*
G01X799850D02*
X800183Y94917D01*
X800433Y94708D01*
X800600Y94458D01*
X800725Y94125D01*
X800767Y93750D01*
X800725Y93375D01*
X800600Y93042D01*
X800433Y92792D01*
X800183Y92583D01*
X799850Y92500D01*
X799517Y92583D01*
X799267Y92792D01*
X799100Y93042D01*
X798975Y93375D01*
X798933Y93750D01*
X798975Y94125D01*
X799100Y94458D01*
X799267Y94708D01*
X799517Y94917D01*
X799850Y95000D01*
G01X809983Y100500D02*
Y103000D01*
X808942D01*
X808608Y102875D01*
X808400Y102708D01*
X808317Y102375D01*
X808400Y102042D01*
X808650Y101833D01*
X808942Y101708D01*
X809983D01*
G01X808942D02*
X808317Y100500D01*
G01X806050D02*
Y103000D01*
X806550Y102500D01*
G01Y100500D02*
X805550D01*
G01X803867Y100875D02*
X803617Y100667D01*
X803325Y100542D01*
X802950Y100500D01*
X802575Y100583D01*
X802283Y100750D01*
X802075Y101042D01*
X802033Y101375D01*
X802117Y101708D01*
X802325Y101917D01*
X802617Y102083D01*
X802908Y102125D01*
X803200Y102083D01*
X803575Y101917D01*
X803450Y103000D01*
X802325D01*
G01X799850Y100500D02*
Y103000D01*
X800350Y102500D01*
G01Y100500D02*
X799350D01*
G01X810483Y104500D02*
Y107000D01*
X809442D01*
X809108Y106875D01*
X808900Y106708D01*
X808817Y106375D01*
X808900Y106042D01*
X809150Y105833D01*
X809442Y105708D01*
X810483D01*
G01X809442D02*
X808817Y104500D01*
G01X806550D02*
Y107000D01*
X807050Y106500D01*
G01Y104500D02*
X806050D01*
G01X804367Y104875D02*
X804117Y104667D01*
X803825Y104542D01*
X803450Y104500D01*
X803075Y104583D01*
X802783Y104750D01*
X802575Y105042D01*
X802533Y105375D01*
X802617Y105708D01*
X802825Y105917D01*
X803117Y106083D01*
X803408Y106125D01*
X803700Y106083D01*
X804075Y105917D01*
X803950Y107000D01*
X802825D01*
G01X801142Y106583D02*
X800892Y106833D01*
X800600Y106958D01*
X800267Y107000D01*
X799850Y106917D01*
X799558Y106708D01*
X799475Y106458D01*
X799517Y106208D01*
X799683Y106000D01*
X800517Y105583D01*
X800892Y105292D01*
X801142Y104875D01*
X801225Y104500D01*
X799475D01*
G01X809983Y108500D02*
Y111000D01*
X808942D01*
X808608Y110875D01*
X808400Y110708D01*
X808317Y110375D01*
X808400Y110042D01*
X808650Y109833D01*
X808942Y109708D01*
X809983D01*
G01X808942D02*
X808317Y108500D01*
G01X805550D02*
Y111000D01*
X807092Y109208D01*
X805008D01*
G01X803658Y108792D02*
X803367Y108583D01*
X803033Y108500D01*
X802700Y108583D01*
X802408Y108833D01*
X802200Y109208D01*
X802117Y109583D01*
Y110042D01*
X802200Y110417D01*
X802408Y110750D01*
X802658Y110917D01*
X802950Y111000D01*
X803283Y110917D01*
X803533Y110750D01*
X803700Y110500D01*
X803783Y110167D01*
X803700Y109875D01*
X803492Y109583D01*
X803242Y109417D01*
X802950Y109375D01*
X802617Y109458D01*
X802367Y109667D01*
X802117Y110042D01*
G01X799933Y108500D02*
X799850Y109042D01*
X799725Y109500D01*
X799558Y109917D01*
X799350Y110375D01*
X799017Y111000D01*
X800683D01*
G01X803517Y132000D02*
Y134500D01*
X805183D01*
G01X808283D02*
X806617D01*
Y132000D01*
X808283D01*
G01X807617Y133208D02*
X806617D01*
G01X809633Y134500D02*
Y132000D01*
X810467D01*
X810800Y132125D01*
X811050Y132292D01*
X811258Y132542D01*
X811425Y132833D01*
X811467Y133250D01*
X811425Y133667D01*
X811258Y133958D01*
X811050Y134208D01*
X810800Y134375D01*
X810467Y134500D01*
X809633D01*
G01X812858Y133458D02*
X813150Y133167D01*
X813400Y133000D01*
X813733Y132917D01*
X814025Y133000D01*
X814233Y133167D01*
X814400Y133417D01*
X814442Y133708D01*
X814400Y133958D01*
X814233Y134208D01*
X813983Y134417D01*
X813692Y134500D01*
X813358Y134417D01*
X813067Y134167D01*
X812900Y133792D01*
X812858Y133375D01*
X812942Y132833D01*
X813067Y132542D01*
X813275Y132250D01*
X813567Y132042D01*
X813858Y132000D01*
X814150Y132083D01*
X814358Y132292D01*
G01X803517Y127500D02*
Y130000D01*
X805183D01*
G01X808283D02*
X806617D01*
Y127500D01*
X808283D01*
G01X807617Y128708D02*
X806617D01*
G01X809633Y130000D02*
Y127500D01*
X810467D01*
X810800Y127625D01*
X811050Y127792D01*
X811258Y128042D01*
X811425Y128333D01*
X811467Y128750D01*
X811425Y129167D01*
X811258Y129458D01*
X811050Y129708D01*
X810800Y129875D01*
X810467Y130000D01*
X809633D01*
G01X812733Y129625D02*
X812983Y129833D01*
X813275Y129958D01*
X813650Y130000D01*
X814025Y129917D01*
X814317Y129750D01*
X814525Y129458D01*
X814567Y129125D01*
X814483Y128792D01*
X814275Y128583D01*
X813983Y128417D01*
X813692Y128375D01*
X813400Y128417D01*
X813025Y128583D01*
X813150Y127500D01*
X814275D01*
G01X803517Y136500D02*
Y139000D01*
X805183D01*
G01X808283D02*
X806617D01*
Y136500D01*
X808283D01*
G01X807617Y137708D02*
X806617D01*
G01X809633Y139000D02*
Y136500D01*
X810467D01*
X810800Y136625D01*
X811050Y136792D01*
X811258Y137042D01*
X811425Y137333D01*
X811467Y137750D01*
X811425Y138167D01*
X811258Y138458D01*
X811050Y138708D01*
X810800Y138875D01*
X810467Y139000D01*
X809633D01*
G01X813567D02*
X813650Y138458D01*
X813775Y138000D01*
X813942Y137583D01*
X814150Y137125D01*
X814483Y136500D01*
X812817D01*
G01X812233Y148792D02*
X812483Y148917D01*
X812775Y149000D01*
X813108D01*
X813483Y148875D01*
X813775Y148667D01*
X813983Y148417D01*
X814150Y148000D01*
X814192Y147625D01*
X814108Y147250D01*
X813983Y147000D01*
X813733Y146750D01*
X813442Y146583D01*
X813150Y146500D01*
X812858D01*
X812567Y146583D01*
X812317Y146708D01*
X812108Y146875D01*
G01X810967Y147000D02*
X810717Y146708D01*
X810383Y146542D01*
X810008Y146500D01*
X809675Y146542D01*
X809342Y146750D01*
X809133Y147000D01*
X809092Y147250D01*
X809175Y147542D01*
X809467Y147750D01*
X809758Y147833D01*
X810133D01*
G01X809758D02*
X809508Y147958D01*
X809300Y148167D01*
X809217Y148417D01*
X809300Y148667D01*
X809508Y148875D01*
X809883Y149000D01*
X810258Y148958D01*
X810633Y148792D01*
G01X807867Y146875D02*
X807617Y146667D01*
X807325Y146542D01*
X806950Y146500D01*
X806575Y146583D01*
X806283Y146750D01*
X806075Y147042D01*
X806033Y147375D01*
X806117Y147708D01*
X806325Y147917D01*
X806617Y148083D01*
X806908Y148125D01*
X807200Y148083D01*
X807575Y147917D01*
X807450Y149000D01*
X806325D01*
G01X803850Y146500D02*
Y149000D01*
X804350Y148500D01*
G01Y146500D02*
X803350D01*
G01X794967Y266000D02*
Y268500D01*
X796633D01*
G01X799733D02*
X798067D01*
Y266000D01*
X799733D01*
G01X799067Y267208D02*
X798067D01*
G01X801083Y268500D02*
Y266000D01*
X801917D01*
X802250Y266125D01*
X802500Y266292D01*
X802708Y266542D01*
X802875Y266833D01*
X802917Y267250D01*
X802875Y267667D01*
X802708Y267958D01*
X802500Y268208D01*
X802250Y268375D01*
X801917Y268500D01*
X801083D01*
G01X805100D02*
Y266000D01*
X804600Y266500D01*
G01Y268500D02*
X805600D01*
G01X808700D02*
Y266000D01*
X807158Y267792D01*
X809242D01*
G01X805883Y286000D02*
Y288500D01*
X804842D01*
X804508Y288375D01*
X804300Y288208D01*
X804217Y287875D01*
X804300Y287542D01*
X804550Y287333D01*
X804842Y287208D01*
X805883D01*
G01X804842D02*
X804217Y286000D01*
G01X801950D02*
Y288500D01*
X802450Y288000D01*
G01Y286000D02*
X801450D01*
G01X817233Y15292D02*
X817483Y15417D01*
X817775Y15500D01*
X818108D01*
X818483Y15375D01*
X818775Y15167D01*
X818983Y14917D01*
X819150Y14500D01*
X819192Y14125D01*
X819108Y13750D01*
X818983Y13500D01*
X818733Y13250D01*
X818442Y13083D01*
X818150Y13000D01*
X817858D01*
X817567Y13083D01*
X817317Y13208D01*
X817108Y13375D01*
G01X815842Y15083D02*
X815592Y15333D01*
X815300Y15458D01*
X814967Y15500D01*
X814550Y15417D01*
X814258Y15208D01*
X814175Y14958D01*
X814217Y14708D01*
X814383Y14500D01*
X815217Y14083D01*
X815592Y13792D01*
X815842Y13375D01*
X815925Y13000D01*
X814175D01*
G01X812658Y13292D02*
X812367Y13083D01*
X812033Y13000D01*
X811700Y13083D01*
X811408Y13333D01*
X811200Y13708D01*
X811117Y14083D01*
Y14542D01*
X811200Y14917D01*
X811408Y15250D01*
X811658Y15417D01*
X811950Y15500D01*
X812283Y15417D01*
X812533Y15250D01*
X812700Y15000D01*
X812783Y14667D01*
X812700Y14375D01*
X812492Y14083D01*
X812242Y13917D01*
X811950Y13875D01*
X811617Y13958D01*
X811367Y14167D01*
X811117Y14542D01*
G01X809642Y15083D02*
X809392Y15333D01*
X809100Y15458D01*
X808767Y15500D01*
X808350Y15417D01*
X808058Y15208D01*
X807975Y14958D01*
X808017Y14708D01*
X808183Y14500D01*
X809017Y14083D01*
X809392Y13792D01*
X809642Y13375D01*
X809725Y13000D01*
X807975D01*
G01X817233Y19492D02*
X817483Y19617D01*
X817775Y19700D01*
X818108D01*
X818483Y19575D01*
X818775Y19367D01*
X818983Y19117D01*
X819150Y18700D01*
X819192Y18325D01*
X819108Y17950D01*
X818983Y17700D01*
X818733Y17450D01*
X818442Y17283D01*
X818150Y17200D01*
X817858D01*
X817567Y17283D01*
X817317Y17408D01*
X817108Y17575D01*
G01X815842Y19283D02*
X815592Y19533D01*
X815300Y19658D01*
X814967Y19700D01*
X814550Y19617D01*
X814258Y19408D01*
X814175Y19158D01*
X814217Y18908D01*
X814383Y18700D01*
X815217Y18283D01*
X815592Y17992D01*
X815842Y17575D01*
X815925Y17200D01*
X814175D01*
G01X811950D02*
X811658Y17242D01*
X811325Y17367D01*
X811117Y17575D01*
X811033Y17867D01*
X811117Y18158D01*
X811367Y18408D01*
X811742Y18533D01*
X812158D01*
X812408Y18617D01*
X812617Y18825D01*
X812700Y19117D01*
X812575Y19408D01*
X812283Y19617D01*
X811950Y19700D01*
X811617Y19617D01*
X811325Y19408D01*
X811200Y19117D01*
X811283Y18825D01*
X811492Y18617D01*
X811742Y18533D01*
X812158D01*
X812533Y18408D01*
X812783Y18158D01*
X812867Y17867D01*
X812783Y17575D01*
X812575Y17367D01*
X812242Y17242D01*
X811950Y17200D01*
G01X808850D02*
X808558Y17242D01*
X808225Y17367D01*
X808017Y17575D01*
X807933Y17867D01*
X808017Y18158D01*
X808267Y18408D01*
X808642Y18533D01*
X809058D01*
X809308Y18617D01*
X809517Y18825D01*
X809600Y19117D01*
X809475Y19408D01*
X809183Y19617D01*
X808850Y19700D01*
X808517Y19617D01*
X808225Y19408D01*
X808100Y19117D01*
X808183Y18825D01*
X808392Y18617D01*
X808642Y18533D01*
X809058D01*
X809433Y18408D01*
X809683Y18158D01*
X809767Y17867D01*
X809683Y17575D01*
X809475Y17367D01*
X809142Y17242D01*
X808850Y17200D01*
G01X815000Y22017D02*
X817500D01*
Y23058D01*
X817375Y23392D01*
X817208Y23600D01*
X816875Y23683D01*
X816542Y23600D01*
X816333Y23350D01*
X816208Y23058D01*
Y22017D01*
G01Y23058D02*
X815000Y23683D01*
G01X815500Y25033D02*
X815208Y25283D01*
X815042Y25617D01*
X815000Y25992D01*
X815042Y26325D01*
X815250Y26658D01*
X815500Y26867D01*
X815750Y26908D01*
X816042Y26825D01*
X816250Y26533D01*
X816333Y26242D01*
Y25867D01*
G01Y26242D02*
X816458Y26492D01*
X816667Y26700D01*
X816917Y26783D01*
X817167Y26700D01*
X817375Y26492D01*
X817500Y26117D01*
X817458Y25742D01*
X817292Y25367D01*
G01X815000Y29050D02*
X815042Y29342D01*
X815167Y29675D01*
X815375Y29883D01*
X815667Y29967D01*
X815958Y29883D01*
X816208Y29633D01*
X816333Y29258D01*
Y28842D01*
X816417Y28592D01*
X816625Y28383D01*
X816917Y28300D01*
X817208Y28425D01*
X817417Y28717D01*
X817500Y29050D01*
X817417Y29383D01*
X817208Y29675D01*
X816917Y29800D01*
X816625Y29717D01*
X816417Y29508D01*
X816333Y29258D01*
Y28842D01*
X816208Y28467D01*
X815958Y28217D01*
X815667Y28133D01*
X815375Y28217D01*
X815167Y28425D01*
X815042Y28758D01*
X815000Y29050D01*
G01Y32650D02*
X817500D01*
X815708Y31108D01*
Y33192D01*
G01X810500Y21917D02*
X813000D01*
Y22958D01*
X812875Y23292D01*
X812708Y23500D01*
X812375Y23583D01*
X812042Y23500D01*
X811833Y23250D01*
X811708Y22958D01*
Y21917D01*
G01Y22958D02*
X810500Y23583D01*
G01X811000Y24933D02*
X810708Y25183D01*
X810542Y25517D01*
X810500Y25892D01*
X810542Y26225D01*
X810750Y26558D01*
X811000Y26767D01*
X811250Y26808D01*
X811542Y26725D01*
X811750Y26433D01*
X811833Y26142D01*
Y25767D01*
G01Y26142D02*
X811958Y26392D01*
X812167Y26600D01*
X812417Y26683D01*
X812667Y26600D01*
X812875Y26392D01*
X813000Y26017D01*
X812958Y25642D01*
X812792Y25267D01*
G01X810500Y28950D02*
X810542Y29242D01*
X810667Y29575D01*
X810875Y29783D01*
X811167Y29867D01*
X811458Y29783D01*
X811708Y29533D01*
X811833Y29158D01*
Y28742D01*
X811917Y28492D01*
X812125Y28283D01*
X812417Y28200D01*
X812708Y28325D01*
X812917Y28617D01*
X813000Y28950D01*
X812917Y29283D01*
X812708Y29575D01*
X812417Y29700D01*
X812125Y29617D01*
X811917Y29408D01*
X811833Y29158D01*
Y28742D01*
X811708Y28367D01*
X811458Y28117D01*
X811167Y28033D01*
X810875Y28117D01*
X810667Y28325D01*
X810542Y28658D01*
X810500Y28950D01*
G01X811000Y31133D02*
X810708Y31383D01*
X810542Y31717D01*
X810500Y32092D01*
X810542Y32425D01*
X810750Y32758D01*
X811000Y32967D01*
X811250Y33008D01*
X811542Y32925D01*
X811750Y32633D01*
X811833Y32342D01*
Y31967D01*
G01Y32342D02*
X811958Y32592D01*
X812167Y32800D01*
X812417Y32883D01*
X812667Y32800D01*
X812875Y32592D01*
X813000Y32217D01*
X812958Y31842D01*
X812792Y31467D01*
G01X823483Y88500D02*
Y91000D01*
X822483D01*
X822150Y90875D01*
X821900Y90583D01*
X821817Y90250D01*
X821900Y89917D01*
X822108Y89667D01*
X822483Y89542D01*
X823483D01*
G01X818633Y90792D02*
X818883Y90917D01*
X819175Y91000D01*
X819508D01*
X819883Y90875D01*
X820175Y90667D01*
X820383Y90417D01*
X820550Y90000D01*
X820592Y89625D01*
X820508Y89250D01*
X820383Y89000D01*
X820133Y88750D01*
X819842Y88583D01*
X819550Y88500D01*
X819258D01*
X818967Y88583D01*
X818717Y88708D01*
X818508Y88875D01*
G01X816450Y88500D02*
X816158Y88542D01*
X815825Y88667D01*
X815617Y88875D01*
X815533Y89167D01*
X815617Y89458D01*
X815867Y89708D01*
X816242Y89833D01*
X816658D01*
X816908Y89917D01*
X817117Y90125D01*
X817200Y90417D01*
X817075Y90708D01*
X816783Y90917D01*
X816450Y91000D01*
X816117Y90917D01*
X815825Y90708D01*
X815700Y90417D01*
X815783Y90125D01*
X815992Y89917D01*
X816242Y89833D01*
X816658D01*
X817033Y89708D01*
X817283Y89458D01*
X817367Y89167D01*
X817283Y88875D01*
X817075Y88667D01*
X816742Y88542D01*
X816450Y88500D01*
G01X812850D02*
Y91000D01*
X814392Y89208D01*
X812308D01*
G01X822233Y106792D02*
X822483Y106917D01*
X822775Y107000D01*
X823108D01*
X823483Y106875D01*
X823775Y106667D01*
X823983Y106417D01*
X824150Y106000D01*
X824192Y105625D01*
X824108Y105250D01*
X823983Y105000D01*
X823733Y104750D01*
X823442Y104583D01*
X823150Y104500D01*
X822858D01*
X822567Y104583D01*
X822317Y104708D01*
X822108Y104875D01*
G01X820967Y105000D02*
X820717Y104708D01*
X820383Y104542D01*
X820008Y104500D01*
X819675Y104542D01*
X819342Y104750D01*
X819133Y105000D01*
X819092Y105250D01*
X819175Y105542D01*
X819467Y105750D01*
X819758Y105833D01*
X820133D01*
G01X819758D02*
X819508Y105958D01*
X819300Y106167D01*
X819217Y106417D01*
X819300Y106667D01*
X819508Y106875D01*
X819883Y107000D01*
X820258Y106958D01*
X820633Y106792D01*
G01X817867Y104875D02*
X817617Y104667D01*
X817325Y104542D01*
X816950Y104500D01*
X816575Y104583D01*
X816283Y104750D01*
X816075Y105042D01*
X816033Y105375D01*
X816117Y105708D01*
X816325Y105917D01*
X816617Y106083D01*
X816908Y106125D01*
X817200Y106083D01*
X817575Y105917D01*
X817450Y107000D01*
X816325D01*
G01X813850D02*
X814183Y106917D01*
X814433Y106708D01*
X814600Y106458D01*
X814725Y106125D01*
X814767Y105750D01*
X814725Y105375D01*
X814600Y105042D01*
X814433Y104792D01*
X814183Y104583D01*
X813850Y104500D01*
X813517Y104583D01*
X813267Y104792D01*
X813100Y105042D01*
X812975Y105375D01*
X812933Y105750D01*
X812975Y106125D01*
X813100Y106458D01*
X813267Y106708D01*
X813517Y106917D01*
X813850Y107000D01*
G01X822233Y102792D02*
X822483Y102917D01*
X822775Y103000D01*
X823108D01*
X823483Y102875D01*
X823775Y102667D01*
X823983Y102417D01*
X824150Y102000D01*
X824192Y101625D01*
X824108Y101250D01*
X823983Y101000D01*
X823733Y100750D01*
X823442Y100583D01*
X823150Y100500D01*
X822858D01*
X822567Y100583D01*
X822317Y100708D01*
X822108Y100875D01*
G01X820967Y101000D02*
X820717Y100708D01*
X820383Y100542D01*
X820008Y100500D01*
X819675Y100542D01*
X819342Y100750D01*
X819133Y101000D01*
X819092Y101250D01*
X819175Y101542D01*
X819467Y101750D01*
X819758Y101833D01*
X820133D01*
G01X819758D02*
X819508Y101958D01*
X819300Y102167D01*
X819217Y102417D01*
X819300Y102667D01*
X819508Y102875D01*
X819883Y103000D01*
X820258Y102958D01*
X820633Y102792D01*
G01X816450Y100500D02*
Y103000D01*
X817992Y101208D01*
X815908D01*
G01X813850Y100500D02*
X813558Y100542D01*
X813225Y100667D01*
X813017Y100875D01*
X812933Y101167D01*
X813017Y101458D01*
X813267Y101708D01*
X813642Y101833D01*
X814058D01*
X814308Y101917D01*
X814517Y102125D01*
X814600Y102417D01*
X814475Y102708D01*
X814183Y102917D01*
X813850Y103000D01*
X813517Y102917D01*
X813225Y102708D01*
X813100Y102417D01*
X813183Y102125D01*
X813392Y101917D01*
X813642Y101833D01*
X814058D01*
X814433Y101708D01*
X814683Y101458D01*
X814767Y101167D01*
X814683Y100875D01*
X814475Y100667D01*
X814142Y100542D01*
X813850Y100500D01*
G01X823483Y92500D02*
Y95000D01*
X822483D01*
X822150Y94875D01*
X821900Y94583D01*
X821817Y94250D01*
X821900Y93917D01*
X822108Y93667D01*
X822483Y93542D01*
X823483D01*
G01X818633Y94792D02*
X818883Y94917D01*
X819175Y95000D01*
X819508D01*
X819883Y94875D01*
X820175Y94667D01*
X820383Y94417D01*
X820550Y94000D01*
X820592Y93625D01*
X820508Y93250D01*
X820383Y93000D01*
X820133Y92750D01*
X819842Y92583D01*
X819550Y92500D01*
X819258D01*
X818967Y92583D01*
X818717Y92708D01*
X818508Y92875D01*
G01X817158Y92792D02*
X816867Y92583D01*
X816533Y92500D01*
X816200Y92583D01*
X815908Y92833D01*
X815700Y93208D01*
X815617Y93583D01*
Y94042D01*
X815700Y94417D01*
X815908Y94750D01*
X816158Y94917D01*
X816450Y95000D01*
X816783Y94917D01*
X817033Y94750D01*
X817200Y94500D01*
X817283Y94167D01*
X817200Y93875D01*
X816992Y93583D01*
X816742Y93417D01*
X816450Y93375D01*
X816117Y93458D01*
X815867Y93667D01*
X815617Y94042D01*
G01X814142Y94583D02*
X813892Y94833D01*
X813600Y94958D01*
X813267Y95000D01*
X812850Y94917D01*
X812558Y94708D01*
X812475Y94458D01*
X812517Y94208D01*
X812683Y94000D01*
X813517Y93583D01*
X813892Y93292D01*
X814142Y92875D01*
X814225Y92500D01*
X812475D01*
G01X804017Y141000D02*
Y143500D01*
X805683D01*
G01X808783D02*
X807117D01*
Y141000D01*
X808783D01*
G01X808117Y142208D02*
X807117D01*
G01X810133Y143500D02*
Y141000D01*
X810967D01*
X811300Y141125D01*
X811550Y141292D01*
X811758Y141542D01*
X811925Y141833D01*
X811967Y142250D01*
X811925Y142667D01*
X811758Y142958D01*
X811550Y143208D01*
X811300Y143375D01*
X810967Y143500D01*
X810133D01*
G01X814150D02*
X814442Y143458D01*
X814775Y143333D01*
X814983Y143125D01*
X815067Y142833D01*
X814983Y142542D01*
X814733Y142292D01*
X814358Y142167D01*
X813942D01*
X813692Y142083D01*
X813483Y141875D01*
X813400Y141583D01*
X813525Y141292D01*
X813817Y141083D01*
X814150Y141000D01*
X814483Y141083D01*
X814775Y141292D01*
X814900Y141583D01*
X814817Y141875D01*
X814608Y142083D01*
X814358Y142167D01*
X813942D01*
X813567Y142292D01*
X813317Y142542D01*
X813233Y142833D01*
X813317Y143125D01*
X813525Y143333D01*
X813858Y143458D01*
X814150Y143500D01*
G01X809517Y151000D02*
Y153500D01*
X811183D01*
G01X814283D02*
X812617D01*
Y151000D01*
X814283D01*
G01X813617Y152208D02*
X812617D01*
G01X815633Y153500D02*
Y151000D01*
X816467D01*
X816800Y151125D01*
X817050Y151292D01*
X817258Y151542D01*
X817425Y151833D01*
X817467Y152250D01*
X817425Y152667D01*
X817258Y152958D01*
X817050Y153208D01*
X816800Y153375D01*
X816467Y153500D01*
X815633D01*
G01X818942Y153208D02*
X819233Y153417D01*
X819567Y153500D01*
X819900Y153417D01*
X820192Y153167D01*
X820400Y152792D01*
X820483Y152417D01*
Y151958D01*
X820400Y151583D01*
X820192Y151250D01*
X819942Y151083D01*
X819650Y151000D01*
X819317Y151083D01*
X819067Y151250D01*
X818900Y151500D01*
X818817Y151833D01*
X818900Y152125D01*
X819108Y152417D01*
X819358Y152583D01*
X819650Y152625D01*
X819983Y152542D01*
X820233Y152333D01*
X820483Y151958D01*
G01X807967Y155500D02*
Y158000D01*
X809633D01*
G01X812733D02*
X811067D01*
Y155500D01*
X812733D01*
G01X812067Y156708D02*
X811067D01*
G01X814083Y158000D02*
Y155500D01*
X814917D01*
X815250Y155625D01*
X815500Y155792D01*
X815708Y156042D01*
X815875Y156333D01*
X815917Y156750D01*
X815875Y157167D01*
X815708Y157458D01*
X815500Y157708D01*
X815250Y157875D01*
X814917Y158000D01*
X814083D01*
G01X818100D02*
Y155500D01*
X817600Y156000D01*
G01Y158000D02*
X818600D01*
G01X821200Y155500D02*
X820867Y155583D01*
X820617Y155792D01*
X820450Y156042D01*
X820325Y156375D01*
X820283Y156750D01*
X820325Y157125D01*
X820450Y157458D01*
X820617Y157708D01*
X820867Y157917D01*
X821200Y158000D01*
X821533Y157917D01*
X821783Y157708D01*
X821950Y157458D01*
X822075Y157125D01*
X822117Y156750D01*
X822075Y156375D01*
X821950Y156042D01*
X821783Y155792D01*
X821533Y155583D01*
X821200Y155500D01*
G01X807967Y160000D02*
Y162500D01*
X809633D01*
G01X812733D02*
X811067D01*
Y160000D01*
X812733D01*
G01X812067Y161208D02*
X811067D01*
G01X814083Y162500D02*
Y160000D01*
X814917D01*
X815250Y160125D01*
X815500Y160292D01*
X815708Y160542D01*
X815875Y160833D01*
X815917Y161250D01*
X815875Y161667D01*
X815708Y161958D01*
X815500Y162208D01*
X815250Y162375D01*
X814917Y162500D01*
X814083D01*
G01X818100D02*
Y160000D01*
X817600Y160500D01*
G01Y162500D02*
X818600D01*
G01X821200D02*
Y160000D01*
X820700Y160500D01*
G01Y162500D02*
X821700D01*
G01X808467Y165000D02*
Y167500D01*
X810133D01*
G01X813233D02*
X811567D01*
Y165000D01*
X813233D01*
G01X812567Y166208D02*
X811567D01*
G01X814583Y167500D02*
Y165000D01*
X815417D01*
X815750Y165125D01*
X816000Y165292D01*
X816208Y165542D01*
X816375Y165833D01*
X816417Y166250D01*
X816375Y166667D01*
X816208Y166958D01*
X816000Y167208D01*
X815750Y167375D01*
X815417Y167500D01*
X814583D01*
G01X818600D02*
Y165000D01*
X818100Y165500D01*
G01Y167500D02*
X819100D01*
G01X820908Y165417D02*
X821158Y165167D01*
X821450Y165042D01*
X821783Y165000D01*
X822200Y165083D01*
X822492Y165292D01*
X822575Y165542D01*
X822533Y165792D01*
X822367Y166000D01*
X821533Y166417D01*
X821158Y166708D01*
X820908Y167125D01*
X820825Y167500D01*
X822575D01*
G01X816000Y181017D02*
X818500D01*
Y182017D01*
X818375Y182350D01*
X818083Y182600D01*
X817750Y182683D01*
X817417Y182600D01*
X817167Y182392D01*
X817042Y182017D01*
Y181017D01*
G01X818292Y185867D02*
X818417Y185617D01*
X818500Y185325D01*
Y184992D01*
X818375Y184617D01*
X818167Y184325D01*
X817917Y184117D01*
X817500Y183950D01*
X817125Y183908D01*
X816750Y183992D01*
X816500Y184117D01*
X816250Y184367D01*
X816083Y184658D01*
X816000Y184950D01*
Y185242D01*
X816083Y185533D01*
X816208Y185783D01*
X816375Y185992D01*
G01X817042Y187258D02*
X817333Y187550D01*
X817500Y187800D01*
X817583Y188133D01*
X817500Y188425D01*
X817333Y188633D01*
X817083Y188800D01*
X816792Y188842D01*
X816542Y188800D01*
X816292Y188633D01*
X816083Y188383D01*
X816000Y188092D01*
X816083Y187758D01*
X816333Y187467D01*
X816708Y187300D01*
X817125Y187258D01*
X817667Y187342D01*
X817958Y187467D01*
X818250Y187675D01*
X818458Y187967D01*
X818500Y188258D01*
X818417Y188550D01*
X818208Y188758D01*
G01X816292Y190442D02*
X816083Y190733D01*
X816000Y191067D01*
X816083Y191400D01*
X816333Y191692D01*
X816708Y191900D01*
X817083Y191983D01*
X817542D01*
X817917Y191900D01*
X818250Y191692D01*
X818417Y191442D01*
X818500Y191150D01*
X818417Y190817D01*
X818250Y190567D01*
X818000Y190400D01*
X817667Y190317D01*
X817375Y190400D01*
X817083Y190608D01*
X816917Y190858D01*
X816875Y191150D01*
X816958Y191483D01*
X817167Y191733D01*
X817542Y191983D01*
G01X821733Y178292D02*
X821983Y178417D01*
X822275Y178500D01*
X822608D01*
X822983Y178375D01*
X823275Y178167D01*
X823483Y177917D01*
X823650Y177500D01*
X823692Y177125D01*
X823608Y176750D01*
X823483Y176500D01*
X823233Y176250D01*
X822942Y176083D01*
X822650Y176000D01*
X822358D01*
X822067Y176083D01*
X821817Y176208D01*
X821608Y176375D01*
G01X820467Y176500D02*
X820217Y176208D01*
X819883Y176042D01*
X819508Y176000D01*
X819175Y176042D01*
X818842Y176250D01*
X818633Y176500D01*
X818592Y176750D01*
X818675Y177042D01*
X818967Y177250D01*
X819258Y177333D01*
X819633D01*
G01X819258D02*
X819008Y177458D01*
X818800Y177667D01*
X818717Y177917D01*
X818800Y178167D01*
X819008Y178375D01*
X819383Y178500D01*
X819758Y178458D01*
X820133Y178292D01*
G01X815950Y176000D02*
Y178500D01*
X817492Y176708D01*
X815408D01*
G01X814058Y176292D02*
X813767Y176083D01*
X813433Y176000D01*
X813100Y176083D01*
X812808Y176333D01*
X812600Y176708D01*
X812517Y177083D01*
Y177542D01*
X812600Y177917D01*
X812808Y178250D01*
X813058Y178417D01*
X813350Y178500D01*
X813683Y178417D01*
X813933Y178250D01*
X814100Y178000D01*
X814183Y177667D01*
X814100Y177375D01*
X813892Y177083D01*
X813642Y176917D01*
X813350Y176875D01*
X813017Y176958D01*
X812767Y177167D01*
X812517Y177542D01*
G01X810500Y194517D02*
X813000D01*
Y195517D01*
X812875Y195850D01*
X812583Y196100D01*
X812250Y196183D01*
X811917Y196100D01*
X811667Y195892D01*
X811542Y195517D01*
Y194517D01*
G01X813000Y198450D02*
X810500D01*
G01X813000Y197492D02*
Y199408D01*
G01X812792Y202467D02*
X812917Y202217D01*
X813000Y201925D01*
Y201592D01*
X812875Y201217D01*
X812667Y200925D01*
X812417Y200717D01*
X812000Y200550D01*
X811625Y200508D01*
X811250Y200592D01*
X811000Y200717D01*
X810750Y200967D01*
X810583Y201258D01*
X810500Y201550D01*
Y201842D01*
X810583Y202133D01*
X810708Y202383D01*
X810875Y202592D01*
G01X812583Y203858D02*
X812833Y204108D01*
X812958Y204400D01*
X813000Y204733D01*
X812917Y205150D01*
X812708Y205442D01*
X812458Y205525D01*
X812208Y205483D01*
X812000Y205317D01*
X811583Y204483D01*
X811292Y204108D01*
X810875Y203858D01*
X810500Y203775D01*
Y205525D01*
G01X823533Y219500D02*
Y222000D01*
X822533D01*
X822200Y221875D01*
X821950Y221583D01*
X821867Y221250D01*
X821950Y220917D01*
X822158Y220667D01*
X822533Y220542D01*
X823533D01*
G01X818683Y221792D02*
X818933Y221917D01*
X819225Y222000D01*
X819558D01*
X819933Y221875D01*
X820225Y221667D01*
X820433Y221417D01*
X820600Y221000D01*
X820642Y220625D01*
X820558Y220250D01*
X820433Y220000D01*
X820183Y219750D01*
X819892Y219583D01*
X819600Y219500D01*
X819308D01*
X819017Y219583D01*
X818767Y219708D01*
X818558Y219875D01*
G01X816500Y219500D02*
Y222000D01*
X817000Y221500D01*
G01Y219500D02*
X816000D01*
G01X814317Y219875D02*
X814067Y219667D01*
X813775Y219542D01*
X813400Y219500D01*
X813025Y219583D01*
X812733Y219750D01*
X812525Y220042D01*
X812483Y220375D01*
X812567Y220708D01*
X812775Y220917D01*
X813067Y221083D01*
X813358Y221125D01*
X813650Y221083D01*
X814025Y220917D01*
X813900Y222000D01*
X812775D01*
G01X810383Y219500D02*
X810300Y220042D01*
X810175Y220500D01*
X810008Y220917D01*
X809800Y221375D01*
X809467Y222000D01*
X811133D01*
G01X823033Y228000D02*
Y230500D01*
X822033D01*
X821700Y230375D01*
X821450Y230083D01*
X821367Y229750D01*
X821450Y229417D01*
X821658Y229167D01*
X822033Y229042D01*
X823033D01*
G01X818183Y230292D02*
X818433Y230417D01*
X818725Y230500D01*
X819058D01*
X819433Y230375D01*
X819725Y230167D01*
X819933Y229917D01*
X820100Y229500D01*
X820142Y229125D01*
X820058Y228750D01*
X819933Y228500D01*
X819683Y228250D01*
X819392Y228083D01*
X819100Y228000D01*
X818808D01*
X818517Y228083D01*
X818267Y228208D01*
X818058Y228375D01*
G01X816000Y228000D02*
Y230500D01*
X816500Y230000D01*
G01Y228000D02*
X815500D01*
G01X813692Y229042D02*
X813400Y229333D01*
X813150Y229500D01*
X812817Y229583D01*
X812525Y229500D01*
X812317Y229333D01*
X812150Y229083D01*
X812108Y228792D01*
X812150Y228542D01*
X812317Y228292D01*
X812567Y228083D01*
X812858Y228000D01*
X813192Y228083D01*
X813483Y228333D01*
X813650Y228708D01*
X813692Y229125D01*
X813608Y229667D01*
X813483Y229958D01*
X813275Y230250D01*
X812983Y230458D01*
X812692Y230500D01*
X812400Y230417D01*
X812192Y230208D01*
G01X810592Y229042D02*
X810300Y229333D01*
X810050Y229500D01*
X809717Y229583D01*
X809425Y229500D01*
X809217Y229333D01*
X809050Y229083D01*
X809008Y228792D01*
X809050Y228542D01*
X809217Y228292D01*
X809467Y228083D01*
X809758Y228000D01*
X810092Y228083D01*
X810383Y228333D01*
X810550Y228708D01*
X810592Y229125D01*
X810508Y229667D01*
X810383Y229958D01*
X810175Y230250D01*
X809883Y230458D01*
X809592Y230500D01*
X809300Y230417D01*
X809092Y230208D01*
G01X823033Y224000D02*
Y226500D01*
X822033D01*
X821700Y226375D01*
X821450Y226083D01*
X821367Y225750D01*
X821450Y225417D01*
X821658Y225167D01*
X822033Y225042D01*
X823033D01*
G01X818183Y226292D02*
X818433Y226417D01*
X818725Y226500D01*
X819058D01*
X819433Y226375D01*
X819725Y226167D01*
X819933Y225917D01*
X820100Y225500D01*
X820142Y225125D01*
X820058Y224750D01*
X819933Y224500D01*
X819683Y224250D01*
X819392Y224083D01*
X819100Y224000D01*
X818808D01*
X818517Y224083D01*
X818267Y224208D01*
X818058Y224375D01*
G01X816000Y224000D02*
Y226500D01*
X816500Y226000D01*
G01Y224000D02*
X815500D01*
G01X813692Y225042D02*
X813400Y225333D01*
X813150Y225500D01*
X812817Y225583D01*
X812525Y225500D01*
X812317Y225333D01*
X812150Y225083D01*
X812108Y224792D01*
X812150Y224542D01*
X812317Y224292D01*
X812567Y224083D01*
X812858Y224000D01*
X813192Y224083D01*
X813483Y224333D01*
X813650Y224708D01*
X813692Y225125D01*
X813608Y225667D01*
X813483Y225958D01*
X813275Y226250D01*
X812983Y226458D01*
X812692Y226500D01*
X812400Y226417D01*
X812192Y226208D01*
G01X809800Y226500D02*
X810133Y226417D01*
X810383Y226208D01*
X810550Y225958D01*
X810675Y225625D01*
X810717Y225250D01*
X810675Y224875D01*
X810550Y224542D01*
X810383Y224292D01*
X810133Y224083D01*
X809800Y224000D01*
X809467Y224083D01*
X809217Y224292D01*
X809050Y224542D01*
X808925Y224875D01*
X808883Y225250D01*
X808925Y225625D01*
X809050Y225958D01*
X809217Y226208D01*
X809467Y226417D01*
X809800Y226500D01*
G01X822533Y243500D02*
Y246000D01*
X821533D01*
X821200Y245875D01*
X820950Y245583D01*
X820867Y245250D01*
X820950Y244917D01*
X821158Y244667D01*
X821533Y244542D01*
X822533D01*
G01X817683Y245792D02*
X817933Y245917D01*
X818225Y246000D01*
X818558D01*
X818933Y245875D01*
X819225Y245667D01*
X819433Y245417D01*
X819600Y245000D01*
X819642Y244625D01*
X819558Y244250D01*
X819433Y244000D01*
X819183Y243750D01*
X818892Y243583D01*
X818600Y243500D01*
X818308D01*
X818017Y243583D01*
X817767Y243708D01*
X817558Y243875D01*
G01X815500Y243500D02*
Y246000D01*
X816000Y245500D01*
G01Y243500D02*
X815000D01*
G01X813192Y244542D02*
X812900Y244833D01*
X812650Y245000D01*
X812317Y245083D01*
X812025Y245000D01*
X811817Y244833D01*
X811650Y244583D01*
X811608Y244292D01*
X811650Y244042D01*
X811817Y243792D01*
X812067Y243583D01*
X812358Y243500D01*
X812692Y243583D01*
X812983Y243833D01*
X813150Y244208D01*
X813192Y244625D01*
X813108Y245167D01*
X812983Y245458D01*
X812775Y245750D01*
X812483Y245958D01*
X812192Y246000D01*
X811900Y245917D01*
X811692Y245708D01*
G01X809300Y243500D02*
Y246000D01*
X809800Y245500D01*
G01Y243500D02*
X808800D01*
G01X822533Y239500D02*
Y242000D01*
X821533D01*
X821200Y241875D01*
X820950Y241583D01*
X820867Y241250D01*
X820950Y240917D01*
X821158Y240667D01*
X821533Y240542D01*
X822533D01*
G01X817683Y241792D02*
X817933Y241917D01*
X818225Y242000D01*
X818558D01*
X818933Y241875D01*
X819225Y241667D01*
X819433Y241417D01*
X819600Y241000D01*
X819642Y240625D01*
X819558Y240250D01*
X819433Y240000D01*
X819183Y239750D01*
X818892Y239583D01*
X818600Y239500D01*
X818308D01*
X818017Y239583D01*
X817767Y239708D01*
X817558Y239875D01*
G01X815500Y239500D02*
Y242000D01*
X816000Y241500D01*
G01Y239500D02*
X815000D01*
G01X813317Y239875D02*
X813067Y239667D01*
X812775Y239542D01*
X812400Y239500D01*
X812025Y239583D01*
X811733Y239750D01*
X811525Y240042D01*
X811483Y240375D01*
X811567Y240708D01*
X811775Y240917D01*
X812067Y241083D01*
X812358Y241125D01*
X812650Y241083D01*
X813025Y240917D01*
X812900Y242000D01*
X811775D01*
G01X810217Y239875D02*
X809967Y239667D01*
X809675Y239542D01*
X809300Y239500D01*
X808925Y239583D01*
X808633Y239750D01*
X808425Y240042D01*
X808383Y240375D01*
X808467Y240708D01*
X808675Y240917D01*
X808967Y241083D01*
X809258Y241125D01*
X809550Y241083D01*
X809925Y240917D01*
X809800Y242000D01*
X808675D01*
G01X822533Y260000D02*
Y262500D01*
X821533D01*
X821200Y262375D01*
X820950Y262083D01*
X820867Y261750D01*
X820950Y261417D01*
X821158Y261167D01*
X821533Y261042D01*
X822533D01*
G01X817683Y262292D02*
X817933Y262417D01*
X818225Y262500D01*
X818558D01*
X818933Y262375D01*
X819225Y262167D01*
X819433Y261917D01*
X819600Y261500D01*
X819642Y261125D01*
X819558Y260750D01*
X819433Y260500D01*
X819183Y260250D01*
X818892Y260083D01*
X818600Y260000D01*
X818308D01*
X818017Y260083D01*
X817767Y260208D01*
X817558Y260375D01*
G01X815500Y260000D02*
Y262500D01*
X816000Y262000D01*
G01Y260000D02*
X815000D01*
G01X813192Y261042D02*
X812900Y261333D01*
X812650Y261500D01*
X812317Y261583D01*
X812025Y261500D01*
X811817Y261333D01*
X811650Y261083D01*
X811608Y260792D01*
X811650Y260542D01*
X811817Y260292D01*
X812067Y260083D01*
X812358Y260000D01*
X812692Y260083D01*
X812983Y260333D01*
X813150Y260708D01*
X813192Y261125D01*
X813108Y261667D01*
X812983Y261958D01*
X812775Y262250D01*
X812483Y262458D01*
X812192Y262500D01*
X811900Y262417D01*
X811692Y262208D01*
G01X809383Y260000D02*
X809300Y260542D01*
X809175Y261000D01*
X809008Y261417D01*
X808800Y261875D01*
X808467Y262500D01*
X810133D01*
G01X822533Y255800D02*
Y258300D01*
X821533D01*
X821200Y258175D01*
X820950Y257883D01*
X820867Y257550D01*
X820950Y257217D01*
X821158Y256967D01*
X821533Y256842D01*
X822533D01*
G01X817683Y258092D02*
X817933Y258217D01*
X818225Y258300D01*
X818558D01*
X818933Y258175D01*
X819225Y257967D01*
X819433Y257717D01*
X819600Y257300D01*
X819642Y256925D01*
X819558Y256550D01*
X819433Y256300D01*
X819183Y256050D01*
X818892Y255883D01*
X818600Y255800D01*
X818308D01*
X818017Y255883D01*
X817767Y256008D01*
X817558Y256175D01*
G01X815500Y255800D02*
Y258300D01*
X816000Y257800D01*
G01Y255800D02*
X815000D01*
G01X813317Y256175D02*
X813067Y255967D01*
X812775Y255842D01*
X812400Y255800D01*
X812025Y255883D01*
X811733Y256050D01*
X811525Y256342D01*
X811483Y256675D01*
X811567Y257008D01*
X811775Y257217D01*
X812067Y257383D01*
X812358Y257425D01*
X812650Y257383D01*
X813025Y257217D01*
X812900Y258300D01*
X811775D01*
G01X808800Y255800D02*
Y258300D01*
X810342Y256508D01*
X808258D01*
G01X822533Y251500D02*
Y254000D01*
X821533D01*
X821200Y253875D01*
X820950Y253583D01*
X820867Y253250D01*
X820950Y252917D01*
X821158Y252667D01*
X821533Y252542D01*
X822533D01*
G01X817683Y253792D02*
X817933Y253917D01*
X818225Y254000D01*
X818558D01*
X818933Y253875D01*
X819225Y253667D01*
X819433Y253417D01*
X819600Y253000D01*
X819642Y252625D01*
X819558Y252250D01*
X819433Y252000D01*
X819183Y251750D01*
X818892Y251583D01*
X818600Y251500D01*
X818308D01*
X818017Y251583D01*
X817767Y251708D01*
X817558Y251875D01*
G01X815500Y251500D02*
Y254000D01*
X816000Y253500D01*
G01Y251500D02*
X815000D01*
G01X813317Y251875D02*
X813067Y251667D01*
X812775Y251542D01*
X812400Y251500D01*
X812025Y251583D01*
X811733Y251750D01*
X811525Y252042D01*
X811483Y252375D01*
X811567Y252708D01*
X811775Y252917D01*
X812067Y253083D01*
X812358Y253125D01*
X812650Y253083D01*
X813025Y252917D01*
X812900Y254000D01*
X811775D01*
G01X810217Y252000D02*
X809967Y251708D01*
X809633Y251542D01*
X809258Y251500D01*
X808925Y251542D01*
X808592Y251750D01*
X808383Y252000D01*
X808342Y252250D01*
X808425Y252542D01*
X808717Y252750D01*
X809008Y252833D01*
X809383D01*
G01X809008D02*
X808758Y252958D01*
X808550Y253167D01*
X808467Y253417D01*
X808550Y253667D01*
X808758Y253875D01*
X809133Y254000D01*
X809508Y253958D01*
X809883Y253792D01*
G01X820500Y180467D02*
X823000D01*
Y181467D01*
X822875Y181800D01*
X822583Y182050D01*
X822250Y182133D01*
X821917Y182050D01*
X821667Y181842D01*
X821542Y181467D01*
Y180467D01*
G01X820500Y183567D02*
X823000D01*
Y184608D01*
X822875Y184942D01*
X822708Y185150D01*
X822375Y185233D01*
X822042Y185150D01*
X821833Y184900D01*
X821708Y184608D01*
Y183567D01*
G01Y184608D02*
X820500Y185233D01*
G01Y187500D02*
X823000D01*
X822500Y187000D01*
G01X820500D02*
Y188000D01*
G01X823000Y190600D02*
X822917Y190267D01*
X822708Y190017D01*
X822458Y189850D01*
X822125Y189725D01*
X821750Y189683D01*
X821375Y189725D01*
X821042Y189850D01*
X820792Y190017D01*
X820583Y190267D01*
X820500Y190600D01*
X820583Y190933D01*
X820792Y191183D01*
X821042Y191350D01*
X821375Y191475D01*
X821750Y191517D01*
X822125Y191475D01*
X822458Y191350D01*
X822708Y191183D01*
X822917Y190933D01*
X823000Y190600D01*
G01X820500Y194200D02*
X823000D01*
X821208Y192658D01*
Y194742D01*
G54D17*
G01X62200Y201500D02*
X61350D01*
G01X64700D02*
X63800D01*
G01X67200D02*
X66350D01*
G01X69700D02*
X68800D01*
G01X69800Y228300D02*
X70650D01*
G01X67300D02*
X68200D01*
G01X74800D02*
X75650D01*
G01X72300D02*
X73200D01*
G01X97500Y193800D02*
Y194650D01*
G01Y191300D02*
Y192200D01*
G01X123500Y119300D02*
Y120200D01*
G01Y121800D02*
Y122650D01*
G01X122700Y167500D02*
X121850D01*
G01X125200D02*
X124300D01*
G01X145500Y192100D02*
Y188900D01*
G01X157500Y159100D02*
Y155900D01*
G01X195500Y116000D02*
Y116850D01*
G01Y113500D02*
Y114400D01*
G01Y118600D02*
Y121800D01*
G01X264000Y83800D02*
Y84650D01*
G01Y81300D02*
Y82200D01*
G01X265000Y66300D02*
Y67150D01*
G01Y63800D02*
Y64700D01*
G01X293500Y85800D02*
Y84950D01*
G01Y88300D02*
Y87400D01*
G01X303000Y78500D02*
Y79350D01*
G01Y76000D02*
Y76900D01*
G01X297800Y206000D02*
X298650D01*
G01X295300D02*
X296200D01*
G01X324800Y247500D02*
X325700D01*
G01X337000Y131800D02*
Y132650D01*
G01Y129300D02*
Y130200D01*
G01X340960Y151200D02*
Y152050D01*
G01Y148700D02*
Y149600D01*
G01X327300Y247500D02*
X328150D01*
G01X342200Y118500D02*
X341350D01*
G01X344700D02*
X343800D01*
G01X371000Y177250D02*
Y174050D01*
G01X361596Y202963D02*
Y202113D01*
G01Y205463D02*
Y204563D01*
G01X373100Y205500D02*
X369900D01*
G01X372996Y69663D02*
Y66463D01*
G01X373000Y74800D02*
Y71600D01*
G01X390500Y176700D02*
Y179900D01*
G01X424000Y76900D02*
Y80100D01*
G01X761200Y147000D02*
X760350D01*
G01X763700D02*
X762800D01*
G54D18*
G01X87200Y221500D02*
X90400D01*
G01X107400Y127500D02*
X110600D01*
G01X101900D02*
X105100D01*
G01X157700Y184500D02*
X154500D01*
G01X155400Y204500D02*
X158600D01*
G01X186600Y166000D02*
X183400D01*
G01X175600Y166500D02*
X172400D01*
G01X195500Y108600D02*
Y111800D01*
G01X274100Y90600D02*
Y93800D01*
G01X378900Y71063D02*
X382100D01*
G01X374900Y205500D02*
X378100D01*
G01X379900D02*
X383100D01*
G01X415600Y75500D02*
X412400D01*
G01X470000Y236900D02*
Y240100D01*
G01Y231400D02*
Y234600D01*
G01X508600Y222000D02*
X505400D01*
G01X510900Y59007D02*
X514100D01*
G01X515900Y222000D02*
X519100D01*
G01X510900D02*
X514100D01*
G01X520900D02*
X524100D01*
G01X597600Y233500D02*
X594400D01*
G01X607600D02*
X604400D01*
G01X620400Y49507D02*
X623600D01*
G01X629600Y233500D02*
X626400D01*
G01X648900Y49507D02*
X652100D01*
G01X643700Y52107D02*
X646900D01*
G01X695600Y166500D02*
X692400D01*
G01X728500Y60600D02*
Y57400D01*
G01Y55600D02*
Y52400D01*
G01X743600Y64500D02*
X740400D01*
G01X741600Y236000D02*
X738400D01*
G01X745900Y64500D02*
X749100D01*
G01X778500Y8100D02*
Y4900D01*
G01Y13300D02*
Y10100D01*
G01X777400Y242700D02*
Y245900D01*
G01Y252700D02*
Y255900D01*
G01Y247700D02*
Y250900D01*
G01X795400Y176000D02*
X798600D01*
G01X802000Y253900D02*
Y250700D01*
G01Y258900D02*
Y255700D01*
G01Y264100D02*
Y260900D01*
M02*
